(kicad_pcb
	(version 20241229)
	(generator "pcbnew")
	(generator_version "9.0")
	(general
		(thickness 1.6)
		(legacy_teardrops no)
	)
	(paper "A4")
	(layers
		(0 "F.Cu" signal)
		(4 "In1.Cu" signal)
		(6 "In2.Cu" signal)
		(2 "B.Cu" signal)
		(9 "F.Adhes" user "F.Adhesive")
		(11 "B.Adhes" user "B.Adhesive")
		(13 "F.Paste" user)
		(15 "B.Paste" user)
		(5 "F.SilkS" user "F.Silkscreen")
		(7 "B.SilkS" user "B.Silkscreen")
		(1 "F.Mask" user)
		(3 "B.Mask" user)
		(17 "Dwgs.User" user "User.Drawings")
		(19 "Cmts.User" user "User.Comments")
		(21 "Eco1.User" user "User.Eco1")
		(23 "Eco2.User" user "User.Eco2")
		(25 "Edge.Cuts" user)
		(27 "Margin" user)
		(31 "F.CrtYd" user "F.Courtyard")
		(29 "B.CrtYd" user "B.Courtyard")
		(35 "F.Fab" user)
		(33 "B.Fab" user)
	)
	(setup
		(stackup
			(layer "F.SilkS"
				(type "Top Silk Screen")
			)
			(layer "F.Paste"
				(type "Top Solder Paste")
			)
			(layer "F.Mask"
				(type "Top Solder Mask")
				(thickness 0.01)
			)
			(layer "F.Cu"
				(type "copper")
				(thickness 0.035)
			)
			(layer "dielectric 1"
				(type "prepreg")
				(thickness 0.12)
				(material "FR4")
				(epsilon_r 4.5)
				(loss_tangent 0.02)
			)
			(layer "In1.Cu"
				(type "copper")
				(thickness 0.035)
			)
			(layer "dielectric 2"
				(type "core")
				(thickness 1.2)
				(material "FR4")
				(epsilon_r 4.5)
				(loss_tangent 0.02)
			)
			(layer "In2.Cu"
				(type "copper")
				(thickness 0.035)
			)
			(layer "dielectric 3"
				(type "prepreg")
				(thickness 0.12)
				(material "FR4")
				(epsilon_r 4.5)
				(loss_tangent 0.02)
			)
			(layer "B.Cu"
				(type "copper")
				(thickness 0.035)
			)
			(layer "B.Mask"
				(type "Bottom Solder Mask")
				(thickness 0.01)
			)
			(layer "B.Paste"
				(type "Bottom Solder Paste")
			)
			(layer "B.SilkS"
				(type "Bottom Silk Screen")
			)
			(copper_finish "None")
			(dielectric_constraints no)
		)
		(pad_to_mask_clearance 0)
		(allow_soldermask_bridges_in_footprints no)
		(tenting front back)
		(aux_axis_origin 160 140)
		(pcbplotparams
			(layerselection 0x00000000_00000000_55555555_5755f5ff)
			(plot_on_all_layers_selection 0x00000000_00000000_00000000_00000000)
			(disableapertmacros no)
			(usegerberextensions no)
			(usegerberattributes yes)
			(usegerberadvancedattributes yes)
			(creategerberjobfile yes)
			(dashed_line_dash_ratio 12.000000)
			(dashed_line_gap_ratio 3.000000)
			(svgprecision 6)
			(plotframeref no)
			(mode 1)
			(useauxorigin no)
			(hpglpennumber 1)
			(hpglpenspeed 20)
			(hpglpendiameter 15.000000)
			(pdf_front_fp_property_popups yes)
			(pdf_back_fp_property_popups yes)
			(pdf_metadata yes)
			(pdf_single_document no)
			(dxfpolygonmode yes)
			(dxfimperialunits yes)
			(dxfusepcbnewfont yes)
			(psnegative no)
			(psa4output no)
			(plot_black_and_white yes)
			(sketchpadsonfab no)
			(plotpadnumbers no)
			(hidednponfab no)
			(sketchdnponfab yes)
			(crossoutdnponfab yes)
			(subtractmaskfromsilk no)
			(outputformat 1)
			(mirror no)
			(drillshape 1)
			(scaleselection 1)
			(outputdirectory "")
		)
	)
	(net 0 "")
	(net 1 "GND")
	(net 2 "+3V3")
	(net 3 "GNDREF")
	(net 4 "/USB_CC1")
	(net 5 "/USB_CC2")
	(net 6 "/USB_D_P")
	(net 7 "/USB_D_N")
	(net 8 "I2C_1_SCL")
	(net 9 "I2C_1_SDA")
	(net 10 "Net-(LD1-A)")
	(net 11 "Net-(LD2-A)")
	(net 12 "/LD2")
	(net 13 "JTRST")
	(net 14 "NRST")
	(net 15 "/FRAM_WP")
	(net 16 "LPUART_1_STM_RX")
	(net 17 "LPUART_1_STM_TX")
	(net 18 "SWCLK-JTCK")
	(net 19 "JTDO")
	(net 20 "SWDIO-JTMS")
	(net 21 "/FTDI_USER_PB")
	(net 22 "unconnected-(MP1-Pad1)")
	(net 23 "unconnected-(MP2-Pad1)")
	(net 24 "unconnected-(MP3-Pad1)")
	(net 25 "JTDI")
	(net 26 "+5V")
	(net 27 "/VBUS")
	(net 28 "Net-(U3-VBAT)")
	(net 29 "Net-(U1-3V3OUT)")
	(net 30 "Net-(U3-VDDA)")
	(net 31 "Net-(U3-PF1-OSC_OUT)")
	(net 32 "Net-(U3-VREF+)")
	(net 33 "Net-(U3-PF0-OSC_IN)")
	(net 34 "unconnected-(J1-SBU_{1}-PadA8)")
	(net 35 "unconnected-(J1-SBU_{2}-PadB8)")
	(net 36 "Net-(U1-RESET#)")
	(net 37 "Net-(U1-DTR#)")
	(net 38 "Net-(U1-RTS#)")
	(net 39 "Net-(U1-DSR#)")
	(net 40 "Net-(U1-DCD#)")
	(net 41 "Net-(U1-CTS#)")
	(net 42 "Net-(U1-RI#)")
	(net 43 "Net-(U1-CBUS0)")
	(net 44 "Net-(U1-TXD)")
	(net 45 "Net-(U1-RXD)")
	(net 46 "Net-(U3-PA15)")
	(net 47 "Net-(U3-PA8)")
	(net 48 "Net-(U3-PA9)")
	(net 49 "Net-(U3-PB8-BOOT0)")
	(net 50 "Net-(U3-PB9)")
	(net 51 "Net-(U4-A1)")
	(net 52 "Net-(U4-A2)")
	(net 53 "Net-(U6-SDO)")
	(net 54 "unconnected-(U1-NC-Pad29)")
	(net 55 "unconnected-(U1-OSCO-Pad28)")
	(net 56 "unconnected-(U1-OSCI-Pad27)")
	(net 57 "unconnected-(U1-NC-Pad25)")
	(net 58 "unconnected-(U1-NC-Pad23)")
	(net 59 "unconnected-(U1-CBUS1-Pad21)")
	(net 60 "unconnected-(U1-NC-Pad13)")
	(net 61 "unconnected-(U1-NC-Pad12)")
	(net 62 "unconnected-(U1-CBUS3-Pad11)")
	(net 63 "unconnected-(U1-CBUS2-Pad10)")
	(net 64 "unconnected-(U1-CBUS4-Pad9)")
	(net 65 "unconnected-(U1-NC-Pad5)")
	(net 66 "unconnected-(U3-PB7-Pad44)")
	(net 67 "unconnected-(U3-PB6-Pad43)")
	(net 68 "unconnected-(U3-PB5-Pad42)")
	(net 69 "unconnected-(U3-PA12-Pad34)")
	(net 70 "unconnected-(U3-PA11-Pad33)")
	(net 71 "unconnected-(U3-PA10-Pad32)")
	(net 72 "unconnected-(U3-PB15-Pad29)")
	(net 73 "unconnected-(U3-PB14-Pad28)")
	(net 74 "unconnected-(U3-PB13-Pad27)")
	(net 75 "unconnected-(U3-PB12-Pad26)")
	(net 76 "unconnected-(U3-PB10-Pad22)")
	(net 77 "unconnected-(U3-PB2-Pad18)")
	(net 78 "unconnected-(U3-PB1-Pad17)")
	(net 79 "unconnected-(U3-PB0-Pad16)")
	(net 80 "unconnected-(U3-PA7-Pad15)")
	(net 81 "unconnected-(U3-PA6-Pad14)")
	(net 82 "unconnected-(U3-PA4-Pad12)")
	(net 83 "unconnected-(U3-PA1-Pad9)")
	(net 84 "unconnected-(U3-PA0-Pad8)")
	(net 85 "unconnected-(U4-NC-Pad1)")
	(net 86 "/OSC32_IN")
	(net 87 "/OSC32_OUT")
	(net 88 "unconnected-(J2-PadMP)")
	(net 89 "unconnected-(J3-PadMP)")
	(footprint "antmicro-footprints:R_0402_1005Metric"
		(layer "F.Cu")
		(at 198.5 131.4)
		(descr "Resistor SMD 0402")
		(tags "resistor SMD 0402")
		(property "Reference" "R22"
			(at 0.85 0.4 0)
			(layer "F.SilkS")
			(effects
				(font
					(size 0.7 0.7)
					(thickness 0.15)
				)
				(justify left bottom)
			)
		)
		(property "Value" "R_100R_0402"
			(at -1.011843 1.772047 0)
			(layer "F.Fab")
			(effects
				(font
					(size 0.7 0.7)
					(thickness 0.15)
				)
				(justify left bottom)
			)
		)
		(property "Description" "SMD Chip Resistor, 100 ohm, ± 1%, 62.5 mW, 0402 [1005 Metric], Thick Film, General Purpose"
			(at 0 0 0)
			(layer "F.Fab")
			(hide yes)
			(effects
				(font
					(size 1.27 1.27)
					(thickness 0.15)
				)
			)
		)
		(property "Author" "Antmicro"
			(at 0 0 0)
			(layer "F.Fab")
			(hide yes)
			(effects
				(font
					(size 1 1)
					(thickness 0.15)
				)
			)
		)
		(property "License" "Apache-2.0"
			(at 0 0 0)
			(layer "F.Fab")
			(hide yes)
			(effects
				(font
					(size 1 1)
					(thickness 0.15)
				)
			)
		)
		(property "MPN" "CR0402-FX-1000GLF"
			(at 0 0 0)
			(layer "F.Fab")
			(hide yes)
			(effects
				(font
					(size 1 1)
					(thickness 0.15)
				)
			)
		)
		(property "Manufacturer" "Bourns"
			(at 0 0 0)
			(layer "F.Fab")
			(hide yes)
			(effects
				(font
					(size 1 1)
					(thickness 0.15)
				)
			)
		)
		(property "Public" "False"
			(at 0 0 0)
			(layer "F.Fab")
			(hide yes)
			(effects
				(font
					(size 1 1)
					(thickness 0.15)
				)
			)
		)
		(property "Tolerance" "1%"
			(at 0 0 0)
			(layer "F.Fab")
			(hide yes)
			(effects
				(font
					(size 1 1)
					(thickness 0.15)
				)
			)
		)
		(property "Val" "100R"
			(at 0 0 0)
			(layer "F.Fab")
			(hide yes)
			(effects
				(font
					(size 1 1)
					(thickness 0.15)
				)
			)
		)
		(sheetfile "environment-sensor.kicad_sch")
		(attr smd exclude_from_pos_files exclude_from_bom dnp)
		(fp_rect
			(start -0.925 -0.47)
			(end 0.925 0.47)
			(stroke
				(width 0.05)
				(type default)
			)
			(fill no)
			(layer "F.CrtYd")
		)
		(fp_rect
			(start -0.5 -0.25)
			(end 0.5 0.25)
			(stroke
				(width 0.15)
				(type solid)
			)
			(fill no)
			(layer "F.Fab")
		)
		(pad "1" smd roundrect
			(at -0.48 0)
			(size 0.59 0.64)
			(layers "F.Cu" "F.Mask" "F.Paste")
			(roundrect_rratio 0.25)
			(net 48 "Net-(U3-PA9)")
			(pintype "passive")
		)
		(pad "2" smd roundrect
			(at 0.48 0)
			(size 0.59 0.64)
			(layers "F.Cu" "F.Mask" "F.Paste")
			(roundrect_rratio 0.25)
			(net 8 "I2C_1_SCL")
			(pintype "passive")
		)
	)
	(footprint "antmicro-footprints:SOD-923"
		(layer "F.Cu")
		(at 168.035 123.95 -90)
		(property "Reference" "D1"
			(at 1.1 0.535 0)
			(unlocked yes)
			(layer "F.SilkS")
			(effects
				(font
					(size 0.65 0.65)
					(thickness 0.15)
				)
			)
		)
		(property "Value" "ESD9X5.0ST5G"
			(at 0 2.4 270)
			(unlocked yes)
			(layer "F.Fab")
			(effects
				(font
					(size 1 1)
					(thickness 0.15)
				)
			)
		)
		(property "Description" "Unidirectional TVS, 30 kV,  SOD-923, 5 V, 65 pF"
			(at 0 0 270)
			(layer "F.Fab")
			(hide yes)
			(effects
				(font
					(size 1.27 1.27)
					(thickness 0.15)
				)
			)
		)
		(property "Author" "Antmicro"
			(at 44.085 291.985 0)
			(layer "F.Fab")
			(hide yes)
			(effects
				(font
					(size 1 1)
					(thickness 0.15)
				)
			)
		)
		(property "License" "Apache-2.0"
			(at 44.085 291.985 0)
			(layer "F.Fab")
			(hide yes)
			(effects
				(font
					(size 1 1)
					(thickness 0.15)
				)
			)
		)
		(property "MPN" "ESD9X5.0ST5G"
			(at 44.085 291.985 0)
			(layer "F.Fab")
			(hide yes)
			(effects
				(font
					(size 1 1)
					(thickness 0.15)
				)
			)
		)
		(property "Manufacturer" "ON Semiconductor"
			(at 44.085 291.985 0)
			(layer "F.Fab")
			(hide yes)
			(effects
				(font
					(size 1 1)
					(thickness 0.15)
				)
			)
		)
		(property "Public" "False"
			(at 44.085 291.985 0)
			(layer "F.Fab")
			(hide yes)
			(effects
				(font
					(size 1 1)
					(thickness 0.15)
				)
			)
		)
		(sheetfile "environment-sensor.kicad_sch")
		(attr smd)
		(fp_line
			(start -0.5 0.4)
			(end 0.5 0.4)
			(stroke
				(width 0.15)
				(type solid)
			)
			(layer "F.SilkS")
		)
		(fp_line
			(start -0.5 0.4)
			(end -0.5 0.3)
			(stroke
				(width 0.15)
				(type solid)
			)
			(layer "F.SilkS")
		)
		(fp_line
			(start 0.5 0.4)
			(end 0.5 0.3)
			(stroke
				(width 0.15)
				(type solid)
			)
			(layer "F.SilkS")
		)
		(fp_line
			(start -0.5 -0.3)
			(end -0.5 -0.4)
			(stroke
				(width 0.15)
				(type solid)
			)
			(layer "F.SilkS")
		)
		(fp_line
			(start -0.5 -0.4)
			(end 0.5 -0.4)
			(stroke
				(width 0.15)
				(type solid)
			)
			(layer "F.SilkS")
		)
		(fp_line
			(start -0.16 -0.4)
			(end -0.16 0.4)
			(stroke
				(width 0.15)
				(type solid)
			)
			(layer "F.SilkS")
		)
		(fp_line
			(start 0.5 -0.4)
			(end 0.5 -0.3)
			(stroke
				(width 0.15)
				(type solid)
			)
			(layer "F.SilkS")
		)
		(fp_rect
			(start -0.68 -0.41)
			(end 0.68 0.41)
			(stroke
				(width 0.05)
				(type solid)
			)
			(fill no)
			(layer "F.CrtYd")
		)
		(fp_line
			(start -0.202 -0.3)
			(end -0.202 0.298)
			(stroke
				(width 0.15)
				(type solid)
			)
			(layer "F.Fab")
		)
		(fp_rect
			(start -0.402 -0.3)
			(end 0.4 0.298)
			(stroke
				(width 0.15)
				(type solid)
			)
			(fill no)
			(layer "F.Fab")
		)
		(fp_text user "${REFERENCE}"
			(at 0 1.1 270)
			(unlocked yes)
			(layer "F.Fab")
			(effects
				(font
					(size 1 1)
					(thickness 0.15)
				)
			)
		)
		(pad "1" smd roundrect
			(at -0.438 0 270)
			(size 0.4 0.325)
			(layers "F.Cu" "F.Mask" "F.Paste")
			(roundrect_rratio 0.25)
			(net 1 "GND")
			(pinfunction "C")
			(pintype "passive")
		)
		(pad "2" smd roundrect
			(at 0.436 0 270)
			(size 0.4 0.325)
			(layers "F.Cu" "F.Mask" "F.Paste")
			(roundrect_rratio 0.25)
			(net 27 "/VBUS")
			(pinfunction "A")
			(pintype "passive")
		)
	)
	(footprint "antmicro-footprints:C_0402_1005Metric"
		(layer "F.Cu")
		(at 172.6 136.15)
		(descr "Capacitor SMD 0402")
		(tags "capacitor SMD 0402")
		(property "Reference" "C8"
			(at 26.15 1.65 0)
			(layer "F.SilkS")
			(effects
				(font
					(size 0.7 0.7)
					(thickness 0.15)
				)
				(justify left bottom)
			)
		)
		(property "Value" "C_100n_0402"
			(at 0 1.4 0)
			(layer "F.Fab")
			(effects
				(font
					(size 0.7 0.7)
					(thickness 0.15)
				)
				(justify left bottom)
			)
		)
		(property "Description" "SMD Multilayer Ceramic Capacitor, 0.1 µF, 50 V, 0402 [1005 Metric], ± 10%, X5R, GRM Series"
			(at 0 0 0)
			(layer "F.Fab")
			(hide yes)
			(effects
				(font
					(size 1.27 1.27)
					(thickness 0.15)
				)
			)
		)
		(property "Author" "Antmicro"
			(at 0 0 0)
			(layer "F.Fab")
			(hide yes)
			(effects
				(font
					(size 1 1)
					(thickness 0.15)
				)
			)
		)
		(property "Dielectric" "X5R"
			(at 0 0 0)
			(layer "F.Fab")
			(hide yes)
			(effects
				(font
					(size 1 1)
					(thickness 0.15)
				)
			)
		)
		(property "License" "Apache-2.0"
			(at 0 0 0)
			(layer "F.Fab")
			(hide yes)
			(effects
				(font
					(size 1 1)
					(thickness 0.15)
				)
			)
		)
		(property "MPN" "GRM155R61H104KE14D"
			(at 0 0 0)
			(layer "F.Fab")
			(hide yes)
			(effects
				(font
					(size 1 1)
					(thickness 0.15)
				)
			)
		)
		(property "Manufacturer" "Murata"
			(at 0 0 0)
			(layer "F.Fab")
			(hide yes)
			(effects
				(font
					(size 1 1)
					(thickness 0.15)
				)
			)
		)
		(property "Public" "False"
			(at 0 0 0)
			(layer "F.Fab")
			(hide yes)
			(effects
				(font
					(size 1 1)
					(thickness 0.15)
				)
			)
		)
		(property "Val" "100n"
			(at 0 0 0)
			(layer "F.Fab")
			(hide yes)
			(effects
				(font
					(size 1 1)
					(thickness 0.15)
				)
			)
		)
		(property "Voltage" "50V"
			(at 0 0 0)
			(layer "F.Fab")
			(hide yes)
			(effects
				(font
					(size 1 1)
					(thickness 0.15)
				)
			)
		)
		(sheetfile "environment-sensor.kicad_sch")
		(attr smd)
		(fp_rect
			(start -0.925 -0.47)
			(end 0.925 0.47)
			(stroke
				(width 0.05)
				(type default)
			)
			(fill no)
			(layer "F.CrtYd")
		)
		(fp_line
			(start -0.494 -0.25)
			(end 0.504 -0.25)
			(stroke
				(width 0.15)
				(type solid)
			)
			(layer "F.Fab")
		)
		(fp_line
			(start -0.494 0.248)
			(end -0.494 -0.25)
			(stroke
				(width 0.15)
				(type solid)
			)
			(layer "F.Fab")
		)
		(fp_line
			(start 0.504 -0.25)
			(end 0.504 0.248)
			(stroke
				(width 0.15)
				(type solid)
			)
			(layer "F.Fab")
		)
		(fp_line
			(start 0.504 0.248)
			(end -0.494 0.248)
			(stroke
				(width 0.15)
				(type solid)
			)
			(layer "F.Fab")
		)
		(pad "1" smd roundrect
			(at -0.48 0)
			(size 0.59 0.64)
			(layers "F.Cu" "F.Mask" "F.Paste")
			(roundrect_rratio 0.25)
			(net 26 "+5V")
			(pintype "passive")
		)
		(pad "2" smd roundrect
			(at 0.48 0)
			(size 0.59 0.64)
			(layers "F.Cu" "F.Mask" "F.Paste")
			(roundrect_rratio 0.25)
			(net 1 "GND")
			(pintype "passive")
		)
	)
	(footprint "antmicro-footprints:MP_Pad5.4mm_Drill2.7mm"
		(layer "F.Cu")
		(at 163.55 117.05)
		(descr "Mounting Hole 2.7mm, M2.5")
		(tags "mounting hole 2.7mm m2.5")
		(property "Reference" "MP1"
			(at -3.5 -2.5 0)
			(layer "F.SilkS")
			(effects
				(font
					(size 0.7 0.7)
					(thickness 0.15)
				)
				(justify left bottom)
			)
		)
		(property "Value" "MP_Pad5.4mm_Drill2.7mm"
			(at 0 3.6 0)
			(layer "F.Fab")
			(effects
				(font
					(size 0.7 0.7)
					(thickness 0.15)
				)
				(justify left bottom)
			)
		)
		(property "Description" "Mechanical part"
			(at 0 0 0)
			(layer "F.Fab")
			(hide yes)
			(effects
				(font
					(size 1.27 1.27)
					(thickness 0.15)
				)
			)
		)
		(property "Author" "Antmicro"
			(at 0 0 0)
			(layer "F.Fab")
			(hide yes)
			(effects
				(font
					(size 1 1)
					(thickness 0.15)
				)
			)
		)
		(property "License" "Apache-2.0"
			(at 0 0 0)
			(layer "F.Fab")
			(hide yes)
			(effects
				(font
					(size 1 1)
					(thickness 0.15)
				)
			)
		)
		(property "Public" "False"
			(at 0 0 0)
			(layer "F.Fab")
			(hide yes)
			(effects
				(font
					(size 1 1)
					(thickness 0.15)
				)
			)
		)
		(sheetfile "environment-sensor.kicad_sch")
		(attr exclude_from_pos_files exclude_from_bom)
		(pad "1" thru_hole circle
			(at 0 0)
			(size 5.4 5.4)
			(drill 2.7)
			(layers "*.Cu" "*.Mask")
			(remove_unused_layers no)
			(net 22 "unconnected-(MP1-Pad1)")
			(pintype "passive+no_connect")
		)
	)
	(footprint "antmicro-footprints:TP_SMD_1.5mm"
		(locked yes)
		(layer "F.Cu")
		(at 183.5 116)
		(property "Reference" "TP5"
			(at -1.73 -1.079 0)
			(layer "F.SilkS")
			(hide yes)
			(effects
				(font
					(size 0.7 0.7)
					(thickness 0.15)
				)
				(justify left bottom)
			)
		)
		(property "Value" "TP_1.5mm_SMD"
			(at 0 1.7 0)
			(layer "F.Fab")
			(effects
				(font
					(size 0.7 0.7)
					(thickness 0.15)
				)
				(justify left bottom)
			)
		)
		(property "Description" "test point, SMT"
			(at 0 0 0)
			(layer "F.Fab")
			(hide yes)
			(effects
				(font
					(size 1.27 1.27)
					(thickness 0.15)
				)
			)
		)
		(property "Author" "Antmicro"
			(at 0 0 0)
			(layer "F.Fab")
			(hide yes)
			(effects
				(font
					(size 1 1)
					(thickness 0.15)
				)
			)
		)
		(property "License" "Apache-2.0"
			(at 0 0 0)
			(layer "F.Fab")
			(hide yes)
			(effects
				(font
					(size 1 1)
					(thickness 0.15)
				)
			)
		)
		(property "MPN" ""
			(at 0 0 0)
			(layer "F.Fab")
			(hide yes)
			(effects
				(font
					(size 1 1)
					(thickness 0.15)
				)
			)
		)
		(property "Manufacturer" ""
			(at 0 0 0)
			(layer "F.Fab")
			(hide yes)
			(effects
				(font
					(size 1 1)
					(thickness 0.15)
				)
			)
		)
		(property "Public" "False"
			(at 0 0 0)
			(layer "F.Fab")
			(hide yes)
			(effects
				(font
					(size 1 1)
					(thickness 0.15)
				)
			)
		)
		(sheetfile "environment-sensor.kicad_sch")
		(attr exclude_from_pos_files)
		(pad "1" smd circle
			(at 0 0 270)
			(size 1.5 1.5)
			(layers "F.Cu" "F.Mask")
			(net 19 "JTDO")
			(pinfunction "1")
			(pintype "passive")
		)
	)
	(footprint "antmicro-footprints:C_0402_1005Metric"
		(layer "F.Cu")
		(at 172.226 121.829 90)
		(descr "Capacitor SMD 0402")
		(tags "capacitor SMD 0402")
		(property "Reference" "C5"
			(at 0.936 -0.575 90)
			(layer "F.SilkS")
			(effects
				(font
					(size 0.7 0.7)
					(thickness 0.15)
				)
				(justify right bottom)
			)
		)
		(property "Value" "C_100n_0402"
			(at 0 1.4 90)
			(layer "F.Fab")
			(effects
				(font
					(size 0.7 0.7)
					(thickness 0.15)
				)
				(justify left bottom)
			)
		)
		(property "Description" "SMD Multilayer Ceramic Capacitor, 0.1 µF, 50 V, 0402 [1005 Metric], ± 10%, X5R, GRM Series"
			(at 0 0 90)
			(layer "F.Fab")
			(hide yes)
			(effects
				(font
					(size 1.27 1.27)
					(thickness 0.15)
				)
			)
		)
		(property "Author" "Antmicro"
			(at 294.055 -50.397 0)
			(layer "F.Fab")
			(hide yes)
			(effects
				(font
					(size 1 1)
					(thickness 0.15)
				)
			)
		)
		(property "Dielectric" "X5R"
			(at 294.055 -50.397 0)
			(layer "F.Fab")
			(hide yes)
			(effects
				(font
					(size 1 1)
					(thickness 0.15)
				)
			)
		)
		(property "License" "Apache-2.0"
			(at 294.055 -50.397 0)
			(layer "F.Fab")
			(hide yes)
			(effects
				(font
					(size 1 1)
					(thickness 0.15)
				)
			)
		)
		(property "MPN" "GRM155R61H104KE14D"
			(at 294.055 -50.397 0)
			(layer "F.Fab")
			(hide yes)
			(effects
				(font
					(size 1 1)
					(thickness 0.15)
				)
			)
		)
		(property "Manufacturer" "Murata"
			(at 294.055 -50.397 0)
			(layer "F.Fab")
			(hide yes)
			(effects
				(font
					(size 1 1)
					(thickness 0.15)
				)
			)
		)
		(property "Public" "False"
			(at 294.055 -50.397 0)
			(layer "F.Fab")
			(hide yes)
			(effects
				(font
					(size 1 1)
					(thickness 0.15)
				)
			)
		)
		(property "Val" "100n"
			(at 294.055 -50.397 0)
			(layer "F.Fab")
			(hide yes)
			(effects
				(font
					(size 1 1)
					(thickness 0.15)
				)
			)
		)
		(property "Voltage" "50V"
			(at 294.055 -50.397 0)
			(layer "F.Fab")
			(hide yes)
			(effects
				(font
					(size 1 1)
					(thickness 0.15)
				)
			)
		)
		(sheetfile "environment-sensor.kicad_sch")
		(attr smd)
		(fp_rect
			(start -0.925 -0.47)
			(end 0.925 0.47)
			(stroke
				(width 0.05)
				(type default)
			)
			(fill no)
			(layer "F.CrtYd")
		)
		(fp_line
			(start 0.504 -0.25)
			(end 0.504 0.248)
			(stroke
				(width 0.15)
				(type solid)
			)
			(layer "F.Fab")
		)
		(fp_line
			(start -0.494 -0.25)
			(end 0.504 -0.25)
			(stroke
				(width 0.15)
				(type solid)
			)
			(layer "F.Fab")
		)
		(fp_line
			(start 0.504 0.248)
			(end -0.494 0.248)
			(stroke
				(width 0.15)
				(type solid)
			)
			(layer "F.Fab")
		)
		(fp_line
			(start -0.494 0.248)
			(end -0.494 -0.25)
			(stroke
				(width 0.15)
				(type solid)
			)
			(layer "F.Fab")
		)
		(pad "1" smd roundrect
			(at -0.48 0 90)
			(size 0.59 0.64)
			(layers "F.Cu" "F.Mask" "F.Paste")
			(roundrect_rratio 0.25)
			(net 1 "GND")
			(pintype "passive")
		)
		(pad "2" smd roundrect
			(at 0.48 0 90)
			(size 0.59 0.64)
			(layers "F.Cu" "F.Mask" "F.Paste")
			(roundrect_rratio 0.25)
			(net 29 "Net-(U1-3V3OUT)")
			(pintype "passive")
		)
	)
	(footprint "antmicro-footprints:R_0402_1005Metric"
		(layer "F.Cu")
		(at 169.985 129.8)
		(descr "Resistor SMD 0402")
		(tags "resistor SMD 0402")
		(property "Reference" "R4"
			(at 0.915 0.4 0)
			(layer "F.SilkS")
			(effects
				(font
					(size 0.7 0.7)
					(thickness 0.15)
				)
				(justify left bottom)
			)
		)
		(property "Value" "R_5k1_0402"
			(at 0 1.4 0)
			(layer "F.Fab")
			(effects
				(font
					(size 0.7 0.7)
					(thickness 0.15)
				)
				(justify left bottom)
			)
		)
		(property "Description" "SMD Chip Resistor, 5.1 kohm, ± 1%, 63 mW, 0402 [1005 Metric], Thick Film, General Purpose"
			(at 0 0 0)
			(layer "F.Fab")
			(hide yes)
			(effects
				(font
					(size 1.27 1.27)
					(thickness 0.15)
				)
			)
		)
		(property "Author" "Antmicro"
			(at 0 0 0)
			(layer "F.Fab")
			(hide yes)
			(effects
				(font
					(size 1 1)
					(thickness 0.15)
				)
			)
		)
		(property "License" "Apache-2.0"
			(at 0 0 0)
			(layer "F.Fab")
			(hide yes)
			(effects
				(font
					(size 1 1)
					(thickness 0.15)
				)
			)
		)
		(property "MPN" "CR0402-FX-5101GLF"
			(at 0 0 0)
			(layer "F.Fab")
			(hide yes)
			(effects
				(font
					(size 1 1)
					(thickness 0.15)
				)
			)
		)
		(property "Manufacturer" "Bourns"
			(at 0 0 0)
			(layer "F.Fab")
			(hide yes)
			(effects
				(font
					(size 1 1)
					(thickness 0.15)
				)
			)
		)
		(property "Public" "False"
			(at 0 0 0)
			(layer "F.Fab")
			(hide yes)
			(effects
				(font
					(size 1 1)
					(thickness 0.15)
				)
			)
		)
		(property "Tolerance" "1%"
			(at 0 0 0)
			(layer "F.Fab")
			(hide yes)
			(effects
				(font
					(size 1 1)
					(thickness 0.15)
				)
			)
		)
		(property "Val" "5k1"
			(at 0 0 0)
			(layer "F.Fab")
			(hide yes)
			(effects
				(font
					(size 1 1)
					(thickness 0.15)
				)
			)
		)
		(sheetfile "environment-sensor.kicad_sch")
		(attr smd)
		(fp_rect
			(start -0.925 -0.47)
			(end 0.925 0.47)
			(stroke
				(width 0.05)
				(type default)
			)
			(fill no)
			(layer "F.CrtYd")
		)
		(fp_rect
			(start -0.5 -0.25)
			(end 0.5 0.25)
			(stroke
				(width 0.15)
				(type solid)
			)
			(fill no)
			(layer "F.Fab")
		)
		(pad "1" smd roundrect
			(at -0.48 0)
			(size 0.59 0.64)
			(layers "F.Cu" "F.Mask" "F.Paste")
			(roundrect_rratio 0.25)
			(net 1 "GND")
			(pintype "passive")
		)
		(pad "2" smd roundrect
			(at 0.48 0)
			(size 0.59 0.64)
			(layers "F.Cu" "F.Mask" "F.Paste")
			(roundrect_rratio 0.25)
			(net 5 "/USB_CC2")
			(pintype "passive")
		)
	)
	(footprint "antmicro-footprints:Resonator_SMD_ECS_ECX-31B_3.2x1.5x0.9mm"
		(layer "F.Cu")
		(at 180.65 131.05 -90)
		(property "Reference" "Y1"
			(at -0.5 1.2 90)
			(layer "F.SilkS")
			(effects
				(font
					(size 0.7 0.7)
					(thickness 0.15)
				)
				(justify right bottom)
			)
		)
		(property "Value" "Resonator_32.768kHz_ECX-31B"
			(at 0 2.25 90)
			(layer "F.Fab")
			(effects
				(font
					(size 0.7 0.7)
					(thickness 0.15)
				)
				(justify right bottom)
			)
		)
		(property "Description" "Crystal, 32.768 kHz, SMT, 3.2mm x 1.5mm, 12.5 pF, 20 ppm, ECX-31B"
			(at 0 0 270)
			(layer "F.Fab")
			(hide yes)
			(effects
				(font
					(size 1.27 1.27)
					(thickness 0.15)
				)
			)
		)
		(property "Author" "Antmicro"
			(at 49.6 311.7 0)
			(layer "F.Fab")
			(hide yes)
			(effects
				(font
					(size 1 1)
					(thickness 0.15)
				)
			)
		)
		(property "License" "Apache-2.0"
			(at 49.6 311.7 0)
			(layer "F.Fab")
			(hide yes)
			(effects
				(font
					(size 1 1)
					(thickness 0.15)
				)
			)
		)
		(property "MPN" "ECS-.327-12.5-34B-TR"
			(at 49.6 311.7 0)
			(layer "F.Fab")
			(hide yes)
			(effects
				(font
					(size 1 1)
					(thickness 0.15)
				)
			)
		)
		(property "Manufacturer" "ECS Inc. International"
			(at 49.6 311.7 0)
			(layer "F.Fab")
			(hide yes)
			(effects
				(font
					(size 1 1)
					(thickness 0.15)
				)
			)
		)
		(property "Public" "False"
			(at 49.6 311.7 0)
			(layer "F.Fab")
			(hide yes)
			(effects
				(font
					(size 1 1)
					(thickness 0.15)
				)
			)
		)
		(property "Val" "32.768 kHz"
			(at 49.6 311.7 0)
			(layer "F.Fab")
			(hide yes)
			(effects
				(font
					(size 1 1)
					(thickness 0.15)
				)
			)
		)
		(sheetfile "environment-sensor.kicad_sch")
		(attr smd)
		(fp_rect
			(start -2.001 -1.25)
			(end 2 1.248)
			(stroke
				(width 0.05)
				(type solid)
			)
			(fill no)
			(layer "F.CrtYd")
		)
		(fp_line
			(start -1.601 0.748)
			(end 1.6 0.748)
			(stroke
				(width 0.15)
				(type solid)
			)
			(layer "F.Fab")
		)
		(fp_line
			(start -1.601 0.748)
			(end -1.6 -0.4)
			(stroke
				(width 0.15)
				(type solid)
			)
			(layer "F.Fab")
		)
		(fp_line
			(start 1.6 0.748)
			(end 1.6 -0.75)
			(stroke
				(width 0.15)
				(type solid)
			)
			(layer "F.Fab")
		)
		(fp_line
			(start -1.3 -0.75)
			(end -1.6 -0.4)
			(stroke
				(width 0.15)
				(type solid)
			)
			(layer "F.Fab")
		)
		(fp_line
			(start 1.6 -0.75)
			(end -1.3 -0.75)
			(stroke
				(width 0.15)
				(type solid)
			)
			(layer "F.Fab")
		)
		(pad "1" smd rect
			(at -1.25 0 270)
			(size 1.1 1.9)
			(layers "F.Cu" "F.Mask" "F.Paste")
			(net 86 "/OSC32_IN")
			(pintype "passive")
		)
		(pad "2" smd rect
			(at 1.25 0 270)
			(size 1.1 1.9)
			(layers "F.Cu" "F.Mask" "F.Paste")
			(net 87 "/OSC32_OUT")
			(pintype "passive")
		)
	)
	(footprint "antmicro-footprints:TP_SMD_1mm"
		(layer "F.Cu")
		(at 176.2 134.55)
		(property "Reference" "TP10"
			(at 0 -0.731898 0)
			(layer "F.SilkS")
			(hide yes)
			(effects
				(font
					(size 0.7 0.7)
					(thickness 0.15)
				)
				(justify left bottom)
			)
		)
		(property "Value" "TP_1mm_SMD"
			(at 0 1.4 0)
			(layer "F.Fab")
			(effects
				(font
					(size 0.7 0.7)
					(thickness 0.15)
				)
				(justify left bottom)
			)
		)
		(property "Description" "Test point 1mm SMD"
			(at 0 0 0)
			(layer "F.Fab")
			(hide yes)
			(effects
				(font
					(size 1.27 1.27)
					(thickness 0.15)
				)
			)
		)
		(property "Author" "Antmicro"
			(at 0 0 0)
			(layer "F.Fab")
			(hide yes)
			(effects
				(font
					(size 1 1)
					(thickness 0.15)
				)
			)
		)
		(property "License" "Apache-2.0"
			(at 0 0 0)
			(layer "F.Fab")
			(hide yes)
			(effects
				(font
					(size 1 1)
					(thickness 0.15)
				)
			)
		)
		(property "MPN" ""
			(at 0 0 0)
			(layer "F.Fab")
			(hide yes)
			(effects
				(font
					(size 1 1)
					(thickness 0.15)
				)
			)
		)
		(property "Manufacturer" ""
			(at 0 0 0)
			(layer "F.Fab")
			(hide yes)
			(effects
				(font
					(size 1 1)
					(thickness 0.15)
				)
			)
		)
		(property "Public" "False"
			(at 0 0 0)
			(layer "F.Fab")
			(hide yes)
			(effects
				(font
					(size 1 1)
					(thickness 0.15)
				)
			)
		)
		(sheetfile "environment-sensor.kicad_sch")
		(attr exclude_from_pos_files)
		(pad "1" smd circle
			(at 0 0)
			(size 1 1)
			(layers "F.Cu" "F.Mask")
			(net 1 "GND")
			(pinfunction "1")
			(pintype "passive")
		)
	)
	(footprint "antmicro-footprints:C_0402_1005Metric"
		(layer "F.Cu")
		(at 182.91 130.4 180)
		(descr "Capacitor SMD 0402")
		(tags "capacitor SMD 0402")
		(property "Reference" "C14"
			(at -3.04 -0.45 0)
			(layer "F.SilkS")
			(effects
				(font
					(size 0.7 0.7)
					(thickness 0.15)
				)
				(justify right bottom)
			)
		)
		(property "Value" "C_16p_0402"
			(at -1.022927 2.155213 0)
			(layer "F.Fab")
			(effects
				(font
					(size 0.7 0.7)
					(thickness 0.15)
				)
				(justify right bottom)
			)
		)
		(property "Description" "SMD Multilayer Ceramic Capacitor, General Purpose, 16 pF, 50 V, 0402 [1005 Metric], ± 5%, C0G / NP0"
			(at 0 0 180)
			(layer "F.Fab")
			(hide yes)
			(effects
				(font
					(size 1.27 1.27)
					(thickness 0.15)
				)
			)
		)
		(property "Author" "Antmicro"
			(at 365.82 260.8 0)
			(layer "F.Fab")
			(hide yes)
			(effects
				(font
					(size 1 1)
					(thickness 0.15)
				)
			)
		)
		(property "Dielectric" ""
			(at 365.82 260.8 0)
			(layer "F.Fab")
			(hide yes)
			(effects
				(font
					(size 1 1)
					(thickness 0.15)
				)
			)
		)
		(property "License" "Apache-2.0"
			(at 365.82 260.8 0)
			(layer "F.Fab")
			(hide yes)
			(effects
				(font
					(size 1 1)
					(thickness 0.15)
				)
			)
		)
		(property "MPN" "0402N160J500CT"
			(at 365.82 260.8 0)
			(layer "F.Fab")
			(hide yes)
			(effects
				(font
					(size 1 1)
					(thickness 0.15)
				)
			)
		)
		(property "Manufacturer" "Walsin"
			(at 365.82 260.8 0)
			(layer "F.Fab")
			(hide yes)
			(effects
				(font
					(size 1 1)
					(thickness 0.15)
				)
			)
		)
		(property "Public" "False"
			(at 365.82 260.8 0)
			(layer "F.Fab")
			(hide yes)
			(effects
				(font
					(size 1 1)
					(thickness 0.15)
				)
			)
		)
		(property "Val" "16p"
			(at 365.82 260.8 0)
			(layer "F.Fab")
			(hide yes)
			(effects
				(font
					(size 1 1)
					(thickness 0.15)
				)
			)
		)
		(property "Voltage" ""
			(at 365.82 260.8 0)
			(layer "F.Fab")
			(hide yes)
			(effects
				(font
					(size 1 1)
					(thickness 0.15)
				)
			)
		)
		(sheetfile "environment-sensor.kicad_sch")
		(attr smd)
		(fp_rect
			(start -0.925 -0.47)
			(end 0.925 0.47)
			(stroke
				(width 0.05)
				(type default)
			)
			(fill no)
			(layer "F.CrtYd")
		)
		(fp_line
			(start 0.504 0.248)
			(end -0.494 0.248)
			(stroke
				(width 0.15)
				(type solid)
			)
			(layer "F.Fab")
		)
		(fp_line
			(start 0.504 -0.25)
			(end 0.504 0.248)
			(stroke
				(width 0.15)
				(type solid)
			)
			(layer "F.Fab")
		)
		(fp_line
			(start -0.494 0.248)
			(end -0.494 -0.25)
			(stroke
				(width 0.15)
				(type solid)
			)
			(layer "F.Fab")
		)
		(fp_line
			(start -0.494 -0.25)
			(end 0.504 -0.25)
			(stroke
				(width 0.15)
				(type solid)
			)
			(layer "F.Fab")
		)
		(pad "1" smd roundrect
			(at -0.48 0 180)
			(size 0.59 0.64)
			(layers "F.Cu" "F.Mask" "F.Paste")
			(roundrect_rratio 0.25)
			(net 86 "/OSC32_IN")
			(pintype "passive")
		)
		(pad "2" smd roundrect
			(at 0.48 0 180)
			(size 0.59 0.64)
			(layers "F.Cu" "F.Mask" "F.Paste")
			(roundrect_rratio 0.25)
			(net 1 "GND")
			(pintype "passive")
		)
	)
	(footprint "antmicro-footprints:QFN-32-1EP_5x5mm"
		(layer "F.Cu")
		(at 175.9435 119.042 -90)
		(property "Reference" "U1"
			(at -2.342 -3.9065 0)
			(layer "F.SilkS")
			(effects
				(font
					(size 0.7 0.7)
					(thickness 0.15)
				)
				(justify right bottom)
			)
		)
		(property "Value" "FT232R_QFN"
			(at -4.939 3.91 90)
			(layer "F.Fab")
			(effects
				(font
					(size 0.7 0.7)
					(thickness 0.15)
				)
				(justify right bottom)
			)
		)
		(property "Description" "Interface Bridges, USB to UART, 1.8 V, 5.25 V, QFN, 32 Pins, -40 °C"
			(at 0 0 270)
			(layer "F.Fab")
			(hide yes)
			(effects
				(font
					(size 1.27 1.27)
					(thickness 0.15)
				)
			)
		)
		(property "Author" "Antmicro"
			(at 56.9015 294.9855 0)
			(layer "F.Fab")
			(hide yes)
			(effects
				(font
					(size 1 1)
					(thickness 0.15)
				)
			)
		)
		(property "License" "Apache-2.0"
			(at 56.9015 294.9855 0)
			(layer "F.Fab")
			(hide yes)
			(effects
				(font
					(size 1 1)
					(thickness 0.15)
				)
			)
		)
		(property "MPN" "FT232RQ-REEL"
			(at 56.9015 294.9855 0)
			(layer "F.Fab")
			(hide yes)
			(effects
				(font
					(size 1 1)
					(thickness 0.15)
				)
			)
		)
		(property "Manufacturer" "FTDI Chip"
			(at 56.9015 294.9855 0)
			(layer "F.Fab")
			(hide yes)
			(effects
				(font
					(size 1 1)
					(thickness 0.15)
				)
			)
		)
		(sheetfile "environment-sensor.kicad_sch")
		(attr smd)
		(fp_line
			(start -2.62 2.648)
			(end -2.62 2.249)
			(stroke
				(width 0.15)
				(type solid)
			)
			(layer "F.SilkS")
		)
		(fp_line
			(start -2.221 2.648)
			(end -2.62 2.648)
			(stroke
				(width 0.15)
				(type solid)
			)
			(layer "F.SilkS")
		)
		(fp_line
			(start 2.581 2.648)
			(end 2.178 2.648)
			(stroke
				(width 0.15)
				(type solid)
			)
			(layer "F.SilkS")
		)
		(fp_line
			(start 2.581 2.249)
			(end 2.581 2.648)
			(stroke
				(width 0.15)
				(type solid)
			)
			(layer "F.SilkS")
		)
		(fp_line
			(start -2.221 -2.551)
			(end -2.62 -2.149)
			(stroke
				(width 0.15)
				(type solid)
			)
			(layer "F.SilkS")
		)
		(fp_line
			(start 2.581 -2.551)
			(end 2.581 -2.149)
			(stroke
				(width 0.15)
				(type solid)
			)
			(layer "F.SilkS")
		)
		(fp_line
			(start 2.581 -2.551)
			(end 2.178 -2.551)
			(stroke
				(width 0.15)
				(type solid)
			)
			(layer "F.SilkS")
		)
		(fp_circle
			(center -3.25 -1.702)
			(end -3.2 -1.702)
			(stroke
				(width 0.15)
				(type solid)
			)
			(fill yes)
			(layer "F.SilkS")
		)
		(fp_rect
			(start -1.446 1.474)
			(end -0.246 0.274)
			(stroke
				(width 0.2)
				(type solid)
			)
			(fill yes)
			(layer "F.Paste")
		)
		(fp_rect
			(start 0.203 1.474)
			(end 1.403 0.274)
			(stroke
				(width 0.2)
				(type solid)
			)
			(fill yes)
			(layer "F.Paste")
		)
		(fp_rect
			(start -1.446 -0.175)
			(end -0.246 -1.375)
			(stroke
				(width 0.2)
				(type solid)
			)
			(fill yes)
			(layer "F.Paste")
		)
		(fp_rect
			(start 0.203 -0.175)
			(end 1.403 -1.375)
			(stroke
				(width 0.2)
				(type solid)
			)
			(fill yes)
			(layer "F.Paste")
		)
		(fp_rect
			(start -2.74 -2.75)
			(end 2.75 2.74)
			(stroke
				(width 0.05)
				(type solid)
			)
			(fill no)
			(layer "F.CrtYd")
		)
		(fp_line
			(start -2.499 -2.299)
			(end -2.298 -2.5)
			(stroke
				(width 0.15)
				(type solid)
			)
			(layer "F.Fab")
		)
		(fp_rect
			(start -2.499 -2.5)
			(end 2.5 2.499)
			(stroke
				(width 0.15)
				(type solid)
			)
			(fill no)
			(layer "F.Fab")
		)
		(pad "1" smd rect
			(at -2.495 -1.702 180)
			(size 0.28 0.85)
			(layers "F.Cu" "F.Mask" "F.Paste")
			(net 29 "Net-(U1-3V3OUT)")
			(pinfunction "VCCIO")
			(pintype "power_in")
			(solder_mask_margin 0.07)
		)
		(pad "2" smd rect
			(at -2.495 -1.2 180)
			(size 0.28 0.85)
			(layers "F.Cu" "F.Mask" "F.Paste")
			(net 45 "Net-(U1-RXD)")
			(pinfunction "RXD")
			(pintype "input")
			(solder_mask_margin 0.07)
		)
		(pad "3" smd rect
			(at -2.495 -0.701 180)
			(size 0.28 0.85)
			(layers "F.Cu" "F.Mask" "F.Paste")
			(net 42 "Net-(U1-RI#)")
			(pinfunction "RI#")
			(pintype "input")
			(solder_mask_margin 0.07)
		)
		(pad "4" smd rect
			(at -2.495 -0.201 180)
			(size 0.28 0.85)
			(layers "F.Cu" "F.Mask" "F.Paste")
			(net 1 "GND")
			(pinfunction "GND")
			(pintype "passive")
			(solder_mask_margin 0.07)
		)
		(pad "5" smd rect
			(at -2.495 0.296 180)
			(size 0.28 0.85)
			(layers "F.Cu" "F.Mask" "F.Paste")
			(net 65 "unconnected-(U1-NC-Pad5)")
			(pinfunction "NC")
			(pintype "no_connect")
			(solder_mask_margin 0.07)
		)
		(pad "6" smd rect
			(at -2.495 0.8 180)
			(size 0.28 0.85)
			(layers "F.Cu" "F.Mask" "F.Paste")
			(net 39 "Net-(U1-DSR#)")
			(pinfunction "DSR#")
			(pintype "input")
			(solder_mask_margin 0.07)
		)
		(pad "7" smd rect
			(at -2.495 1.3 180)
			(size 0.28 0.85)
			(layers "F.Cu" "F.Mask" "F.Paste")
			(net 40 "Net-(U1-DCD#)")
			(pinfunction "DCD#")
			(pintype "input")
			(solder_mask_margin 0.07)
		)
		(pad "8" smd rect
			(at -2.495 1.8 180)
			(size 0.28 0.85)
			(layers "F.Cu" "F.Mask" "F.Paste")
			(net 41 "Net-(U1-CTS#)")
			(pinfunction "CTS#")
			(pintype "input")
			(solder_mask_margin 0.07)
		)
		(pad "9" smd rect
			(at -1.768 2.523 180)
			(size 0.85 0.28)
			(layers "F.Cu" "F.Mask" "F.Paste")
			(net 64 "unconnected-(U1-CBUS4-Pad9)")
			(pinfunction "CBUS4")
			(pintype "bidirectional+no_connect")
			(solder_mask_margin 0.07)
		)
		(pad "10" smd rect
			(at -1.269 2.523 180)
			(size 0.85 0.28)
			(layers "F.Cu" "F.Mask" "F.Paste")
			(net 63 "unconnected-(U1-CBUS2-Pad10)")
			(pinfunction "CBUS2")
			(pintype "bidirectional+no_connect")
			(solder_mask_margin 0.07)
		)
		(pad "11" smd rect
			(at -0.772 2.523 180)
			(size 0.85 0.28)
			(layers "F.Cu" "F.Mask" "F.Paste")
			(net 62 "unconnected-(U1-CBUS3-Pad11)")
			(pinfunction "CBUS3")
			(pintype "bidirectional+no_connect")
			(solder_mask_margin 0.07)
		)
		(pad "12" smd rect
			(at -0.272 2.523 180)
			(size 0.85 0.28)
			(layers "F.Cu" "F.Mask" "F.Paste")
			(net 61 "unconnected-(U1-NC-Pad12)")
			(pinfunction "NC")
			(pintype "no_connect")
			(solder_mask_margin 0.07)
		)
		(pad "13" smd rect
			(at 0.229 2.523 180)
			(size 0.85 0.28)
			(layers "F.Cu" "F.Mask" "F.Paste")
			(net 60 "unconnected-(U1-NC-Pad13)")
			(pinfunction "NC")
			(pintype "no_connect")
			(solder_mask_margin 0.07)
		)
		(pad "14" smd rect
			(at 0.728 2.523 180)
			(size 0.85 0.28)
			(layers "F.Cu" "F.Mask" "F.Paste")
			(net 6 "/USB_D_P")
			(pinfunction "USBDP")
			(pintype "bidirectional")
			(solder_mask_margin 0.07)
		)
		(pad "15" smd rect
			(at 1.23 2.523 180)
			(size 0.85 0.28)
			(layers "F.Cu" "F.Mask" "F.Paste")
			(net 7 "/USB_D_N")
			(pinfunction "USBDM")
			(pintype "bidirectional")
			(solder_mask_margin 0.07)
		)
		(pad "16" smd rect
			(at 1.73 2.523 180)
			(size 0.85 0.28)
			(layers "F.Cu" "F.Mask" "F.Paste")
			(net 29 "Net-(U1-3V3OUT)")
			(pinfunction "3V3OUT")
			(pintype "output")
			(solder_mask_margin 0.07)
		)
		(pad "17" smd rect
			(at 2.456 1.8 180)
			(size 0.28 0.85)
			(layers "F.Cu" "F.Mask" "F.Paste")
			(net 1 "GND")
			(pinfunction "GND")
			(pintype "power_in")
			(solder_mask_margin 0.07)
		)
		(pad "18" smd rect
			(at 2.456 1.3 180)
			(size 0.28 0.85)
			(layers "F.Cu" "F.Mask" "F.Paste")
			(net 36 "Net-(U1-RESET#)")
			(pinfunction "RESET#")
			(pintype "input")
			(solder_mask_margin 0.07)
		)
		(pad "19" smd rect
			(at 2.456 0.8 180)
			(size 0.28 0.85)
			(layers "F.Cu" "F.Mask" "F.Paste")
			(net 26 "+5V")
			(pinfunction "VCC")
			(pintype "power_in")
			(solder_mask_margin 0.07)
		)
		(pad "20" smd rect
			(at 2.456 0.296 180)
			(size 0.28 0.85)
			(layers "F.Cu" "F.Mask" "F.Paste")
			(net 1 "GND")
			(pinfunction "GND")
			(pintype "passive")
			(solder_mask_margin 0.07)
		)
		(pad "21" smd rect
			(at 2.456 -0.201 180)
			(size 0.28 0.85)
			(layers "F.Cu" "F.Mask" "F.Paste")
			(net 59 "unconnected-(U1-CBUS1-Pad21)")
			(pinfunction "CBUS1")
			(pintype "bidirectional+no_connect")
			(solder_mask_margin 0.07)
		)
		(pad "22" smd rect
			(at 2.456 -0.701 180)
			(size 0.28 0.85)
			(layers "F.Cu" "F.Mask" "F.Paste")
			(net 43 "Net-(U1-CBUS0)")
			(pinfunction "CBUS0")
			(pintype "bidirectional")
			(solder_mask_margin 0.07)
		)
		(pad "23" smd rect
			(at 2.456 -1.2 180)
			(size 0.28 0.85)
			(layers "F.Cu" "F.Mask" "F.Paste")
			(net 58 "unconnected-(U1-NC-Pad23)")
			(pinfunction "NC")
			(pintype "no_connect")
			(solder_mask_margin 0.07)
		)
		(pad "24" smd rect
			(at 2.456 -1.702 180)
			(size 0.28 0.85)
			(layers "F.Cu" "F.Mask" "F.Paste")
			(net 1 "GND")
			(pinfunction "AGND")
			(pintype "power_in")
			(solder_mask_margin 0.07)
		)
		(pad "25" smd rect
			(at 1.73 -2.426 180)
			(size 0.85 0.28)
			(layers "F.Cu" "F.Mask" "F.Paste")
			(net 57 "unconnected-(U1-NC-Pad25)")
			(pinfunction "NC")
			(pintype "no_connect")
			(solder_mask_margin 0.07)
		)
		(pad "26" smd rect
			(at 1.23 -2.426 180)
			(size 0.85 0.28)
			(layers "F.Cu" "F.Mask" "F.Paste")
			(net 1 "GND")
			(pinfunction "TEST")
			(pintype "input")
			(solder_mask_margin 0.07)
		)
		(pad "27" smd rect
			(at 0.728 -2.426 180)
			(size 0.85 0.28)
			(layers "F.Cu" "F.Mask" "F.Paste")
			(net 56 "unconnected-(U1-OSCI-Pad27)")
			(pinfunction "OSCI")
			(pintype "input+no_connect")
			(solder_mask_margin 0.07)
		)
		(pad "28" smd rect
			(at 0.229 -2.426 180)
			(size 0.85 0.28)
			(layers "F.Cu" "F.Mask" "F.Paste")
			(net 55 "unconnected-(U1-OSCO-Pad28)")
			(pinfunction "OSCO")
			(pintype "output+no_connect")
			(solder_mask_margin 0.07)
		)
		(pad "29" smd rect
			(at -0.272 -2.426 180)
			(size 0.85 0.28)
			(layers "F.Cu" "F.Mask" "F.Paste")
			(net 54 "unconnected-(U1-NC-Pad29)")
			(pinfunction "NC")
			(pintype "no_connect")
			(solder_mask_margin 0.07)
		)
		(pad "30" smd rect
			(at -0.772 -2.426 180)
			(size 0.85 0.28)
			(layers "F.Cu" "F.Mask" "F.Paste")
			(net 44 "Net-(U1-TXD)")
			(pinfunction "TXD")
			(pintype "output")
			(solder_mask_margin 0.07)
		)
		(pad "31" smd rect
			(at -1.269 -2.426 180)
			(size 0.85 0.28)
			(layers "F.Cu" "F.Mask" "F.Paste")
			(net 37 "Net-(U1-DTR#)")
			(pinfunction "DTR#")
			(pintype "output")
			(solder_mask_margin 0.07)
		)
		(pad "32" smd rect
			(at -1.768 -2.426 180)
			(size 0.85 0.28)
			(layers "F.Cu" "F.Mask" "F.Paste")
			(net 38 "Net-(U1-RTS#)")
			(pinfunction "RTS#")
			(pintype "output")
			(solder_mask_margin 0.07)
		)
		(pad "33" smd rect
			(at -0.02 0.048 180)
			(size 3.45 3.45)
			(layers "F.Cu" "F.Mask")
			(net 1 "GND")
			(pinfunction "EP")
			(pintype "passive")
		)
	)
	(footprint "antmicro-footprints:R_0402_1005Metric"
		(layer "F.Cu")
		(at 198.5 133.6 180)
		(descr "Resistor SMD 0402")
		(tags "resistor SMD 0402")
		(property "Reference" "R38"
			(at -0.85 -0.4 180)
			(layer "F.SilkS")
			(effects
				(font
					(size 0.7 0.7)
					(thickness 0.15)
				)
				(justify left bottom)
			)
		)
		(property "Value" "R_5k1_0402"
			(at 0 1.4 180)
			(layer "F.Fab")
			(effects
				(font
					(size 0.7 0.7)
					(thickness 0.15)
				)
				(justify left bottom)
			)
		)
		(property "Description" "SMD Chip Resistor, 5.1 kohm, ± 1%, 63 mW, 0402 [1005 Metric], Thick Film, General Purpose"
			(at 0 0 180)
			(layer "F.Fab")
			(hide yes)
			(effects
				(font
					(size 1.27 1.27)
					(thickness 0.15)
				)
			)
		)
		(property "Author" "Antmicro"
			(at 397 267.2 0)
			(layer "F.Fab")
			(hide yes)
			(effects
				(font
					(size 1 1)
					(thickness 0.15)
				)
			)
		)
		(property "License" "Apache-2.0"
			(at 397 267.2 0)
			(layer "F.Fab")
			(hide yes)
			(effects
				(font
					(size 1 1)
					(thickness 0.15)
				)
			)
		)
		(property "MPN" "CR0402-FX-5101GLF"
			(at 397 267.2 0)
			(layer "F.Fab")
			(hide yes)
			(effects
				(font
					(size 1 1)
					(thickness 0.15)
				)
			)
		)
		(property "Manufacturer" "Bourns"
			(at 397 267.2 0)
			(layer "F.Fab")
			(hide yes)
			(effects
				(font
					(size 1 1)
					(thickness 0.15)
				)
			)
		)
		(property "Public" "False"
			(at 397 267.2 0)
			(layer "F.Fab")
			(hide yes)
			(effects
				(font
					(size 1 1)
					(thickness 0.15)
				)
			)
		)
		(property "Tolerance" "1%"
			(at 397 267.2 0)
			(layer "F.Fab")
			(hide yes)
			(effects
				(font
					(size 1 1)
					(thickness 0.15)
				)
			)
		)
		(property "Val" "5k1"
			(at 397 267.2 0)
			(layer "F.Fab")
			(hide yes)
			(effects
				(font
					(size 1 1)
					(thickness 0.15)
				)
			)
		)
		(sheetfile "environment-sensor.kicad_sch")
		(attr smd)
		(fp_rect
			(start -0.925 -0.47)
			(end 0.925 0.47)
			(stroke
				(width 0.05)
				(type default)
			)
			(fill no)
			(layer "F.CrtYd")
		)
		(fp_rect
			(start -0.5 -0.25)
			(end 0.5 0.25)
			(stroke
				(width 0.15)
				(type solid)
			)
			(fill no)
			(layer "F.Fab")
		)
		(pad "1" smd roundrect
			(at -0.48 0 180)
			(size 0.59 0.64)
			(layers "F.Cu" "F.Mask" "F.Paste")
			(roundrect_rratio 0.25)
			(net 9 "I2C_1_SDA")
			(pintype "passive")
		)
		(pad "2" smd roundrect
			(at 0.48 0 180)
			(size 0.59 0.64)
			(layers "F.Cu" "F.Mask" "F.Paste")
			(roundrect_rratio 0.25)
			(net 2 "+3V3")
			(pintype "passive")
		)
	)
	(footprint "antmicro-footprints:C_0402_1005Metric"
		(layer "F.Cu")
		(at 172.6 137.3)
		(descr "Capacitor SMD 0402")
		(tags "capacitor SMD 0402")
		(property "Reference" "C7"
			(at 26.15 1.4 180)
			(layer "F.SilkS")
			(effects
				(font
					(size 0.7 0.7)
					(thickness 0.15)
				)
				(justify left bottom)
			)
		)
		(property "Value" "C_2u2_0402"
			(at 0 1.4 0)
			(layer "F.Fab")
			(effects
				(font
					(size 0.7 0.7)
					(thickness 0.15)
				)
				(justify left bottom)
			)
		)
		(property "Description" "SMD Multilayer Ceramic Capacitor, 2.2 µF, 10 V, 0402 [1005 Metric], ± 10%, X5R, C"
			(at 0 0 0)
			(layer "F.Fab")
			(hide yes)
			(effects
				(font
					(size 1.27 1.27)
					(thickness 0.15)
				)
			)
		)
		(property "Author" "Antmicro"
			(at 0 0 0)
			(layer "F.Fab")
			(hide yes)
			(effects
				(font
					(size 1 1)
					(thickness 0.15)
				)
			)
		)
		(property "Dielectric" ""
			(at 0 0 0)
			(layer "F.Fab")
			(hide yes)
			(effects
				(font
					(size 1 1)
					(thickness 0.15)
				)
			)
		)
		(property "License" "Apache-2.0"
			(at 0 0 0)
			(layer "F.Fab")
			(hide yes)
			(effects
				(font
					(size 1 1)
					(thickness 0.15)
				)
			)
		)
		(property "MPN" "C1005X5R1A225K050BC"
			(at 0 0 0)
			(layer "F.Fab")
			(hide yes)
			(effects
				(font
					(size 1 1)
					(thickness 0.15)
				)
			)
		)
		(property "Manufacturer" "TDK"
			(at 0 0 0)
			(layer "F.Fab")
			(hide yes)
			(effects
				(font
					(size 1 1)
					(thickness 0.15)
				)
			)
		)
		(property "Public" "False"
			(at 0 0 0)
			(layer "F.Fab")
			(hide yes)
			(effects
				(font
					(size 1 1)
					(thickness 0.15)
				)
			)
		)
		(property "Val" "2u2"
			(at 0 0 0)
			(layer "F.Fab")
			(hide yes)
			(effects
				(font
					(size 1 1)
					(thickness 0.15)
				)
			)
		)
		(property "Voltage" ""
			(at 0 0 0)
			(layer "F.Fab")
			(hide yes)
			(effects
				(font
					(size 1 1)
					(thickness 0.15)
				)
			)
		)
		(sheetfile "environment-sensor.kicad_sch")
		(attr smd)
		(fp_rect
			(start -0.925 -0.47)
			(end 0.925 0.47)
			(stroke
				(width 0.05)
				(type default)
			)
			(fill no)
			(layer "F.CrtYd")
		)
		(fp_line
			(start -0.494 -0.25)
			(end 0.504 -0.25)
			(stroke
				(width 0.15)
				(type solid)
			)
			(layer "F.Fab")
		)
		(fp_line
			(start -0.494 0.248)
			(end -0.494 -0.25)
			(stroke
				(width 0.15)
				(type solid)
			)
			(layer "F.Fab")
		)
		(fp_line
			(start 0.504 -0.25)
			(end 0.504 0.248)
			(stroke
				(width 0.15)
				(type solid)
			)
			(layer "F.Fab")
		)
		(fp_line
			(start 0.504 0.248)
			(end -0.494 0.248)
			(stroke
				(width 0.15)
				(type solid)
			)
			(layer "F.Fab")
		)
		(pad "1" smd roundrect
			(at -0.48 0)
			(size 0.59 0.64)
			(layers "F.Cu" "F.Mask" "F.Paste")
			(roundrect_rratio 0.25)
			(net 26 "+5V")
			(pintype "passive")
		)
		(pad "2" smd roundrect
			(at 0.48 0)
			(size 0.59 0.64)
			(layers "F.Cu" "F.Mask" "F.Paste")
			(roundrect_rratio 0.25)
			(net 1 "GND")
			(pintype "passive")
		)
	)
	(footprint "antmicro-footprints:SOT-723"
		(layer "F.Cu")
		(at 169.448 126.768)
		(property "Reference" "D5"
			(at 1.552 0.032 90)
			(layer "F.SilkS")
			(effects
				(font
					(size 0.65 0.65)
					(thickness 0.15)
				)
			)
		)
		(property "Value" "TPD2E009_SOT-9X3"
			(at -0.025 2.975 0)
			(layer "F.Fab")
			(effects
				(font
					(size 1 1)
					(thickness 0.15)
				)
			)
		)
		(property "Description" "TVS diode array, 8 kV, SOT-723, 5.5 V, 0.9 pF"
			(at 0 0 0)
			(layer "F.Fab")
			(hide yes)
			(effects
				(font
					(size 1.27 1.27)
					(thickness 0.15)
				)
			)
		)
		(property "Author" "Antmicro"
			(at 0 0 0)
			(layer "F.Fab")
			(hide yes)
			(effects
				(font
					(size 1 1)
					(thickness 0.15)
				)
			)
		)
		(property "License" "Apache-2.0"
			(at 0 0 0)
			(layer "F.Fab")
			(hide yes)
			(effects
				(font
					(size 1 1)
					(thickness 0.15)
				)
			)
		)
		(property "MPN" "TPD2E009DRTR"
			(at 0 0 0)
			(layer "F.Fab")
			(hide yes)
			(effects
				(font
					(size 1 1)
					(thickness 0.15)
				)
			)
		)
		(property "Manufacturer" "Texas Instruments"
			(at 0 0 0)
			(layer "F.Fab")
			(hide yes)
			(effects
				(font
					(size 1 1)
					(thickness 0.15)
				)
			)
		)
		(sheetfile "environment-sensor.kicad_sch")
		(attr smd)
		(fp_line
			(start -0.43 -0.1375)
			(end -0.43 0.1375)
			(stroke
				(width 0.15)
				(type solid)
			)
			(layer "F.SilkS")
		)
		(fp_line
			(start 0.43 -0.63)
			(end -0.2175 -0.63)
			(stroke
				(width 0.15)
				(type solid)
			)
			(layer "F.SilkS")
		)
		(fp_line
			(start 0.43 -0.23)
			(end 0.43 -0.63)
			(stroke
				(width 0.15)
				(type solid)
			)
			(layer "F.SilkS")
		)
		(fp_line
			(start 0.43 0.23)
			(end 0.43 0.63)
			(stroke
				(width 0.15)
				(type solid)
			)
			(layer "F.SilkS")
		)
		(fp_line
			(start 0.43 0.63)
			(end -0.22 0.63)
			(stroke
				(width 0.15)
				(type solid)
			)
			(layer "F.SilkS")
		)
		(fp_rect
			(start -0.83 -0.83)
			(end 0.83 0.83)
			(stroke
				(width 0.05)
				(type solid)
			)
			(fill no)
			(layer "F.CrtYd")
		)
		(fp_line
			(start -0.09 -0.53)
			(end -0.43 -0.19)
			(stroke
				(width 0.15)
				(type solid)
			)
			(layer "F.Fab")
		)
		(fp_line
			(start 0.424 -0.528)
			(end 0.424 0.524)
			(stroke
				(width 0.15)
				(type solid)
			)
			(layer "F.Fab")
		)
		(fp_line
			(start 0.424 0.524)
			(end -0.424 0.524)
			(stroke
				(width 0.15)
				(type solid)
			)
			(layer "F.Fab")
		)
		(fp_rect
			(start 0.424 0.524)
			(end -0.43 -0.528)
			(stroke
				(width 0.15)
				(type solid)
			)
			(fill no)
			(layer "F.Fab")
		)
		(fp_text user "${REFERENCE}"
			(at 0 0 0)
			(layer "F.Fab")
			(effects
				(font
					(size 0.2 0.2)
					(thickness 0.025)
				)
			)
		)
		(pad "1" smd rect
			(at -0.501 -0.401 270)
			(size 0.3 0.4)
			(layers "F.Cu" "F.Mask" "F.Paste")
			(net 6 "/USB_D_P")
			(pinfunction "1")
			(pintype "passive")
		)
		(pad "2" smd rect
			(at -0.501 0.399 270)
			(size 0.3 0.4)
			(layers "F.Cu" "F.Mask" "F.Paste")
			(net 7 "/USB_D_N")
			(pinfunction "2")
			(pintype "passive")
		)
		(pad "3" smd rect
			(at 0.499 -0.001 270)
			(size 0.3 0.4)
			(layers "F.Cu" "F.Mask" "F.Paste")
			(net 1 "GND")
			(pinfunction "3")
			(pintype "passive")
		)
	)
	(footprint "antmicro-footprints:R_0402_1005Metric"
		(layer "F.Cu")
		(at 180.75 126.25 90)
		(descr "Resistor SMD 0402")
		(tags "resistor SMD 0402")
		(property "Reference" "R20"
			(at 11.75 1.25 270)
			(layer "B.SilkS")
			(effects
				(font
					(size 0.7 0.7)
					(thickness 0.15)
				)
				(justify left bottom mirror)
			)
		)
		(property "Value" "R_0R_0402"
			(at 0 1.4 90)
			(layer "F.Fab")
			(effects
				(font
					(size 0.7 0.7)
					(thickness 0.15)
				)
				(justify left bottom)
			)
		)
		(property "Description" "SMD Chip Resistor, Jumper, 0 ohm, 100 mW, 0402 [1005 Metric], Thick Film, General Purpose"
			(at 0 0 90)
			(layer "F.Fab")
			(hide yes)
			(effects
				(font
					(size 1.27 1.27)
					(thickness 0.15)
				)
			)
		)
		(property "Author" "Antmicro"
			(at 307 -54.5 0)
			(layer "F.Fab")
			(hide yes)
			(effects
				(font
					(size 1 1)
					(thickness 0.15)
				)
			)
		)
		(property "Current" "1A"
			(at 307 -54.5 0)
			(layer "F.Fab")
			(hide yes)
			(effects
				(font
					(size 1 1)
					(thickness 0.15)
				)
			)
		)
		(property "License" "Apache-2.0"
			(at 307 -54.5 0)
			(layer "F.Fab")
			(hide yes)
			(effects
				(font
					(size 1 1)
					(thickness 0.15)
				)
			)
		)
		(property "MPN" "ERJ2GE0R00X"
			(at 307 -54.5 0)
			(layer "F.Fab")
			(hide yes)
			(effects
				(font
					(size 1 1)
					(thickness 0.15)
				)
			)
		)
		(property "Manufacturer" "Panasonic"
			(at 307 -54.5 0)
			(layer "F.Fab")
			(hide yes)
			(effects
				(font
					(size 1 1)
					(thickness 0.15)
				)
			)
		)
		(property "Public" "False"
			(at 307 -54.5 0)
			(layer "F.Fab")
			(hide yes)
			(effects
				(font
					(size 1 1)
					(thickness 0.15)
				)
			)
		)
		(property "Tolerance" ""
			(at 307 -54.5 0)
			(layer "F.Fab")
			(hide yes)
			(effects
				(font
					(size 1 1)
					(thickness 0.15)
				)
			)
		)
		(property "Val" "0R"
			(at 307 -54.5 0)
			(layer "F.Fab")
			(hide yes)
			(effects
				(font
					(size 1 1)
					(thickness 0.15)
				)
			)
		)
		(sheetfile "environment-sensor.kicad_sch")
		(attr smd)
		(fp_rect
			(start -0.925 -0.47)
			(end 0.925 0.47)
			(stroke
				(width 0.05)
				(type default)
			)
			(fill no)
			(layer "F.CrtYd")
		)
		(fp_rect
			(start -0.5 -0.25)
			(end 0.5 0.25)
			(stroke
				(width 0.15)
				(type solid)
			)
			(fill no)
			(layer "F.Fab")
		)
		(pad "1" smd roundrect
			(at -0.48 0 90)
			(size 0.59 0.64)
			(layers "F.Cu" "F.Mask" "F.Paste")
			(roundrect_rratio 0.25)
			(net 25 "JTDI")
			(pintype "passive")
		)
		(pad "2" smd roundrect
			(at 0.48 0 90)
			(size 0.59 0.64)
			(layers "F.Cu" "F.Mask" "F.Paste")
			(roundrect_rratio 0.25)
			(net 46 "Net-(U3-PA15)")
			(pintype "passive")
		)
	)
	(footprint "antmicro-footprints:R_0402_1005Metric"
		(layer "F.Cu")
		(at 175.55 137.3 180)
		(descr "Resistor SMD 0402")
		(tags "resistor SMD 0402")
		(property "Reference" "R17"
			(at -25.25 -1.4 180)
			(layer "F.SilkS")
			(effects
				(font
					(size 0.7 0.7)
					(thickness 0.15)
				)
				(justify left bottom)
			)
		)
		(property "Value" "R_470R_0402"
			(at 0 1.4 180)
			(layer "F.Fab")
			(effects
				(font
					(size 0.7 0.7)
					(thickness 0.15)
				)
				(justify left bottom)
			)
		)
		(property "Description" "SMD Chip Resistor, 470 ohm, ± 1%, 62.5 mW, 0402 [1005 Metric], Thick Film, General Purpose"
			(at 0 0 180)
			(layer "F.Fab")
			(hide yes)
			(effects
				(font
					(size 1.27 1.27)
					(thickness 0.15)
				)
			)
		)
		(property "Author" "Antmicro"
			(at 351.1 274.6 0)
			(layer "F.Fab")
			(hide yes)
			(effects
				(font
					(size 1 1)
					(thickness 0.15)
				)
			)
		)
		(property "License" "Apache-2.0"
			(at 351.1 274.6 0)
			(layer "F.Fab")
			(hide yes)
			(effects
				(font
					(size 1 1)
					(thickness 0.15)
				)
			)
		)
		(property "MPN" "CR0402-FX-4700GLF"
			(at 351.1 274.6 0)
			(layer "F.Fab")
			(hide yes)
			(effects
				(font
					(size 1 1)
					(thickness 0.15)
				)
			)
		)
		(property "Manufacturer" "Bourns"
			(at 351.1 274.6 0)
			(layer "F.Fab")
			(hide yes)
			(effects
				(font
					(size 1 1)
					(thickness 0.15)
				)
			)
		)
		(property "Public" "False"
			(at 351.1 274.6 0)
			(layer "F.Fab")
			(hide yes)
			(effects
				(font
					(size 1 1)
					(thickness 0.15)
				)
			)
		)
		(property "Tolerance" "1%"
			(at 351.1 274.6 0)
			(layer "F.Fab")
			(hide yes)
			(effects
				(font
					(size 1 1)
					(thickness 0.15)
				)
			)
		)
		(property "Val" "470R"
			(at 351.1 274.6 0)
			(layer "F.Fab")
			(hide yes)
			(effects
				(font
					(size 1 1)
					(thickness 0.15)
				)
			)
		)
		(sheetfile "environment-sensor.kicad_sch")
		(attr smd)
		(fp_rect
			(start -0.925 -0.47)
			(end 0.925 0.47)
			(stroke
				(width 0.05)
				(type default)
			)
			(fill no)
			(layer "F.CrtYd")
		)
		(fp_rect
			(start -0.5 -0.25)
			(end 0.5 0.25)
			(stroke
				(width 0.15)
				(type solid)
			)
			(fill no)
			(layer "F.Fab")
		)
		(pad "1" smd roundrect
			(at -0.48 0 180)
			(size 0.59 0.64)
			(layers "F.Cu" "F.Mask" "F.Paste")
			(roundrect_rratio 0.25)
			(net 1 "GND")
			(pintype "passive")
		)
		(pad "2" smd roundrect
			(at 0.48 0 180)
			(size 0.59 0.64)
			(layers "F.Cu" "F.Mask" "F.Paste")
			(roundrect_rratio 0.25)
			(net 11 "Net-(LD2-A)")
			(pintype "passive")
		)
	)
	(footprint "antmicro-footprints:R_0402_1005Metric"
		(layer "F.Cu")
		(at 176.246 123.678 90)
		(descr "Resistor SMD 0402")
		(tags "resistor SMD 0402")
		(property "Reference" "R2"
			(at -2.395 0.392 90)
			(layer "F.SilkS")
			(effects
				(font
					(size 0.7 0.7)
					(thickness 0.15)
				)
				(justify left bottom)
			)
		)
		(property "Value" "R_1k_0402"
			(at 0 1.4 90)
			(layer "F.Fab")
			(effects
				(font
					(size 0.7 0.7)
					(thickness 0.15)
				)
				(justify left bottom)
			)
		)
		(property "Description" "SMD Chip Resistor, 1 kohm, ± 1%, 63 mW, 0402 [1005 Metric], Thick Film, General Purpose"
			(at 0 0 90)
			(layer "F.Fab")
			(hide yes)
			(effects
				(font
					(size 1.27 1.27)
					(thickness 0.15)
				)
			)
		)
		(property "Author" "Antmicro"
			(at 299.924 -52.568 0)
			(layer "F.Fab")
			(hide yes)
			(effects
				(font
					(size 1 1)
					(thickness 0.15)
				)
			)
		)
		(property "License" "Apache-2.0"
			(at 299.924 -52.568 0)
			(layer "F.Fab")
			(hide yes)
			(effects
				(font
					(size 1 1)
					(thickness 0.15)
				)
			)
		)
		(property "MPN" "CR0402-FX-1001GLF"
			(at 299.924 -52.568 0)
			(layer "F.Fab")
			(hide yes)
			(effects
				(font
					(size 1 1)
					(thickness 0.15)
				)
			)
		)
		(property "Manufacturer" "Bourns"
			(at 299.924 -52.568 0)
			(layer "F.Fab")
			(hide yes)
			(effects
				(font
					(size 1 1)
					(thickness 0.15)
				)
			)
		)
		(property "Public" "False"
			(at 299.924 -52.568 0)
			(layer "F.Fab")
			(hide yes)
			(effects
				(font
					(size 1 1)
					(thickness 0.15)
				)
			)
		)
		(property "Tolerance" "1%"
			(at 299.924 -52.568 0)
			(layer "F.Fab")
			(hide yes)
			(effects
				(font
					(size 1 1)
					(thickness 0.15)
				)
			)
		)
		(property "Val" "1k"
			(at 299.924 -52.568 0)
			(layer "F.Fab")
			(hide yes)
			(effects
				(font
					(size 1 1)
					(thickness 0.15)
				)
			)
		)
		(sheetfile "environment-sensor.kicad_sch")
		(attr smd)
		(fp_rect
			(start -0.925 -0.47)
			(end 0.925 0.47)
			(stroke
				(width 0.05)
				(type default)
			)
			(fill no)
			(layer "F.CrtYd")
		)
		(fp_rect
			(start -0.5 -0.25)
			(end 0.5 0.25)
			(stroke
				(width 0.15)
				(type solid)
			)
			(fill no)
			(layer "F.Fab")
		)
		(pad "1" smd roundrect
			(at -0.48 0 90)
			(size 0.59 0.64)
			(layers "F.Cu" "F.Mask" "F.Paste")
			(roundrect_rratio 0.25)
			(net 26 "+5V")
			(pintype "passive")
		)
		(pad "2" smd roundrect
			(at 0.48 0 90)
			(size 0.59 0.64)
			(layers "F.Cu" "F.Mask" "F.Paste")
			(roundrect_rratio 0.25)
			(net 36 "Net-(U1-RESET#)")
			(pintype "passive")
		)
	)
	(footprint "antmicro-footprints:Conn_JST_SH_1x4_SM04B-SRSS-TB-LF-SN"
		(layer "F.Cu")
		(at 207.2755 129.25 90)
		(property "Reference" "J2"
			(at 2.15 -2.3255 90)
			(layer "F.SilkS")
			(effects
				(font
					(size 0.7 0.7)
					(thickness 0.15)
				)
				(justify left bottom)
			)
		)
		(property "Value" "JST_SH_1x4_SM04B-SRSS-TB-LF-SN"
			(at 0 3.9 90)
			(layer "F.Fab")
			(effects
				(font
					(size 0.7 0.7)
					(thickness 0.15)
				)
				(justify left bottom)
			)
		)
		(property "Description" "Pin Header, Right Angle, Wire-to-Board, 1 mm, 1 Rows, 4 Contacts, Surface Mount Right Angle, SH"
			(at 0 0 90)
			(layer "F.Fab")
			(hide yes)
			(effects
				(font
					(size 1.27 1.27)
					(thickness 0.15)
				)
			)
		)
		(property "Author" "Antmicro"
			(at 336.5255 -78.0255 0)
			(layer "F.Fab")
			(hide yes)
			(effects
				(font
					(size 1 1)
					(thickness 0.15)
				)
			)
		)
		(property "License" "Apache-2.0"
			(at 336.5255 -78.0255 0)
			(layer "F.Fab")
			(hide yes)
			(effects
				(font
					(size 1 1)
					(thickness 0.15)
				)
			)
		)
		(property "MPN" "SM04B-SRSS-TB(LF)(SN)"
			(at 336.5255 -78.0255 0)
			(layer "F.Fab")
			(hide yes)
			(effects
				(font
					(size 1 1)
					(thickness 0.15)
				)
			)
		)
		(property "Manufacturer" "JST Automotive Connectors"
			(at 336.5255 -78.0255 0)
			(layer "F.Fab")
			(hide yes)
			(effects
				(font
					(size 1 1)
					(thickness 0.15)
				)
			)
		)
		(sheetfile "environment-sensor.kicad_sch")
		(attr smd)
		(fp_line
			(start 3.2 -2)
			(end 3.2 0.6)
			(stroke
				(width 0.15)
				(type solid)
			)
			(layer "F.SilkS")
		)
		(fp_line
			(start 2 -2)
			(end 3.2 -2)
			(stroke
				(width 0.15)
				(type solid)
			)
			(layer "F.SilkS")
		)
		(fp_line
			(start -2 -2)
			(end -3.2 -2)
			(stroke
				(width 0.15)
				(type solid)
			)
			(layer "F.SilkS")
		)
		(fp_line
			(start -3.2 -2)
			(end -3.2 0.6)
			(stroke
				(width 0.15)
				(type solid)
			)
			(layer "F.SilkS")
		)
		(fp_line
			(start -2 2.6)
			(end 2 2.6)
			(stroke
				(width 0.15)
				(type solid)
			)
			(layer "F.SilkS")
		)
		(fp_circle
			(center -2.1 -2.5)
			(end -2.05 -2.5)
			(stroke
				(width 0.15)
				(type solid)
			)
			(fill yes)
			(layer "F.SilkS")
		)
		(fp_rect
			(start -3.65 -3.14)
			(end 3.65 2.9)
			(stroke
				(width 0.05)
				(type solid)
			)
			(fill no)
			(layer "F.CrtYd")
		)
		(fp_rect
			(start -3 -2.475)
			(end 3 2.475)
			(stroke
				(width 0.15)
				(type solid)
			)
			(fill no)
			(layer "F.Fab")
		)
		(pad "1" smd roundrect
			(at -1.5 -2.12 270)
			(size 0.6 1.55)
			(layers "F.Cu" "F.Mask" "F.Paste")
			(roundrect_rratio 0.25)
			(net 1 "GND")
			(pintype "passive")
		)
		(pad "2" smd roundrect
			(at -0.5 -2.12 270)
			(size 0.6 1.55)
			(layers "F.Cu" "F.Mask" "F.Paste")
			(roundrect_rratio 0.25)
			(net 2 "+3V3")
			(pintype "passive")
		)
		(pad "3" smd roundrect
			(at 0.5 -2.12 270)
			(size 0.6 1.55)
			(layers "F.Cu" "F.Mask" "F.Paste")
			(roundrect_rratio 0.25)
			(net 9 "I2C_1_SDA")
			(pintype "passive")
		)
		(pad "4" smd roundrect
			(at 1.5 -2.12 270)
			(size 0.6 1.55)
			(layers "F.Cu" "F.Mask" "F.Paste")
			(roundrect_rratio 0.25)
			(net 8 "I2C_1_SCL")
			(pintype "passive")
		)
		(pad "MP" smd roundrect
			(at -2.8 1.755 90)
			(size 1.2 1.8)
			(layers "F.Cu" "F.Mask" "F.Paste")
			(roundrect_rratio 0.25)
			(net 88 "unconnected-(J2-PadMP)")
			(pintype "passive+no_connect")
		)
		(pad "MP" smd roundrect
			(at 2.8 1.755 90)
			(size 1.2 1.8)
			(layers "F.Cu" "F.Mask" "F.Paste")
			(roundrect_rratio 0.25)
			(net 88 "unconnected-(J2-PadMP)")
			(pintype "passive+no_connect")
		)
	)
	(footprint "antmicro-footprints:C_0402_1005Metric"
		(layer "F.Cu")
		(at 190.3 138.415 -90)
		(descr "Capacitor SMD 0402")
		(tags "capacitor SMD 0402")
		(property "Reference" "C24"
			(at -15.769 8.2 90)
			(layer "B.SilkS")
			(effects
				(font
					(size 0.7 0.7)
					(thickness 0.15)
				)
				(justify right bottom mirror)
			)
		)
		(property "Value" "C_2u2_0402"
			(at 0 1.4 90)
			(layer "F.Fab")
			(effects
				(font
					(size 0.7 0.7)
					(thickness 0.15)
				)
				(justify right bottom)
			)
		)
		(property "Description" "SMD Multilayer Ceramic Capacitor, 2.2 µF, 10 V, 0402 [1005 Metric], ± 10%, X5R, C"
			(at 0 0 270)
			(layer "F.Fab")
			(hide yes)
			(effects
				(font
					(size 1.27 1.27)
					(thickness 0.15)
				)
			)
		)
		(property "Author" "Antmicro"
			(at 51.885 328.715 0)
			(layer "F.Fab")
			(hide yes)
			(effects
				(font
					(size 1 1)
					(thickness 0.15)
				)
			)
		)
		(property "Dielectric" ""
			(at 51.885 328.715 0)
			(layer "F.Fab")
			(hide yes)
			(effects
				(font
					(size 1 1)
					(thickness 0.15)
				)
			)
		)
		(property "License" "Apache-2.0"
			(at 51.885 328.715 0)
			(layer "F.Fab")
			(hide yes)
			(effects
				(font
					(size 1 1)
					(thickness 0.15)
				)
			)
		)
		(property "MPN" "C1005X5R1A225K050BC"
			(at 51.885 328.715 0)
			(layer "F.Fab")
			(hide yes)
			(effects
				(font
					(size 1 1)
					(thickness 0.15)
				)
			)
		)
		(property "Manufacturer" "TDK"
			(at 51.885 328.715 0)
			(layer "F.Fab")
			(hide yes)
			(effects
				(font
					(size 1 1)
					(thickness 0.15)
				)
			)
		)
		(property "Public" "False"
			(at 51.885 328.715 0)
			(layer "F.Fab")
			(hide yes)
			(effects
				(font
					(size 1 1)
					(thickness 0.15)
				)
			)
		)
		(property "Val" "2u2"
			(at 51.885 328.715 0)
			(layer "F.Fab")
			(hide yes)
			(effects
				(font
					(size 1 1)
					(thickness 0.15)
				)
			)
		)
		(property "Voltage" ""
			(at 51.885 328.715 0)
			(layer "F.Fab")
			(hide yes)
			(effects
				(font
					(size 1 1)
					(thickness 0.15)
				)
			)
		)
		(sheetfile "environment-sensor.kicad_sch")
		(attr smd)
		(fp_rect
			(start -0.925 -0.47)
			(end 0.925 0.47)
			(stroke
				(width 0.05)
				(type default)
			)
			(fill no)
			(layer "F.CrtYd")
		)
		(fp_line
			(start -0.494 0.248)
			(end -0.494 -0.25)
			(stroke
				(width 0.15)
				(type solid)
			)
			(layer "F.Fab")
		)
		(fp_line
			(start 0.504 0.248)
			(end -0.494 0.248)
			(stroke
				(width 0.15)
				(type solid)
			)
			(layer "F.Fab")
		)
		(fp_line
			(start -0.494 -0.25)
			(end 0.504 -0.25)
			(stroke
				(width 0.15)
				(type solid)
			)
			(layer "F.Fab")
		)
		(fp_line
			(start 0.504 -0.25)
			(end 0.504 0.248)
			(stroke
				(width 0.15)
				(type solid)
			)
			(layer "F.Fab")
		)
		(pad "1" smd roundrect
			(at -0.48 0 270)
			(size 0.59 0.64)
			(layers "F.Cu" "F.Mask" "F.Paste")
			(roundrect_rratio 0.25)
			(net 1 "GND")
			(pintype "passive")
		)
		(pad "2" smd roundrect
			(at 0.48 0 270)
			(size 0.59 0.64)
			(layers "F.Cu" "F.Mask" "F.Paste")
			(roundrect_rratio 0.25)
			(net 32 "Net-(U3-VREF+)")
			(pintype "passive")
		)
	)
	(footprint "antmicro-footprints:MP_Pad5.4mm_Drill2.7mm"
		(layer "F.Cu")
		(at 163.7 136.3)
		(descr "Mounting Hole 2.7mm, M2.5")
		(tags "mounting hole 2.7mm m2.5")
		(property "Reference" "MP2"
			(at -3.55 3.45 0)
			(layer "F.SilkS")
			(effects
				(font
					(size 0.7 0.7)
					(thickness 0.15)
				)
				(justify left bottom)
			)
		)
		(property "Value" "MP_Pad5.4mm_Drill2.7mm"
			(at 0 3.6 0)
			(layer "F.Fab")
			(effects
				(font
					(size 0.7 0.7)
					(thickness 0.15)
				)
				(justify left bottom)
			)
		)
		(property "Description" "Mechanical part"
			(at 0 0 0)
			(layer "F.Fab")
			(hide yes)
			(effects
				(font
					(size 1.27 1.27)
					(thickness 0.15)
				)
			)
		)
		(property "Author" "Antmicro"
			(at 0 0 0)
			(layer "F.Fab")
			(hide yes)
			(effects
				(font
					(size 1 1)
					(thickness 0.15)
				)
			)
		)
		(property "License" "Apache-2.0"
			(at 0 0 0)
			(layer "F.Fab")
			(hide yes)
			(effects
				(font
					(size 1 1)
					(thickness 0.15)
				)
			)
		)
		(property "Public" "False"
			(at 0 0 0)
			(layer "F.Fab")
			(hide yes)
			(effects
				(font
					(size 1 1)
					(thickness 0.15)
				)
			)
		)
		(sheetfile "environment-sensor.kicad_sch")
		(attr exclude_from_pos_files exclude_from_bom)
		(pad "1" thru_hole circle
			(at 0 0)
			(size 5.4 5.4)
			(drill 2.7)
			(layers "*.Cu" "*.Mask")
			(remove_unused_layers no)
			(net 23 "unconnected-(MP2-Pad1)")
			(pintype "passive+no_connect")
		)
	)
	(footprint "antmicro-footprints:C_0402_1005Metric"
		(layer "F.Cu")
		(at 189.754 117.597)
		(descr "Capacitor SMD 0402")
		(tags "capacitor SMD 0402")
		(property "Reference" "C18"
			(at 1.013 0.303 0)
			(layer "F.SilkS")
			(effects
				(font
					(size 0.7 0.7)
					(thickness 0.15)
				)
				(justify left bottom)
			)
		)
		(property "Value" "C_100n_0402"
			(at 0 1.4 0)
			(layer "F.Fab")
			(effects
				(font
					(size 0.7 0.7)
					(thickness 0.15)
				)
				(justify left bottom)
			)
		)
		(property "Description" "SMD Multilayer Ceramic Capacitor, 0.1 µF, 50 V, 0402 [1005 Metric], ± 10%, X5R, GRM Series"
			(at 0 0 0)
			(layer "F.Fab")
			(hide yes)
			(effects
				(font
					(size 1.27 1.27)
					(thickness 0.15)
				)
			)
		)
		(property "Author" "Antmicro"
			(at 0 0 0)
			(layer "F.Fab")
			(hide yes)
			(effects
				(font
					(size 1 1)
					(thickness 0.15)
				)
			)
		)
		(property "Dielectric" "X5R"
			(at 0 0 0)
			(layer "F.Fab")
			(hide yes)
			(effects
				(font
					(size 1 1)
					(thickness 0.15)
				)
			)
		)
		(property "License" "Apache-2.0"
			(at 0 0 0)
			(layer "F.Fab")
			(hide yes)
			(effects
				(font
					(size 1 1)
					(thickness 0.15)
				)
			)
		)
		(property "MPN" "GRM155R61H104KE14D"
			(at 0 0 0)
			(layer "F.Fab")
			(hide yes)
			(effects
				(font
					(size 1 1)
					(thickness 0.15)
				)
			)
		)
		(property "Manufacturer" "Murata"
			(at 0 0 0)
			(layer "F.Fab")
			(hide yes)
			(effects
				(font
					(size 1 1)
					(thickness 0.15)
				)
			)
		)
		(property "Public" "False"
			(at 0 0 0)
			(layer "F.Fab")
			(hide yes)
			(effects
				(font
					(size 1 1)
					(thickness 0.15)
				)
			)
		)
		(property "Val" "100n"
			(at 0 0 0)
			(layer "F.Fab")
			(hide yes)
			(effects
				(font
					(size 1 1)
					(thickness 0.15)
				)
			)
		)
		(property "Voltage" "50V"
			(at 0 0 0)
			(layer "F.Fab")
			(hide yes)
			(effects
				(font
					(size 1 1)
					(thickness 0.15)
				)
			)
		)
		(sheetfile "environment-sensor.kicad_sch")
		(attr smd)
		(fp_rect
			(start -0.925 -0.47)
			(end 0.925 0.47)
			(stroke
				(width 0.05)
				(type default)
			)
			(fill no)
			(layer "F.CrtYd")
		)
		(fp_line
			(start -0.494 -0.25)
			(end 0.504 -0.25)
			(stroke
				(width 0.15)
				(type solid)
			)
			(layer "F.Fab")
		)
		(fp_line
			(start -0.494 0.248)
			(end -0.494 -0.25)
			(stroke
				(width 0.15)
				(type solid)
			)
			(layer "F.Fab")
		)
		(fp_line
			(start 0.504 -0.25)
			(end 0.504 0.248)
			(stroke
				(width 0.15)
				(type solid)
			)
			(layer "F.Fab")
		)
		(fp_line
			(start 0.504 0.248)
			(end -0.494 0.248)
			(stroke
				(width 0.15)
				(type solid)
			)
			(layer "F.Fab")
		)
		(pad "1" smd roundrect
			(at -0.48 0)
			(size 0.59 0.64)
			(layers "F.Cu" "F.Mask" "F.Paste")
			(roundrect_rratio 0.25)
			(net 1 "GND")
			(pintype "passive")
		)
		(pad "2" smd roundrect
			(at 0.48 0)
			(size 0.59 0.64)
			(layers "F.Cu" "F.Mask" "F.Paste")
			(roundrect_rratio 0.25)
			(net 2 "+3V3")
			(pintype "passive")
		)
	)
	(footprint "antmicro-footprints:TP_SMD_1mm"
		(layer "F.Cu")
		(at 199 134.75)
		(property "Reference" "TP11"
			(at -3.25 -0.05 0)
			(layer "F.SilkS")
			(hide yes)
			(effects
				(font
					(size 0.7 0.7)
					(thickness 0.15)
				)
				(justify left bottom)
			)
		)
		(property "Value" "TP_1mm_SMD"
			(at 0 1.4 0)
			(layer "F.Fab")
			(effects
				(font
					(size 0.7 0.7)
					(thickness 0.15)
				)
				(justify left bottom)
			)
		)
		(property "Description" "Test point 1mm SMD"
			(at 0 0 0)
			(layer "F.Fab")
			(hide yes)
			(effects
				(font
					(size 1.27 1.27)
					(thickness 0.15)
				)
			)
		)
		(property "Author" "Antmicro"
			(at 0 0 0)
			(layer "F.Fab")
			(hide yes)
			(effects
				(font
					(size 1 1)
					(thickness 0.15)
				)
			)
		)
		(property "License" "Apache-2.0"
			(at 0 0 0)
			(layer "F.Fab")
			(hide yes)
			(effects
				(font
					(size 1 1)
					(thickness 0.15)
				)
			)
		)
		(property "MPN" ""
			(at 0 0 0)
			(layer "F.Fab")
			(hide yes)
			(effects
				(font
					(size 1 1)
					(thickness 0.15)
				)
			)
		)
		(property "Manufacturer" ""
			(at 0 0 0)
			(layer "F.Fab")
			(hide yes)
			(effects
				(font
					(size 1 1)
					(thickness 0.15)
				)
			)
		)
		(property "Public" "False"
			(at 0 0 0)
			(layer "F.Fab")
			(hide yes)
			(effects
				(font
					(size 1 1)
					(thickness 0.15)
				)
			)
		)
		(sheetfile "environment-sensor.kicad_sch")
		(attr exclude_from_pos_files)
		(pad "1" smd circle
			(at 0 0)
			(size 1 1)
			(layers "F.Cu" "F.Mask")
			(net 9 "I2C_1_SDA")
			(pinfunction "1")
			(pintype "passive")
		)
	)
	(footprint "antmicro-footprints:R_0402_1005Metric"
		(layer "F.Cu")
		(at 175.55 136.15 180)
		(descr "Resistor SMD 0402")
		(tags "resistor SMD 0402")
		(property "Reference" "R12"
			(at -25.25 -1.65 180)
			(layer "F.SilkS")
			(effects
				(font
					(size 0.7 0.7)
					(thickness 0.15)
				)
				(justify left bottom)
			)
		)
		(property "Value" "R_470R_0402"
			(at 0 1.4 180)
			(layer "F.Fab")
			(effects
				(font
					(size 0.7 0.7)
					(thickness 0.15)
				)
				(justify left bottom)
			)
		)
		(property "Description" "SMD Chip Resistor, 470 ohm, ± 1%, 62.5 mW, 0402 [1005 Metric], Thick Film, General Purpose"
			(at 0 0 180)
			(layer "F.Fab")
			(hide yes)
			(effects
				(font
					(size 1.27 1.27)
					(thickness 0.15)
				)
			)
		)
		(property "Author" "Antmicro"
			(at 351.1 272.3 0)
			(layer "F.Fab")
			(hide yes)
			(effects
				(font
					(size 1 1)
					(thickness 0.15)
				)
			)
		)
		(property "License" "Apache-2.0"
			(at 351.1 272.3 0)
			(layer "F.Fab")
			(hide yes)
			(effects
				(font
					(size 1 1)
					(thickness 0.15)
				)
			)
		)
		(property "MPN" "CR0402-FX-4700GLF"
			(at 351.1 272.3 0)
			(layer "F.Fab")
			(hide yes)
			(effects
				(font
					(size 1 1)
					(thickness 0.15)
				)
			)
		)
		(property "Manufacturer" "Bourns"
			(at 351.1 272.3 0)
			(layer "F.Fab")
			(hide yes)
			(effects
				(font
					(size 1 1)
					(thickness 0.15)
				)
			)
		)
		(property "Public" "False"
			(at 351.1 272.3 0)
			(layer "F.Fab")
			(hide yes)
			(effects
				(font
					(size 1 1)
					(thickness 0.15)
				)
			)
		)
		(property "Tolerance" "1%"
			(at 351.1 272.3 0)
			(layer "F.Fab")
			(hide yes)
			(effects
				(font
					(size 1 1)
					(thickness 0.15)
				)
			)
		)
		(property "Val" "470R"
			(at 351.1 272.3 0)
			(layer "F.Fab")
			(hide yes)
			(effects
				(font
					(size 1 1)
					(thickness 0.15)
				)
			)
		)
		(sheetfile "environment-sensor.kicad_sch")
		(attr smd)
		(fp_rect
			(start -0.925 -0.47)
			(end 0.925 0.47)
			(stroke
				(width 0.05)
				(type default)
			)
			(fill no)
			(layer "F.CrtYd")
		)
		(fp_rect
			(start -0.5 -0.25)
			(end 0.5 0.25)
			(stroke
				(width 0.15)
				(type solid)
			)
			(fill no)
			(layer "F.Fab")
		)
		(pad "1" smd roundrect
			(at -0.48 0 180)
			(size 0.59 0.64)
			(layers "F.Cu" "F.Mask" "F.Paste")
			(roundrect_rratio 0.25)
			(net 1 "GND")
			(pintype "passive")
		)
		(pad "2" smd roundrect
			(at 0.48 0 180)
			(size 0.59 0.64)
			(layers "F.Cu" "F.Mask" "F.Paste")
			(roundrect_rratio 0.25)
			(net 10 "Net-(LD1-A)")
			(pintype "passive")
		)
	)
	(footprint "antmicro-footprints:R_0402_1005Metric"
		(layer "F.Cu")
		(at 182.75 126.25 -90)
		(descr "Resistor SMD 0402")
		(tags "resistor SMD 0402")
		(property "Reference" "R5"
			(at -11.75 -1.05 90)
			(layer "B.SilkS")
			(effects
				(font
					(size 0.7 0.7)
					(thickness 0.15)
				)
				(justify left bottom mirror)
			)
		)
		(property "Value" "R_0R_0402"
			(at 0 1.4 90)
			(layer "F.Fab")
			(effects
				(font
					(size 0.7 0.7)
					(thickness 0.15)
				)
				(justify right bottom)
			)
		)
		(property "Description" "SMD Chip Resistor, Jumper, 0 ohm, 100 mW, 0402 [1005 Metric], Thick Film, General Purpose"
			(at 0 0 270)
			(layer "F.Fab")
			(hide yes)
			(effects
				(font
					(size 1.27 1.27)
					(thickness 0.15)
				)
			)
		)
		(property "Author" "Antmicro"
			(at 56.5 309 0)
			(layer "F.Fab")
			(hide yes)
			(effects
				(font
					(size 1 1)
					(thickness 0.15)
				)
			)
		)
		(property "Current" "1A"
			(at 56.5 309 0)
			(layer "F.Fab")
			(hide yes)
			(effects
				(font
					(size 1 1)
					(thickness 0.15)
				)
			)
		)
		(property "License" "Apache-2.0"
			(at 56.5 309 0)
			(layer "F.Fab")
			(hide yes)
			(effects
				(font
					(size 1 1)
					(thickness 0.15)
				)
			)
		)
		(property "MPN" "ERJ2GE0R00X"
			(at 56.5 309 0)
			(layer "F.Fab")
			(hide yes)
			(effects
				(font
					(size 1 1)
					(thickness 0.15)
				)
			)
		)
		(property "Manufacturer" "Panasonic"
			(at 56.5 309 0)
			(layer "F.Fab")
			(hide yes)
			(effects
				(font
					(size 1 1)
					(thickness 0.15)
				)
			)
		)
		(property "Public" "False"
			(at 56.5 309 0)
			(layer "F.Fab")
			(hide yes)
			(effects
				(font
					(size 1 1)
					(thickness 0.15)
				)
			)
		)
		(property "Tolerance" ""
			(at 56.5 309 0)
			(layer "F.Fab")
			(hide yes)
			(effects
				(font
					(size 1 1)
					(thickness 0.15)
				)
			)
		)
		(property "Val" "0R"
			(at 56.5 309 0)
			(layer "F.Fab")
			(hide yes)
			(effects
				(font
					(size 1 1)
					(thickness 0.15)
				)
			)
		)
		(sheetfile "environment-sensor.kicad_sch")
		(attr smd)
		(fp_rect
			(start -0.925 -0.47)
			(end 0.925 0.47)
			(stroke
				(width 0.05)
				(type default)
			)
			(fill no)
			(layer "F.CrtYd")
		)
		(fp_rect
			(start -0.5 -0.25)
			(end 0.5 0.25)
			(stroke
				(width 0.15)
				(type solid)
			)
			(fill no)
			(layer "F.Fab")
		)
		(pad "1" smd roundrect
			(at -0.48 0 270)
			(size 0.59 0.64)
			(layers "F.Cu" "F.Mask" "F.Paste")
			(roundrect_rratio 0.25)
			(net 37 "Net-(U1-DTR#)")
			(pintype "passive")
		)
		(pad "2" smd roundrect
			(at 0.48 0 270)
			(size 0.59 0.64)
			(layers "F.Cu" "F.Mask" "F.Paste")
			(roundrect_rratio 0.25)
			(net 20 "SWDIO-JTMS")
			(pintype "passive")
		)
	)
	(footprint "antmicro-footprints:R_0402_1005Metric"
		(layer "F.Cu")
		(at 185.15 138.4 90)
		(descr "Resistor SMD 0402")
		(tags "resistor SMD 0402")
		(property "Reference" "R14"
			(at 20.346 -1.2685 270)
			(layer "B.SilkS")
			(effects
				(font
					(size 0.7 0.7)
					(thickness 0.15)
				)
				(justify left bottom mirror)
			)
		)
		(property "Value" "R_0R_0402"
			(at 0 1.4 90)
			(layer "F.Fab")
			(effects
				(font
					(size 0.7 0.7)
					(thickness 0.15)
				)
				(justify left bottom)
			)
		)
		(property "Description" "SMD Chip Resistor, Jumper, 0 ohm, 100 mW, 0402 [1005 Metric], Thick Film, General Purpose"
			(at 0 0 90)
			(layer "F.Fab")
			(hide yes)
			(effects
				(font
					(size 1.27 1.27)
					(thickness 0.15)
				)
			)
		)
		(property "Author" "Antmicro"
			(at 323.55 -46.75 0)
			(layer "F.Fab")
			(hide yes)
			(effects
				(font
					(size 1 1)
					(thickness 0.15)
				)
			)
		)
		(property "Current" "1A"
			(at 323.55 -46.75 0)
			(layer "F.Fab")
			(hide yes)
			(effects
				(font
					(size 1 1)
					(thickness 0.15)
				)
			)
		)
		(property "License" "Apache-2.0"
			(at 323.55 -46.75 0)
			(layer "F.Fab")
			(hide yes)
			(effects
				(font
					(size 1 1)
					(thickness 0.15)
				)
			)
		)
		(property "MPN" "ERJ2GE0R00X"
			(at 323.55 -46.75 0)
			(layer "F.Fab")
			(hide yes)
			(effects
				(font
					(size 1 1)
					(thickness 0.15)
				)
			)
		)
		(property "Manufacturer" "Panasonic"
			(at 323.55 -46.75 0)
			(layer "F.Fab")
			(hide yes)
			(effects
				(font
					(size 1 1)
					(thickness 0.15)
				)
			)
		)
		(property "Public" "False"
			(at 323.55 -46.75 0)
			(layer "F.Fab")
			(hide yes)
			(effects
				(font
					(size 1 1)
					(thickness 0.15)
				)
			)
		)
		(property "Tolerance" ""
			(at 323.55 -46.75 0)
			(layer "F.Fab")
			(hide yes)
			(effects
				(font
					(size 1 1)
					(thickness 0.15)
				)
			)
		)
		(property "Val" "0R"
			(at 323.55 -46.75 0)
			(layer "F.Fab")
			(hide yes)
			(effects
				(font
					(size 1 1)
					(thickness 0.15)
				)
			)
		)
		(sheetfile "environment-sensor.kicad_sch")
		(attr smd)
		(fp_rect
			(start -0.925 -0.47)
			(end 0.925 0.47)
			(stroke
				(width 0.05)
				(type default)
			)
			(fill no)
			(layer "F.CrtYd")
		)
		(fp_rect
			(start -0.5 -0.25)
			(end 0.5 0.25)
			(stroke
				(width 0.15)
				(type solid)
			)
			(fill no)
			(layer "F.Fab")
		)
		(pad "1" smd roundrect
			(at -0.48 0 90)
			(size 0.59 0.64)
			(layers "F.Cu" "F.Mask" "F.Paste")
			(roundrect_rratio 0.25)
			(net 45 "Net-(U1-RXD)")
			(pintype "passive")
		)
		(pad "2" smd roundrect
			(at 0.48 0 90)
			(size 0.59 0.64)
			(layers "F.Cu" "F.Mask" "F.Paste")
			(roundrect_rratio 0.25)
			(net 17 "LPUART_1_STM_TX")
			(pintype "passive")
		)
	)
	(footprint "antmicro-footprints:C_0402_1005Metric"
		(layer "F.Cu")
		(at 187.094 125.087 90)
		(descr "Capacitor SMD 0402")
		(tags "capacitor SMD 0402")
		(property "Reference" "C11"
			(at 6.887 8.006 180)
			(layer "F.SilkS")
			(effects
				(font
					(size 0.7 0.7)
					(thickness 0.15)
				)
				(justify left bottom)
			)
		)
		(property "Value" "C_2u2_0402"
			(at 0 1.4 90)
			(layer "F.Fab")
			(effects
				(font
					(size 0.7 0.7)
					(thickness 0.15)
				)
				(justify left bottom)
			)
		)
		(property "Description" "SMD Multilayer Ceramic Capacitor, 2.2 µF, 10 V, 0402 [1005 Metric], ± 10%, X5R, C"
			(at 0 0 90)
			(layer "F.Fab")
			(hide yes)
			(effects
				(font
					(size 1.27 1.27)
					(thickness 0.15)
				)
			)
		)
		(property "Author" "Antmicro"
			(at 312.181 -62.007 0)
			(layer "F.Fab")
			(hide yes)
			(effects
				(font
					(size 1 1)
					(thickness 0.15)
				)
			)
		)
		(property "Dielectric" ""
			(at 312.181 -62.007 0)
			(layer "F.Fab")
			(hide yes)
			(effects
				(font
					(size 1 1)
					(thickness 0.15)
				)
			)
		)
		(property "License" "Apache-2.0"
			(at 312.181 -62.007 0)
			(layer "F.Fab")
			(hide yes)
			(effects
				(font
					(size 1 1)
					(thickness 0.15)
				)
			)
		)
		(property "MPN" "C1005X5R1A225K050BC"
			(at 312.181 -62.007 0)
			(layer "F.Fab")
			(hide yes)
			(effects
				(font
					(size 1 1)
					(thickness 0.15)
				)
			)
		)
		(property "Manufacturer" "TDK"
			(at 312.181 -62.007 0)
			(layer "F.Fab")
			(hide yes)
			(effects
				(font
					(size 1 1)
					(thickness 0.15)
				)
			)
		)
		(property "Public" "False"
			(at 312.181 -62.007 0)
			(layer "F.Fab")
			(hide yes)
			(effects
				(font
					(size 1 1)
					(thickness 0.15)
				)
			)
		)
		(property "Val" "2u2"
			(at 312.181 -62.007 0)
			(layer "F.Fab")
			(hide yes)
			(effects
				(font
					(size 1 1)
					(thickness 0.15)
				)
			)
		)
		(property "Voltage" ""
			(at 312.181 -62.007 0)
			(layer "F.Fab")
			(hide yes)
			(effects
				(font
					(size 1 1)
					(thickness 0.15)
				)
			)
		)
		(sheetfile "environment-sensor.kicad_sch")
		(attr smd)
		(fp_rect
			(start -0.925 -0.47)
			(end 0.925 0.47)
			(stroke
				(width 0.05)
				(type default)
			)
			(fill no)
			(layer "F.CrtYd")
		)
		(fp_line
			(start 0.504 -0.25)
			(end 0.504 0.248)
			(stroke
				(width 0.15)
				(type solid)
			)
			(layer "F.Fab")
		)
		(fp_line
			(start -0.494 -0.25)
			(end 0.504 -0.25)
			(stroke
				(width 0.15)
				(type solid)
			)
			(layer "F.Fab")
		)
		(fp_line
			(start 0.504 0.248)
			(end -0.494 0.248)
			(stroke
				(width 0.15)
				(type solid)
			)
			(layer "F.Fab")
		)
		(fp_line
			(start -0.494 0.248)
			(end -0.494 -0.25)
			(stroke
				(width 0.15)
				(type solid)
			)
			(layer "F.Fab")
		)
		(pad "1" smd roundrect
			(at -0.48 0 90)
			(size 0.59 0.64)
			(layers "F.Cu" "F.Mask" "F.Paste")
			(roundrect_rratio 0.25)
			(net 2 "+3V3")
			(pintype "passive")
		)
		(pad "2" smd roundrect
			(at 0.48 0 90)
			(size 0.59 0.64)
			(layers "F.Cu" "F.Mask" "F.Paste")
			(roundrect_rratio 0.25)
			(net 1 "GND")
			(pintype "passive")
		)
	)
	(footprint "antmicro-footprints:C_0402_1005Metric"
		(layer "F.Cu")
		(at 182.91 132.6 180)
		(descr "Capacitor SMD 0402")
		(tags "capacitor SMD 0402")
		(property "Reference" "C16"
			(at -3.04 -0.45 0)
			(layer "F.SilkS")
			(effects
				(font
					(size 0.7 0.7)
					(thickness 0.15)
				)
				(justify right bottom)
			)
		)
		(property "Value" "C_16p_0402"
			(at -1.022927 2.155213 0)
			(layer "F.Fab")
			(effects
				(font
					(size 0.7 0.7)
					(thickness 0.15)
				)
				(justify right bottom)
			)
		)
		(property "Description" "SMD Multilayer Ceramic Capacitor, General Purpose, 16 pF, 50 V, 0402 [1005 Metric], ± 5%, C0G / NP0"
			(at 0 0 180)
			(layer "F.Fab")
			(hide yes)
			(effects
				(font
					(size 1.27 1.27)
					(thickness 0.15)
				)
			)
		)
		(property "Author" "Antmicro"
			(at 365.82 265.2 0)
			(layer "F.Fab")
			(hide yes)
			(effects
				(font
					(size 1 1)
					(thickness 0.15)
				)
			)
		)
		(property "Dielectric" ""
			(at 365.82 265.2 0)
			(layer "F.Fab")
			(hide yes)
			(effects
				(font
					(size 1 1)
					(thickness 0.15)
				)
			)
		)
		(property "License" "Apache-2.0"
			(at 365.82 265.2 0)
			(layer "F.Fab")
			(hide yes)
			(effects
				(font
					(size 1 1)
					(thickness 0.15)
				)
			)
		)
		(property "MPN" "0402N160J500CT"
			(at 365.82 265.2 0)
			(layer "F.Fab")
			(hide yes)
			(effects
				(font
					(size 1 1)
					(thickness 0.15)
				)
			)
		)
		(property "Manufacturer" "Walsin"
			(at 365.82 265.2 0)
			(layer "F.Fab")
			(hide yes)
			(effects
				(font
					(size 1 1)
					(thickness 0.15)
				)
			)
		)
		(property "Public" "False"
			(at 365.82 265.2 0)
			(layer "F.Fab")
			(hide yes)
			(effects
				(font
					(size 1 1)
					(thickness 0.15)
				)
			)
		)
		(property "Val" "16p"
			(at 365.82 265.2 0)
			(layer "F.Fab")
			(hide yes)
			(effects
				(font
					(size 1 1)
					(thickness 0.15)
				)
			)
		)
		(property "Voltage" ""
			(at 365.82 265.2 0)
			(layer "F.Fab")
			(hide yes)
			(effects
				(font
					(size 1 1)
					(thickness 0.15)
				)
			)
		)
		(sheetfile "environment-sensor.kicad_sch")
		(attr smd)
		(fp_rect
			(start -0.925 -0.47)
			(end 0.925 0.47)
			(stroke
				(width 0.05)
				(type default)
			)
			(fill no)
			(layer "F.CrtYd")
		)
		(fp_line
			(start 0.504 0.248)
			(end -0.494 0.248)
			(stroke
				(width 0.15)
				(type solid)
			)
			(layer "F.Fab")
		)
		(fp_line
			(start 0.504 -0.25)
			(end 0.504 0.248)
			(stroke
				(width 0.15)
				(type solid)
			)
			(layer "F.Fab")
		)
		(fp_line
			(start -0.494 0.248)
			(end -0.494 -0.25)
			(stroke
				(width 0.15)
				(type solid)
			)
			(layer "F.Fab")
		)
		(fp_line
			(start -0.494 -0.25)
			(end 0.504 -0.25)
			(stroke
				(width 0.15)
				(type solid)
			)
			(layer "F.Fab")
		)
		(pad "1" smd roundrect
			(at -0.48 0 180)
			(size 0.59 0.64)
			(layers "F.Cu" "F.Mask" "F.Paste")
			(roundrect_rratio 0.25)
			(net 87 "/OSC32_OUT")
			(pintype "passive")
		)
		(pad "2" smd roundrect
			(at 0.48 0 180)
			(size 0.59 0.64)
			(layers "F.Cu" "F.Mask" "F.Paste")
			(roundrect_rratio 0.25)
			(net 1 "GND")
			(pintype "passive")
		)
	)
	(footprint "antmicro-footprints:Sensirion_DFN-4-1.5x1.5x0.5mm_P0.8mm"
		(layer "F.Cu")
		(at 207.85 119.685 180)
		(descr "Sensiron's 4-pin 1.5mm x 1.5mm Dual Flat No-Lead, used for SHT4x series I²C Humidity & Temperature Sensors, 0.5mm Height. Based on \"Recommended land pattern\" from SHT4x Datasheet V3: https://sensirion.com/media/documents/33FD6951/624C4357/Datasheet_SHT4x.pdf")
		(tags "dfn4 DFN-4 sensirion sht4x SHT40 SHT41 SHT45")
		(property "Reference" "U5"
			(at -0.45 1.485 0)
			(unlocked yes)
			(layer "F.SilkS")
			(effects
				(font
					(size 0.65 0.65)
					(thickness 0.15)
				)
			)
		)
		(property "Value" "SHT45"
			(at 0 -2.2 180)
			(unlocked yes)
			(layer "F.Fab")
			(effects
				(font
					(size 1 1)
					(thickness 0.15)
				)
			)
		)
		(property "Description" "Sensor"
			(at 0 0 180)
			(layer "F.Fab")
			(hide yes)
			(effects
				(font
					(size 1.27 1.27)
					(thickness 0.15)
				)
			)
		)
		(property "Author" "Antmicro"
			(at 415.7 239.37 0)
			(layer "F.Fab")
			(hide yes)
			(effects
				(font
					(size 1 1)
					(thickness 0.15)
				)
			)
		)
		(property "License" "Apache-2.0"
			(at 415.7 239.37 0)
			(layer "F.Fab")
			(hide yes)
			(effects
				(font
					(size 1 1)
					(thickness 0.15)
				)
			)
		)
		(property "MPN" "SHT45-AD1B-R2"
			(at 415.7 239.37 0)
			(layer "F.Fab")
			(hide yes)
			(effects
				(font
					(size 1 1)
					(thickness 0.15)
				)
			)
		)
		(property "Manufacturer" "Sensirion"
			(at 415.7 239.37 0)
			(layer "F.Fab")
			(hide yes)
			(effects
				(font
					(size 1 1)
					(thickness 0.15)
				)
			)
		)
		(sheetfile "environment-sensor.kicad_sch")
		(attr smd)
		(fp_line
			(start 0.801 0.801)
			(end 0.801 0.699)
			(stroke
				(width 0.15)
				(type solid)
			)
			(layer "F.SilkS")
		)
		(fp_line
			(start 0.801 -0.701)
			(end 0.801 -0.803)
			(stroke
				(width 0.15)
				(type solid)
			)
			(layer "F.SilkS")
		)
		(fp_line
			(start 0.801 -0.803)
			(end -1.2 -0.803)
			(stroke
				(width 0.15)
				(type solid)
			)
			(layer "F.SilkS")
		)
		(fp_line
			(start -0.803 0.801)
			(end 0.801 0.801)
			(stroke
				(width 0.15)
				(type solid)
			)
			(layer "F.SilkS")
		)
		(fp_line
			(start -0.803 0.699)
			(end -0.803 0.801)
			(stroke
				(width 0.15)
				(type solid)
			)
			(layer "F.SilkS")
		)
		(fp_circle
			(center -1.21 -0.41)
			(end -1.162 -0.41)
			(stroke
				(width 0.15)
				(type solid)
			)
			(fill yes)
			(layer "F.SilkS")
		)
		(fp_rect
			(start -1.25 -1.25)
			(end 1.248 1.248)
			(stroke
				(width 0.05)
				(type solid)
			)
			(fill no)
			(layer "F.CrtYd")
		)
		(fp_line
			(start 0.749 0.749)
			(end -0.749 0.749)
			(stroke
				(width 0.15)
				(type solid)
			)
			(layer "F.Fab")
		)
		(fp_line
			(start 0.749 -0.749)
			(end 0.749 0.749)
			(stroke
				(width 0.15)
				(type solid)
			)
			(layer "F.Fab")
		)
		(fp_line
			(start -0.599 -0.749)
			(end 0.749 -0.749)
			(stroke
				(width 0.15)
				(type solid)
			)
			(layer "F.Fab")
		)
		(fp_line
			(start -0.749 0.749)
			(end -0.749 -0.599)
			(stroke
				(width 0.15)
				(type solid)
			)
			(layer "F.Fab")
		)
		(fp_line
			(start -0.749 -0.599)
			(end -0.599 -0.749)
			(stroke
				(width 0.15)
				(type solid)
			)
			(layer "F.Fab")
		)
		(fp_circle
			(center 0.001 0.001)
			(end 0.297 0.001)
			(stroke
				(width 0.15)
				(type solid)
			)
			(fill no)
			(layer "F.Fab")
		)
		(fp_circle
			(center -0.499 -0.499)
			(end -0.453 -0.499)
			(stroke
				(width 0.15)
				(type solid)
			)
			(fill yes)
			(layer "F.Fab")
		)
		(fp_text user "${REFERENCE}"
			(at 0.2 1.7 180)
			(unlocked yes)
			(layer "F.Fab")
			(effects
				(font
					(size 1 1)
					(thickness 0.15)
				)
			)
		)
		(pad "1" smd roundrect
			(at -0.701 -0.403 180)
			(size 0.5 0.3)
			(layers "F.Cu" "F.Mask" "F.Paste")
			(roundrect_rratio 0.25)
			(net 9 "I2C_1_SDA")
			(pinfunction "SDA")
			(pintype "bidirectional")
		)
		(pad "2" smd roundrect
			(at -0.701 0.401 180)
			(size 0.5 0.3)
			(layers "F.Cu" "F.Mask" "F.Paste")
			(roundrect_rratio 0.25)
			(net 8 "I2C_1_SCL")
			(pinfunction "SCL")
			(pintype "input")
		)
		(pad "3" smd roundrect
			(at 0.699 0.401 180)
			(size 0.5 0.3)
			(layers "F.Cu" "F.Mask" "F.Paste")
			(roundrect_rratio 0.25)
			(net 2 "+3V3")
			(pinfunction "VDD")
			(pintype "power_in")
		)
		(pad "4" smd roundrect
			(at 0.699 -0.403 180)
			(size 0.5 0.3)
			(layers "F.Cu" "F.Mask" "F.Paste")
			(roundrect_rratio 0.25)
			(net 1 "GND")
			(pinfunction "VSS")
			(pintype "power_in")
		)
	)
	(footprint "antmicro-footprints:C_0402_1005Metric"
		(layer "F.Cu")
		(at 195.376 138.397 90)
		(descr "Capacitor SMD 0402")
		(tags "capacitor SMD 0402")
		(property "Reference" "C17"
			(at 17.93 -9.694 270)
			(layer "B.SilkS")
			(effects
				(font
					(size 0.7 0.7)
					(thickness 0.15)
				)
				(justify left bottom mirror)
			)
		)
		(property "Value" "C_100n_0402"
			(at 0 1.4 90)
			(layer "F.Fab")
			(effects
				(font
					(size 0.7 0.7)
					(thickness 0.15)
				)
				(justify left bottom)
			)
		)
		(property "Description" "SMD Multilayer Ceramic Capacitor, 0.1 µF, 50 V, 0402 [1005 Metric], ± 10%, X5R, GRM Series"
			(at 0 0 90)
			(layer "F.Fab")
			(hide yes)
			(effects
				(font
					(size 1.27 1.27)
					(thickness 0.15)
				)
			)
		)
		(property "Author" "Antmicro"
			(at 333.773 -56.979 0)
			(layer "F.Fab")
			(hide yes)
			(effects
				(font
					(size 1 1)
					(thickness 0.15)
				)
			)
		)
		(property "Dielectric" "X5R"
			(at 333.773 -56.979 0)
			(layer "F.Fab")
			(hide yes)
			(effects
				(font
					(size 1 1)
					(thickness 0.15)
				)
			)
		)
		(property "License" "Apache-2.0"
			(at 333.773 -56.979 0)
			(layer "F.Fab")
			(hide yes)
			(effects
				(font
					(size 1 1)
					(thickness 0.15)
				)
			)
		)
		(property "MPN" "GRM155R61H104KE14D"
			(at 333.773 -56.979 0)
			(layer "F.Fab")
			(hide yes)
			(effects
				(font
					(size 1 1)
					(thickness 0.15)
				)
			)
		)
		(property "Manufacturer" "Murata"
			(at 333.773 -56.979 0)
			(layer "F.Fab")
			(hide yes)
			(effects
				(font
					(size 1 1)
					(thickness 0.15)
				)
			)
		)
		(property "Public" "False"
			(at 333.773 -56.979 0)
			(layer "F.Fab")
			(hide yes)
			(effects
				(font
					(size 1 1)
					(thickness 0.15)
				)
			)
		)
		(property "Val" "100n"
			(at 333.773 -56.979 0)
			(layer "F.Fab")
			(hide yes)
			(effects
				(font
					(size 1 1)
					(thickness 0.15)
				)
			)
		)
		(property "Voltage" "50V"
			(at 333.773 -56.979 0)
			(layer "F.Fab")
			(hide yes)
			(effects
				(font
					(size 1 1)
					(thickness 0.15)
				)
			)
		)
		(sheetfile "environment-sensor.kicad_sch")
		(attr smd)
		(fp_rect
			(start -0.925 -0.47)
			(end 0.925 0.47)
			(stroke
				(width 0.05)
				(type default)
			)
			(fill no)
			(layer "F.CrtYd")
		)
		(fp_line
			(start 0.504 -0.25)
			(end 0.504 0.248)
			(stroke
				(width 0.15)
				(type solid)
			)
			(layer "F.Fab")
		)
		(fp_line
			(start -0.494 -0.25)
			(end 0.504 -0.25)
			(stroke
				(width 0.15)
				(type solid)
			)
			(layer "F.Fab")
		)
		(fp_line
			(start 0.504 0.248)
			(end -0.494 0.248)
			(stroke
				(width 0.15)
				(type solid)
			)
			(layer "F.Fab")
		)
		(fp_line
			(start -0.494 0.248)
			(end -0.494 -0.25)
			(stroke
				(width 0.15)
				(type solid)
			)
			(layer "F.Fab")
		)
		(pad "1" smd roundrect
			(at -0.48 0 90)
			(size 0.59 0.64)
			(layers "F.Cu" "F.Mask" "F.Paste")
			(roundrect_rratio 0.25)
			(net 1 "GND")
			(pintype "passive")
		)
		(pad "2" smd roundrect
			(at 0.48 0 90)
			(size 0.59 0.64)
			(layers "F.Cu" "F.Mask" "F.Paste")
			(roundrect_rratio 0.25)
			(net 2 "+3V3")
			(pintype "passive")
		)
	)
	(footprint "antmicro-footprints:R_0402_1005Metric"
		(layer "F.Cu")
		(at 187.35 138.4 90)
		(descr "Resistor SMD 0402")
		(tags "resistor SMD 0402")
		(property "Reference" "R16"
			(at 20.35 -1.65 90)
			(layer "B.SilkS")
			(effects
				(font
					(size 0.7 0.7)
					(thickness 0.15)
				)
				(justify left bottom mirror)
			)
		)
		(property "Value" "R_0R_0402"
			(at -1.011843 1.772047 90)
			(layer "F.Fab")
			(effects
				(font
					(size 0.7 0.7)
					(thickness 0.15)
				)
				(justify left bottom)
			)
		)
		(property "Description" "SMD Chip Resistor, Jumper, 0 ohm, 100 mW, 0402 [1005 Metric], Thick Film, General Purpose"
			(at 0 0 90)
			(layer "F.Fab")
			(hide yes)
			(effects
				(font
					(size 1.27 1.27)
					(thickness 0.15)
				)
			)
		)
		(property "Author" "Antmicro"
			(at 325.75 -48.95 0)
			(layer "F.Fab")
			(hide yes)
			(effects
				(font
					(size 1 1)
					(thickness 0.15)
				)
			)
		)
		(property "Current" "1A"
			(at 325.75 -48.95 0)
			(layer "F.Fab")
			(hide yes)
			(effects
				(font
					(size 1 1)
					(thickness 0.15)
				)
			)
		)
		(property "License" "Apache-2.0"
			(at 325.75 -48.95 0)
			(layer "F.Fab")
			(hide yes)
			(effects
				(font
					(size 1 1)
					(thickness 0.15)
				)
			)
		)
		(property "MPN" "ERJ2GE0R00X"
			(at 325.75 -48.95 0)
			(layer "F.Fab")
			(hide yes)
			(effects
				(font
					(size 1 1)
					(thickness 0.15)
				)
			)
		)
		(property "Manufacturer" "Panasonic"
			(at 325.75 -48.95 0)
			(layer "F.Fab")
			(hide yes)
			(effects
				(font
					(size 1 1)
					(thickness 0.15)
				)
			)
		)
		(property "Public" "False"
			(at 325.75 -48.95 0)
			(layer "F.Fab")
			(hide yes)
			(effects
				(font
					(size 1 1)
					(thickness 0.15)
				)
			)
		)
		(property "Tolerance" ""
			(at 325.75 -48.95 0)
			(layer "F.Fab")
			(hide yes)
			(effects
				(font
					(size 1 1)
					(thickness 0.15)
				)
			)
		)
		(property "Val" "0R"
			(at 325.75 -48.95 0)
			(layer "F.Fab")
			(hide yes)
			(effects
				(font
					(size 1 1)
					(thickness 0.15)
				)
			)
		)
		(sheetfile "environment-sensor.kicad_sch")
		(attr smd exclude_from_pos_files exclude_from_bom dnp)
		(fp_rect
			(start -0.925 -0.47)
			(end 0.925 0.47)
			(stroke
				(width 0.05)
				(type default)
			)
			(fill no)
			(layer "F.CrtYd")
		)
		(fp_rect
			(start -0.5 -0.25)
			(end 0.5 0.25)
			(stroke
				(width 0.15)
				(type solid)
			)
			(fill no)
			(layer "F.Fab")
		)
		(pad "1" smd roundrect
			(at -0.48 0 90)
			(size 0.59 0.64)
			(layers "F.Cu" "F.Mask" "F.Paste")
			(roundrect_rratio 0.25)
			(net 45 "Net-(U1-RXD)")
			(pintype "passive")
		)
		(pad "2" smd roundrect
			(at 0.48 0 90)
			(size 0.59 0.64)
			(layers "F.Cu" "F.Mask" "F.Paste")
			(roundrect_rratio 0.25)
			(net 16 "LPUART_1_STM_RX")
			(pintype "passive")
		)
	)
	(footprint "antmicro-footprints:TP_SMD_1mm"
		(layer "F.Cu")
		(at 199.404 127.566)
		(property "Reference" "TP12"
			(at 0 -0.731898 0)
			(layer "F.SilkS")
			(hide yes)
			(effects
				(font
					(size 0.7 0.7)
					(thickness 0.15)
				)
				(justify left bottom)
			)
		)
		(property "Value" "TP_1mm_SMD"
			(at 0 1.4 0)
			(layer "F.Fab")
			(effects
				(font
					(size 0.7 0.7)
					(thickness 0.15)
				)
				(justify left bottom)
			)
		)
		(property "Description" "Test point 1mm SMD"
			(at 0 0 0)
			(layer "F.Fab")
			(hide yes)
			(effects
				(font
					(size 1.27 1.27)
					(thickness 0.15)
				)
			)
		)
		(property "Author" "Antmicro"
			(at 0 0 0)
			(layer "F.Fab")
			(hide yes)
			(effects
				(font
					(size 1 1)
					(thickness 0.15)
				)
			)
		)
		(property "License" "Apache-2.0"
			(at 0 0 0)
			(layer "F.Fab")
			(hide yes)
			(effects
				(font
					(size 1 1)
					(thickness 0.15)
				)
			)
		)
		(property "MPN" ""
			(at 0 0 0)
			(layer "F.Fab")
			(hide yes)
			(effects
				(font
					(size 1 1)
					(thickness 0.15)
				)
			)
		)
		(property "Manufacturer" ""
			(at 0 0 0)
			(layer "F.Fab")
			(hide yes)
			(effects
				(font
					(size 1 1)
					(thickness 0.15)
				)
			)
		)
		(property "Public" "False"
			(at 0 0 0)
			(layer "F.Fab")
			(hide yes)
			(effects
				(font
					(size 1 1)
					(thickness 0.15)
				)
			)
		)
		(sheetfile "environment-sensor.kicad_sch")
		(attr exclude_from_pos_files)
		(pad "1" smd circle
			(at 0 0)
			(size 1 1)
			(layers "F.Cu" "F.Mask")
			(net 8 "I2C_1_SCL")
			(pinfunction "1")
			(pintype "passive")
		)
	)
	(footprint "antmicro-footprints:C_0402_1005Metric"
		(layer "F.Cu")
		(at 175.05 133.6 90)
		(descr "Capacitor SMD 0402")
		(tags "capacitor SMD 0402")
		(property "Reference" "C10"
			(at 0.85 -0.1 45)
			(layer "F.SilkS")
			(effects
				(font
					(size 0.7 0.7)
					(thickness 0.15)
				)
				(justify left bottom)
			)
		)
		(property "Value" "C_4u7_0402"
			(at 0 1.4 90)
			(layer "F.Fab")
			(effects
				(font
					(size 0.7 0.7)
					(thickness 0.15)
				)
				(justify left bottom)
			)
		)
		(property "Description" "SMD Multilayer Ceramic Capacitor, 4.7 µF, 10 V, 0402 [1005 Metric], ± 20%, X5R, GRM Series"
			(at 0 0 90)
			(layer "F.Fab")
			(hide yes)
			(effects
				(font
					(size 1.27 1.27)
					(thickness 0.15)
				)
			)
		)
		(property "Author" "Antmicro"
			(at 308.65 -41.45 0)
			(layer "F.Fab")
			(hide yes)
			(effects
				(font
					(size 1 1)
					(thickness 0.15)
				)
			)
		)
		(property "Dielectric" ""
			(at 308.65 -41.45 0)
			(layer "F.Fab")
			(hide yes)
			(effects
				(font
					(size 1 1)
					(thickness 0.15)
				)
			)
		)
		(property "License" "Apache-2.0"
			(at 308.65 -41.45 0)
			(layer "F.Fab")
			(hide yes)
			(effects
				(font
					(size 1 1)
					(thickness 0.15)
				)
			)
		)
		(property "MPN" "GRM155R61A475MEAAD"
			(at 308.65 -41.45 0)
			(layer "F.Fab")
			(hide yes)
			(effects
				(font
					(size 1 1)
					(thickness 0.15)
				)
			)
		)
		(property "Manufacturer" "Murata"
			(at 308.65 -41.45 0)
			(layer "F.Fab")
			(hide yes)
			(effects
				(font
					(size 1 1)
					(thickness 0.15)
				)
			)
		)
		(property "Public" "False"
			(at 308.65 -41.45 0)
			(layer "F.Fab")
			(hide yes)
			(effects
				(font
					(size 1 1)
					(thickness 0.15)
				)
			)
		)
		(property "Val" "4u7"
			(at 308.65 -41.45 0)
			(layer "F.Fab")
			(hide yes)
			(effects
				(font
					(size 1 1)
					(thickness 0.15)
				)
			)
		)
		(property "Voltage" ""
			(at 308.65 -41.45 0)
			(layer "F.Fab")
			(hide yes)
			(effects
				(font
					(size 1 1)
					(thickness 0.15)
				)
			)
		)
		(sheetfile "environment-sensor.kicad_sch")
		(attr smd)
		(fp_rect
			(start -0.925 -0.47)
			(end 0.925 0.47)
			(stroke
				(width 0.05)
				(type default)
			)
			(fill no)
			(layer "F.CrtYd")
		)
		(fp_line
			(start 0.504 -0.25)
			(end 0.504 0.248)
			(stroke
				(width 0.15)
				(type solid)
			)
			(layer "F.Fab")
		)
		(fp_line
			(start -0.494 -0.25)
			(end 0.504 -0.25)
			(stroke
				(width 0.15)
				(type solid)
			)
			(layer "F.Fab")
		)
		(fp_line
			(start 0.504 0.248)
			(end -0.494 0.248)
			(stroke
				(width 0.15)
				(type solid)
			)
			(layer "F.Fab")
		)
		(fp_line
			(start -0.494 0.248)
			(end -0.494 -0.25)
			(stroke
				(width 0.15)
				(type solid)
			)
			(layer "F.Fab")
		)
		(pad "1" smd roundrect
			(at -0.48 0 90)
			(size 0.59 0.64)
			(layers "F.Cu" "F.Mask" "F.Paste")
			(roundrect_rratio 0.25)
			(net 1 "GND")
			(pintype "passive")
		)
		(pad "2" smd roundrect
			(at 0.48 0 90)
			(size 0.59 0.64)
			(layers "F.Cu" "F.Mask" "F.Paste")
			(roundrect_rratio 0.25)
			(net 2 "+3V3")
			(pintype "passive")
		)
	)
	(footprint "antmicro-footprints:C_0402_1005Metric"
		(layer "F.Cu")
		(at 205.15 119.835 -90)
		(descr "Capacitor SMD 0402")
		(tags "capacitor SMD 0402")
		(property "Reference" "C26"
			(at -0.935 -1.35 90)
			(layer "F.SilkS")
			(effects
				(font
					(size 0.7 0.7)
					(thickness 0.15)
				)
				(justify right bottom)
			)
		)
		(property "Value" "C_100n_0402"
			(at 0 1.4 90)
			(layer "F.Fab")
			(effects
				(font
					(size 0.7 0.7)
					(thickness 0.15)
				)
				(justify right bottom)
			)
		)
		(property "Description" "SMD Multilayer Ceramic Capacitor, 0.1 µF, 50 V, 0402 [1005 Metric], ± 10%, X5R, GRM Series"
			(at 0 0 270)
			(layer "F.Fab")
			(hide yes)
			(effects
				(font
					(size 1.27 1.27)
					(thickness 0.15)
				)
			)
		)
		(property "Author" "Antmicro"
			(at 85.315 324.985 0)
			(layer "F.Fab")
			(hide yes)
			(effects
				(font
					(size 1 1)
					(thickness 0.15)
				)
			)
		)
		(property "Dielectric" "X5R"
			(at 85.315 324.985 0)
			(layer "F.Fab")
			(hide yes)
			(effects
				(font
					(size 1 1)
					(thickness 0.15)
				)
			)
		)
		(property "License" "Apache-2.0"
			(at 85.315 324.985 0)
			(layer "F.Fab")
			(hide yes)
			(effects
				(font
					(size 1 1)
					(thickness 0.15)
				)
			)
		)
		(property "MPN" "GRM155R61H104KE14D"
			(at 85.315 324.985 0)
			(layer "F.Fab")
			(hide yes)
			(effects
				(font
					(size 1 1)
					(thickness 0.15)
				)
			)
		)
		(property "Manufacturer" "Murata"
			(at 85.315 324.985 0)
			(layer "F.Fab")
			(hide yes)
			(effects
				(font
					(size 1 1)
					(thickness 0.15)
				)
			)
		)
		(property "Public" "False"
			(at 85.315 324.985 0)
			(layer "F.Fab")
			(hide yes)
			(effects
				(font
					(size 1 1)
					(thickness 0.15)
				)
			)
		)
		(property "Val" "100n"
			(at 85.315 324.985 0)
			(layer "F.Fab")
			(hide yes)
			(effects
				(font
					(size 1 1)
					(thickness 0.15)
				)
			)
		)
		(property "Voltage" "50V"
			(at 85.315 324.985 0)
			(layer "F.Fab")
			(hide yes)
			(effects
				(font
					(size 1 1)
					(thickness 0.15)
				)
			)
		)
		(sheetfile "environment-sensor.kicad_sch")
		(attr smd)
		(fp_rect
			(start -0.925 -0.47)
			(end 0.925 0.47)
			(stroke
				(width 0.05)
				(type default)
			)
			(fill no)
			(layer "F.CrtYd")
		)
		(fp_line
			(start -0.494 0.248)
			(end -0.494 -0.25)
			(stroke
				(width 0.15)
				(type solid)
			)
			(layer "F.Fab")
		)
		(fp_line
			(start 0.504 0.248)
			(end -0.494 0.248)
			(stroke
				(width 0.15)
				(type solid)
			)
			(layer "F.Fab")
		)
		(fp_line
			(start -0.494 -0.25)
			(end 0.504 -0.25)
			(stroke
				(width 0.15)
				(type solid)
			)
			(layer "F.Fab")
		)
		(fp_line
			(start 0.504 -0.25)
			(end 0.504 0.248)
			(stroke
				(width 0.15)
				(type solid)
			)
			(layer "F.Fab")
		)
		(pad "1" smd roundrect
			(at -0.48 0 270)
			(size 0.59 0.64)
			(layers "F.Cu" "F.Mask" "F.Paste")
			(roundrect_rratio 0.25)
			(net 2 "+3V3")
			(pintype "passive")
		)
		(pad "2" smd roundrect
			(at 0.48 0 270)
			(size 0.59 0.64)
			(layers "F.Cu" "F.Mask" "F.Paste")
			(roundrect_rratio 0.25)
			(net 1 "GND")
			(pintype "passive")
		)
	)
	(footprint "antmicro-footprints:C_0402_1005Metric"
		(layer "F.Cu")
		(at 174.249 123.7 90)
		(descr "Capacitor SMD 0402")
		(tags "capacitor SMD 0402")
		(property "Reference" "C1"
			(at -2.373 0.344 90)
			(layer "F.SilkS")
			(effects
				(font
					(size 0.7 0.7)
					(thickness 0.15)
				)
				(justify left bottom)
			)
		)
		(property "Value" "C_4u7_0402"
			(at 0 1.4 90)
			(layer "F.Fab")
			(effects
				(font
					(size 0.7 0.7)
					(thickness 0.15)
				)
				(justify left bottom)
			)
		)
		(property "Description" "SMD Multilayer Ceramic Capacitor, 4.7 µF, 10 V, 0402 [1005 Metric], ± 20%, X5R, GRM Series"
			(at 0 0 90)
			(layer "F.Fab")
			(hide yes)
			(effects
				(font
					(size 1.27 1.27)
					(thickness 0.15)
				)
			)
		)
		(property "Author" "Antmicro"
			(at 297.949 -50.549 0)
			(layer "F.Fab")
			(hide yes)
			(effects
				(font
					(size 1 1)
					(thickness 0.15)
				)
			)
		)
		(property "Dielectric" ""
			(at 297.949 -50.549 0)
			(layer "F.Fab")
			(hide yes)
			(effects
				(font
					(size 1 1)
					(thickness 0.15)
				)
			)
		)
		(property "License" "Apache-2.0"
			(at 297.949 -50.549 0)
			(layer "F.Fab")
			(hide yes)
			(effects
				(font
					(size 1 1)
					(thickness 0.15)
				)
			)
		)
		(property "MPN" "GRM155R61A475MEAAD"
			(at 297.949 -50.549 0)
			(layer "F.Fab")
			(hide yes)
			(effects
				(font
					(size 1 1)
					(thickness 0.15)
				)
			)
		)
		(property "Manufacturer" "Murata"
			(at 297.949 -50.549 0)
			(layer "F.Fab")
			(hide yes)
			(effects
				(font
					(size 1 1)
					(thickness 0.15)
				)
			)
		)
		(property "Public" "False"
			(at 297.949 -50.549 0)
			(layer "F.Fab")
			(hide yes)
			(effects
				(font
					(size 1 1)
					(thickness 0.15)
				)
			)
		)
		(property "Val" "4u7"
			(at 297.949 -50.549 0)
			(layer "F.Fab")
			(hide yes)
			(effects
				(font
					(size 1 1)
					(thickness 0.15)
				)
			)
		)
		(property "Voltage" ""
			(at 297.949 -50.549 0)
			(layer "F.Fab")
			(hide yes)
			(effects
				(font
					(size 1 1)
					(thickness 0.15)
				)
			)
		)
		(sheetfile "environment-sensor.kicad_sch")
		(attr smd)
		(fp_rect
			(start -0.925 -0.47)
			(end 0.925 0.47)
			(stroke
				(width 0.05)
				(type default)
			)
			(fill no)
			(layer "F.CrtYd")
		)
		(fp_line
			(start 0.504 -0.25)
			(end 0.504 0.248)
			(stroke
				(width 0.15)
				(type solid)
			)
			(layer "F.Fab")
		)
		(fp_line
			(start -0.494 -0.25)
			(end 0.504 -0.25)
			(stroke
				(width 0.15)
				(type solid)
			)
			(layer "F.Fab")
		)
		(fp_line
			(start 0.504 0.248)
			(end -0.494 0.248)
			(stroke
				(width 0.15)
				(type solid)
			)
			(layer "F.Fab")
		)
		(fp_line
			(start -0.494 0.248)
			(end -0.494 -0.25)
			(stroke
				(width 0.15)
				(type solid)
			)
			(layer "F.Fab")
		)
		(pad "1" smd roundrect
			(at -0.48 0 90)
			(size 0.59 0.64)
			(layers "F.Cu" "F.Mask" "F.Paste")
			(roundrect_rratio 0.25)
			(net 1 "GND")
			(pintype "passive")
		)
		(pad "2" smd roundrect
			(at 0.48 0 90)
			(size 0.59 0.64)
			(layers "F.Cu" "F.Mask" "F.Paste")
			(roundrect_rratio 0.25)
			(net 26 "+5V")
			(pintype "passive")
		)
	)
	(footprint "antmicro-footprints:R_0402_1005Metric"
		(layer "F.Cu")
		(at 184.05 138.4 90)
		(descr "Resistor SMD 0402")
		(tags "resistor SMD 0402")
		(property "Reference" "R15"
			(at 20.35 -1.1 90)
			(layer "B.SilkS")
			(effects
				(font
					(size 0.7 0.7)
					(thickness 0.15)
				)
				(justify left bottom mirror)
			)
		)
		(property "Value" "R_0R_0402"
			(at -1.011843 1.772047 90)
			(layer "F.Fab")
			(effects
				(font
					(size 0.7 0.7)
					(thickness 0.15)
				)
				(justify left bottom)
			)
		)
		(property "Description" "SMD Chip Resistor, Jumper, 0 ohm, 100 mW, 0402 [1005 Metric], Thick Film, General Purpose"
			(at 0 0 90)
			(layer "F.Fab")
			(hide yes)
			(effects
				(font
					(size 1.27 1.27)
					(thickness 0.15)
				)
			)
		)
		(property "Author" "Antmicro"
			(at 322.45 -45.65 0)
			(layer "F.Fab")
			(hide yes)
			(effects
				(font
					(size 1 1)
					(thickness 0.15)
				)
			)
		)
		(property "Current" "1A"
			(at 322.45 -45.65 0)
			(layer "F.Fab")
			(hide yes)
			(effects
				(font
					(size 1 1)
					(thickness 0.15)
				)
			)
		)
		(property "License" "Apache-2.0"
			(at 322.45 -45.65 0)
			(layer "F.Fab")
			(hide yes)
			(effects
				(font
					(size 1 1)
					(thickness 0.15)
				)
			)
		)
		(property "MPN" "ERJ2GE0R00X"
			(at 322.45 -45.65 0)
			(layer "F.Fab")
			(hide yes)
			(effects
				(font
					(size 1 1)
					(thickness 0.15)
				)
			)
		)
		(property "Manufacturer" "Panasonic"
			(at 322.45 -45.65 0)
			(layer "F.Fab")
			(hide yes)
			(effects
				(font
					(size 1 1)
					(thickness 0.15)
				)
			)
		)
		(property "Public" "False"
			(at 322.45 -45.65 0)
			(layer "F.Fab")
			(hide yes)
			(effects
				(font
					(size 1 1)
					(thickness 0.15)
				)
			)
		)
		(property "Tolerance" ""
			(at 322.45 -45.65 0)
			(layer "F.Fab")
			(hide yes)
			(effects
				(font
					(size 1 1)
					(thickness 0.15)
				)
			)
		)
		(property "Val" "0R"
			(at 322.45 -45.65 0)
			(layer "F.Fab")
			(hide yes)
			(effects
				(font
					(size 1 1)
					(thickness 0.15)
				)
			)
		)
		(sheetfile "environment-sensor.kicad_sch")
		(attr smd exclude_from_pos_files exclude_from_bom dnp)
		(fp_rect
			(start -0.925 -0.47)
			(end 0.925 0.47)
			(stroke
				(width 0.05)
				(type default)
			)
			(fill no)
			(layer "F.CrtYd")
		)
		(fp_rect
			(start -0.5 -0.25)
			(end 0.5 0.25)
			(stroke
				(width 0.15)
				(type solid)
			)
			(fill no)
			(layer "F.Fab")
		)
		(pad "1" smd roundrect
			(at -0.48 0 90)
			(size 0.59 0.64)
			(layers "F.Cu" "F.Mask" "F.Paste")
			(roundrect_rratio 0.25)
			(net 44 "Net-(U1-TXD)")
			(pintype "passive")
		)
		(pad "2" smd roundrect
			(at 0.48 0 90)
			(size 0.59 0.64)
			(layers "F.Cu" "F.Mask" "F.Paste")
			(roundrect_rratio 0.25)
			(net 17 "LPUART_1_STM_TX")
			(pintype "passive")
		)
	)
	(footprint "antmicro-footprints:R_0402_1005Metric"
		(layer "F.Cu")
		(at 203.75 117.835 90)
		(descr "Resistor SMD 0402")
		(tags "resistor SMD 0402")
		(property "Reference" "R35"
			(at -2.465 -3.55 180)
			(layer "F.SilkS")
			(effects
				(font
					(size 0.7 0.7)
					(thickness 0.15)
				)
				(justify left bottom)
			)
		)
		(property "Value" "R_100k_0402"
			(at 0 1.4 90)
			(layer "F.Fab")
			(effects
				(font
					(size 0.7 0.7)
					(thickness 0.15)
				)
				(justify left bottom)
			)
		)
		(property "Description" "SMD Chip Resistor, 100 kohm, ± 1%, 62.5 mW, 0402 [1005 Metric], Thick Film, General Purpose"
			(at 0 0 90)
			(layer "F.Fab")
			(hide yes)
			(effects
				(font
					(size 1.27 1.27)
					(thickness 0.15)
				)
			)
		)
		(property "Author" "Antmicro"
			(at 321.585 -85.915 0)
			(layer "F.Fab")
			(hide yes)
			(effects
				(font
					(size 1 1)
					(thickness 0.15)
				)
			)
		)
		(property "License" "Apache-2.0"
			(at 321.585 -85.915 0)
			(layer "F.Fab")
			(hide yes)
			(effects
				(font
					(size 1 1)
					(thickness 0.15)
				)
			)
		)
		(property "MPN" "CR0402-FX-1003GLF"
			(at 321.585 -85.915 0)
			(layer "F.Fab")
			(hide yes)
			(effects
				(font
					(size 1 1)
					(thickness 0.15)
				)
			)
		)
		(property "Manufacturer" "Bourns"
			(at 321.585 -85.915 0)
			(layer "F.Fab")
			(hide yes)
			(effects
				(font
					(size 1 1)
					(thickness 0.15)
				)
			)
		)
		(property "Public" "False"
			(at 321.585 -85.915 0)
			(layer "F.Fab")
			(hide yes)
			(effects
				(font
					(size 1 1)
					(thickness 0.15)
				)
			)
		)
		(property "Tolerance" "1%"
			(at 321.585 -85.915 0)
			(layer "F.Fab")
			(hide yes)
			(effects
				(font
					(size 1 1)
					(thickness 0.15)
				)
			)
		)
		(property "Val" "100k"
			(at 321.585 -85.915 0)
			(layer "F.Fab")
			(hide yes)
			(effects
				(font
					(size 1 1)
					(thickness 0.15)
				)
			)
		)
		(sheetfile "environment-sensor.kicad_sch")
		(attr smd exclude_from_pos_files exclude_from_bom dnp)
		(fp_rect
			(start -0.925 -0.47)
			(end 0.925 0.47)
			(stroke
				(width 0.05)
				(type default)
			)
			(fill no)
			(layer "F.CrtYd")
		)
		(fp_rect
			(start -0.5 -0.25)
			(end 0.5 0.25)
			(stroke
				(width 0.15)
				(type solid)
			)
			(fill no)
			(layer "F.Fab")
		)
		(pad "1" smd roundrect
			(at -0.48 0 90)
			(size 0.59 0.64)
			(layers "F.Cu" "F.Mask" "F.Paste")
			(roundrect_rratio 0.25)
			(net 2 "+3V3")
			(pintype "passive")
		)
		(pad "2" smd roundrect
			(at 0.48 0 90)
			(size 0.59 0.64)
			(layers "F.Cu" "F.Mask" "F.Paste")
			(roundrect_rratio 0.25)
			(net 53 "Net-(U6-SDO)")
			(pintype "passive")
		)
	)
	(footprint "antmicro-footprints:R_0402_1005Metric"
		(layer "F.Cu")
		(at 186.25 138.4 90)
		(descr "Resistor SMD 0402")
		(tags "resistor SMD 0402")
		(property "Reference" "R13"
			(at 20.346 -1.4685 270)
			(layer "B.SilkS")
			(effects
				(font
					(size 0.7 0.7)
					(thickness 0.15)
				)
				(justify left bottom mirror)
			)
		)
		(property "Value" "R_0R_0402"
			(at 0 1.4 90)
			(layer "F.Fab")
			(effects
				(font
					(size 0.7 0.7)
					(thickness 0.15)
				)
				(justify left bottom)
			)
		)
		(property "Description" "SMD Chip Resistor, Jumper, 0 ohm, 100 mW, 0402 [1005 Metric], Thick Film, General Purpose"
			(at 0 0 90)
			(layer "F.Fab")
			(hide yes)
			(effects
				(font
					(size 1.27 1.27)
					(thickness 0.15)
				)
			)
		)
		(property "Author" "Antmicro"
			(at 324.65 -47.85 0)
			(layer "F.Fab")
			(hide yes)
			(effects
				(font
					(size 1 1)
					(thickness 0.15)
				)
			)
		)
		(property "Current" "1A"
			(at 324.65 -47.85 0)
			(layer "F.Fab")
			(hide yes)
			(effects
				(font
					(size 1 1)
					(thickness 0.15)
				)
			)
		)
		(property "License" "Apache-2.0"
			(at 324.65 -47.85 0)
			(layer "F.Fab")
			(hide yes)
			(effects
				(font
					(size 1 1)
					(thickness 0.15)
				)
			)
		)
		(property "MPN" "ERJ2GE0R00X"
			(at 324.65 -47.85 0)
			(layer "F.Fab")
			(hide yes)
			(effects
				(font
					(size 1 1)
					(thickness 0.15)
				)
			)
		)
		(property "Manufacturer" "Panasonic"
			(at 324.65 -47.85 0)
			(layer "F.Fab")
			(hide yes)
			(effects
				(font
					(size 1 1)
					(thickness 0.15)
				)
			)
		)
		(property "Public" "False"
			(at 324.65 -47.85 0)
			(layer "F.Fab")
			(hide yes)
			(effects
				(font
					(size 1 1)
					(thickness 0.15)
				)
			)
		)
		(property "Tolerance" ""
			(at 324.65 -47.85 0)
			(layer "F.Fab")
			(hide yes)
			(effects
				(font
					(size 1 1)
					(thickness 0.15)
				)
			)
		)
		(property "Val" "0R"
			(at 324.65 -47.85 0)
			(layer "F.Fab")
			(hide yes)
			(effects
				(font
					(size 1 1)
					(thickness 0.15)
				)
			)
		)
		(sheetfile "environment-sensor.kicad_sch")
		(attr smd)
		(fp_rect
			(start -0.925 -0.47)
			(end 0.925 0.47)
			(stroke
				(width 0.05)
				(type default)
			)
			(fill no)
			(layer "F.CrtYd")
		)
		(fp_rect
			(start -0.5 -0.25)
			(end 0.5 0.25)
			(stroke
				(width 0.15)
				(type solid)
			)
			(fill no)
			(layer "F.Fab")
		)
		(pad "1" smd roundrect
			(at -0.48 0 90)
			(size 0.59 0.64)
			(layers "F.Cu" "F.Mask" "F.Paste")
			(roundrect_rratio 0.25)
			(net 44 "Net-(U1-TXD)")
			(pintype "passive")
		)
		(pad "2" smd roundrect
			(at 0.48 0 90)
			(size 0.59 0.64)
			(layers "F.Cu" "F.Mask" "F.Paste")
			(roundrect_rratio 0.25)
			(net 16 "LPUART_1_STM_RX")
			(pintype "passive")
		)
	)
	(footprint "antmicro-footprints:TP_SMD_1mm"
		(layer "F.Cu")
		(at 176.2 132.65)
		(property "Reference" "TP9"
			(at 0 -0.731898 0)
			(layer "F.SilkS")
			(hide yes)
			(effects
				(font
					(size 0.7 0.7)
					(thickness 0.15)
				)
				(justify left bottom)
			)
		)
		(property "Value" "TP_1mm_SMD"
			(at 0 1.4 0)
			(layer "F.Fab")
			(effects
				(font
					(size 0.7 0.7)
					(thickness 0.15)
				)
				(justify left bottom)
			)
		)
		(property "Description" "Test point 1mm SMD"
			(at 0 0 0)
			(layer "F.Fab")
			(hide yes)
			(effects
				(font
					(size 1.27 1.27)
					(thickness 0.15)
				)
			)
		)
		(property "Author" "Antmicro"
			(at 0 0 0)
			(layer "F.Fab")
			(hide yes)
			(effects
				(font
					(size 1 1)
					(thickness 0.15)
				)
			)
		)
		(property "License" "Apache-2.0"
			(at 0 0 0)
			(layer "F.Fab")
			(hide yes)
			(effects
				(font
					(size 1 1)
					(thickness 0.15)
				)
			)
		)
		(property "MPN" ""
			(at 0 0 0)
			(layer "F.Fab")
			(hide yes)
			(effects
				(font
					(size 1 1)
					(thickness 0.15)
				)
			)
		)
		(property "Manufacturer" ""
			(at 0 0 0)
			(layer "F.Fab")
			(hide yes)
			(effects
				(font
					(size 1 1)
					(thickness 0.15)
				)
			)
		)
		(property "Public" "False"
			(at 0 0 0)
			(layer "F.Fab")
			(hide yes)
			(effects
				(font
					(size 1 1)
					(thickness 0.15)
				)
			)
		)
		(sheetfile "environment-sensor.kicad_sch")
		(attr exclude_from_pos_files)
		(pad "1" smd circle
			(at 0 0)
			(size 1 1)
			(layers "F.Cu" "F.Mask")
			(net 2 "+3V3")
			(pinfunction "1")
			(pintype "passive")
		)
	)
	(footprint "antmicro-footprints:SOP-8_3.9x5.05mm_P1.27mm"
		(layer "F.Cu")
		(at 187.804 120.997 -90)
		(property "Reference" "U4"
			(at 3.353 3.804 0)
			(unlocked yes)
			(layer "F.SilkS")
			(effects
				(font
					(size 0.7 0.7)
					(thickness 0.15)
				)
				(justify left bottom)
			)
		)
		(property "Value" "MB85RC1MTPNF-G"
			(at -2.641 6.368 270)
			(unlocked yes)
			(layer "F.Fab")
			(effects
				(font
					(size 0.7 0.7)
					(thickness 0.15)
				)
				(justify left bottom)
			)
		)
		(property "Description" "FRAM (Ferroelectric RAM) Memory IC 1Mbit I²C 3.4 MHz 130 ns 8-SOP"
			(at 0 0 270)
			(layer "F.Fab")
			(hide yes)
			(effects
				(font
					(size 1.27 1.27)
					(thickness 0.15)
				)
			)
		)
		(property "Author" "Antmicro"
			(at 66.807 308.801 0)
			(layer "F.Fab")
			(hide yes)
			(effects
				(font
					(size 1 1)
					(thickness 0.15)
				)
			)
		)
		(property "License" "Apache-2.0"
			(at 66.807 308.801 0)
			(layer "F.Fab")
			(hide yes)
			(effects
				(font
					(size 1 1)
					(thickness 0.15)
				)
			)
		)
		(property "MPN" "MB85RC1MTPNF-G-JNERE1"
			(at 66.807 308.801 0)
			(layer "F.Fab")
			(hide yes)
			(effects
				(font
					(size 1 1)
					(thickness 0.15)
				)
			)
		)
		(property "Manufacturer" "Fujitsu"
			(at 66.807 308.801 0)
			(layer "F.Fab")
			(hide yes)
			(effects
				(font
					(size 1 1)
					(thickness 0.15)
				)
			)
		)
		(sheetfile "environment-sensor.kicad_sch")
		(attr smd)
		(fp_line
			(start 2.289 2.12)
			(end 2.588 2.12)
			(stroke
				(width 0.15)
				(type solid)
			)
			(layer "F.SilkS")
		)
		(fp_line
			(start 2.588 2.12)
			(end 2.588 1.82)
			(stroke
				(width 0.15)
				(type solid)
			)
			(layer "F.SilkS")
		)
		(fp_line
			(start -2.311 1.912)
			(end -2.311 2.717)
			(stroke
				(width 0.15)
				(type solid)
			)
			(layer "F.SilkS")
		)
		(fp_line
			(start -2.609 1.62)
			(end -2.311 1.912)
			(stroke
				(width 0.15)
				(type solid)
			)
			(layer "F.SilkS")
		)
		(fp_line
			(start -2.609 1.217)
			(end -2.609 1.62)
			(stroke
				(width 0.15)
				(type solid)
			)
			(layer "F.SilkS")
		)
		(fp_line
			(start -2.609 -2.081)
			(end -2.609 -1.782)
			(stroke
				(width 0.15)
				(type solid)
			)
			(layer "F.SilkS")
		)
		(fp_line
			(start -2.311 -2.081)
			(end -2.609 -2.081)
			(stroke
				(width 0.15)
				(type solid)
			)
			(layer "F.SilkS")
		)
		(fp_line
			(start 2.289 -2.081)
			(end 2.588 -2.081)
			(stroke
				(width 0.15)
				(type solid)
			)
			(layer "F.SilkS")
		)
		(fp_line
			(start 2.588 -2.081)
			(end 2.588 -1.782)
			(stroke
				(width 0.15)
				(type solid)
			)
			(layer "F.SilkS")
		)
		(fp_circle
			(center -2.54 3.81)
			(end -2.49 3.81)
			(stroke
				(width 0.15)
				(type solid)
			)
			(fill yes)
			(layer "F.SilkS")
		)
		(fp_rect
			(start -2.79 -3.75)
			(end 2.76 3.79)
			(stroke
				(width 0.05)
				(type solid)
			)
			(fill no)
			(layer "F.CrtYd")
		)
		(fp_line
			(start -2.058 1.969)
			(end 2.439 1.969)
			(stroke
				(width 0.15)
				(type solid)
			)
			(layer "F.Fab")
		)
		(fp_line
			(start -2.46 1.568)
			(end -2.058 1.969)
			(stroke
				(width 0.15)
				(type solid)
			)
			(layer "F.Fab")
		)
		(fp_line
			(start -2.46 1.568)
			(end -2.46 -1.93)
			(stroke
				(width 0.15)
				(type solid)
			)
			(layer "F.Fab")
		)
		(fp_line
			(start -2.46 -1.93)
			(end 2.439 -1.93)
			(stroke
				(width 0.15)
				(type solid)
			)
			(layer "F.Fab")
		)
		(fp_line
			(start 2.439 -1.93)
			(end 2.439 1.969)
			(stroke
				(width 0.15)
				(type solid)
			)
			(layer "F.Fab")
		)
		(pad "1" smd rect
			(at -1.915 2.467 270)
			(size 0.6 2)
			(layers "F.Cu" "F.Mask" "F.Paste")
			(net 85 "unconnected-(U4-NC-Pad1)")
			(pinfunction "NC")
			(pintype "no_connect")
		)
		(pad "2" smd rect
			(at -0.652 2.467 270)
			(size 0.6 2)
			(layers "F.Cu" "F.Mask" "F.Paste")
			(net 51 "Net-(U4-A1)")
			(pinfunction "A1")
			(pintype "input")
		)
		(pad "3" smd rect
			(at 0.618 2.467 270)
			(size 0.6 2)
			(layers "F.Cu" "F.Mask" "F.Paste")
			(net 52 "Net-(U4-A2)")
			(pinfunction "A2")
			(pintype "input")
		)
		(pad "4" smd rect
			(at 1.89 2.467 270)
			(size 0.6 2)
			(layers "F.Cu" "F.Mask" "F.Paste")
			(net 1 "GND")
			(pinfunction "VSS")
			(pintype "power_in")
		)
		(pad "5" smd rect
			(at 1.89 -2.431 270)
			(size 0.6 2)
			(layers "F.Cu" "F.Mask" "F.Paste")
			(net 9 "I2C_1_SDA")
			(pinfunction "SDA")
			(pintype "bidirectional")
		)
		(pad "6" smd rect
			(at 0.618 -2.431 270)
			(size 0.6 2)
			(layers "F.Cu" "F.Mask" "F.Paste")
			(net 8 "I2C_1_SCL")
			(pinfunction "SCL")
			(pintype "input")
		)
		(pad "7" smd rect
			(at -0.652 -2.431 270)
			(size 0.6 2)
			(layers "F.Cu" "F.Mask" "F.Paste")
			(net 15 "/FRAM_WP")
			(pinfunction "WP")
			(pintype "input")
		)
		(pad "8" smd rect
			(at -1.915 -2.431 270)
			(size 0.6 2)
			(layers "F.Cu" "F.Mask" "F.Paste")
			(net 2 "+3V3")
			(pinfunction "VDD")
			(pintype "power_in")
		)
	)
	(footprint "antmicro-footprints:SOT-23-3"
		(layer "F.Cu")
		(at 172.55 133.5 180)
		(property "Reference" "U2"
			(at 1.35 1.3 90)
			(layer "F.SilkS")
			(effects
				(font
					(size 0.65 0.65)
					(thickness 0.15)
				)
			)
		)
		(property "Value" "AP7370-33SA-7"
			(at 0.025 3.25 0)
			(layer "F.Fab")
			(effects
				(font
					(size 1 1)
					(thickness 0.15)
				)
			)
		)
		(property "Description" "Voltage regulator"
			(at 0 0 180)
			(layer "F.Fab")
			(hide yes)
			(effects
				(font
					(size 1.27 1.27)
					(thickness 0.15)
				)
			)
		)
		(property "Author" "Antmicro"
			(at 345.1 267 0)
			(layer "F.Fab")
			(hide yes)
			(effects
				(font
					(size 1 1)
					(thickness 0.15)
				)
			)
		)
		(property "License" "Apache-2.0"
			(at 345.1 267 0)
			(layer "F.Fab")
			(hide yes)
			(effects
				(font
					(size 1 1)
					(thickness 0.15)
				)
			)
		)
		(property "MPN" "AP7370-33SA-7"
			(at 345.1 267 0)
			(layer "F.Fab")
			(hide yes)
			(effects
				(font
					(size 1 1)
					(thickness 0.15)
				)
			)
		)
		(property "Manufacturer" "Diodes Incorporated"
			(at 345.1 267 0)
			(layer "F.Fab")
			(hide yes)
			(effects
				(font
					(size 1 1)
					(thickness 0.15)
				)
			)
		)
		(sheetfile "environment-sensor.kicad_sch")
		(attr smd)
		(fp_line
			(start 0.7 1.5)
			(end -0.7 1.5)
			(stroke
				(width 0.15)
				(type solid)
			)
			(layer "F.SilkS")
		)
		(fp_line
			(start 0.7 0.4)
			(end 0.7 1.5)
			(stroke
				(width 0.15)
				(type solid)
			)
			(layer "F.SilkS")
		)
		(fp_line
			(start 0.7 -0.4)
			(end 0.7 -1.5)
			(stroke
				(width 0.15)
				(type solid)
			)
			(layer "F.SilkS")
		)
		(fp_line
			(start 0.7 -1.5)
			(end -0.7 -1.5)
			(stroke
				(width 0.15)
				(type solid)
			)
			(layer "F.SilkS")
		)
		(fp_line
			(start -0.7 1.5)
			(end -0.7 1.35)
			(stroke
				(width 0.15)
				(type solid)
			)
			(layer "F.SilkS")
		)
		(fp_line
			(start -0.85 -1.35)
			(end -0.7 -1.5)
			(stroke
				(width 0.15)
				(type solid)
			)
			(layer "F.SilkS")
		)
		(fp_line
			(start -1.45 -1.35)
			(end -0.85 -1.35)
			(stroke
				(width 0.15)
				(type solid)
			)
			(layer "F.SilkS")
		)
		(fp_line
			(start 1.75 0.45)
			(end 0.85 0.45)
			(stroke
				(width 0.05)
				(type solid)
			)
			(layer "F.CrtYd")
		)
		(fp_line
			(start 1.75 -0.45)
			(end 1.75 0.45)
			(stroke
				(width 0.05)
				(type solid)
			)
			(layer "F.CrtYd")
		)
		(fp_line
			(start 0.85 1.65)
			(end -0.85 1.65)
			(stroke
				(width 0.05)
				(type solid)
			)
			(layer "F.CrtYd")
		)
		(fp_line
			(start 0.85 0.45)
			(end 0.85 1.65)
			(stroke
				(width 0.05)
				(type solid)
			)
			(layer "F.CrtYd")
		)
		(fp_line
			(start 0.825 -0.45)
			(end 1.75 -0.45)
			(stroke
				(width 0.05)
				(type solid)
			)
			(layer "F.CrtYd")
		)
		(fp_line
			(start 0.825 -1.6)
			(end 0.825 -0.45)
			(stroke
				(width 0.05)
				(type solid)
			)
			(layer "F.CrtYd")
		)
		(fp_line
			(start -0.85 1.65)
			(end -0.85 1.4)
			(stroke
				(width 0.05)
				(type solid)
			)
			(layer "F.CrtYd")
		)
		(fp_line
			(start -0.85 1.4)
			(end -1.75 1.4)
			(stroke
				(width 0.05)
				(type solid)
			)
			(layer "F.CrtYd")
		)
		(fp_line
			(start -0.85 0.5)
			(end -0.85 -0.5)
			(stroke
				(width 0.05)
				(type solid)
			)
			(layer "F.CrtYd")
		)
		(fp_line
			(start -0.85 -0.5)
			(end -1.75 -0.5)
			(stroke
				(width 0.05)
				(type solid)
			)
			(layer "F.CrtYd")
		)
		(fp_line
			(start -0.9 -1.4)
			(end -1.75 -1.4)
			(stroke
				(width 0.05)
				(type solid)
			)
			(layer "F.CrtYd")
		)
		(fp_line
			(start -0.9 -1.6)
			(end 0.825 -1.6)
			(stroke
				(width 0.05)
				(type solid)
			)
			(layer "F.CrtYd")
		)
		(fp_line
			(start -0.9 -1.6)
			(end -0.9 -1.4)
			(stroke
				(width 0.05)
				(type solid)
			)
			(layer "F.CrtYd")
		)
		(fp_line
			(start -1.75 1.4)
			(end -1.75 0.5)
			(stroke
				(width 0.05)
				(type solid)
			)
			(layer "F.CrtYd")
		)
		(fp_line
			(start -1.75 0.5)
			(end -0.85 0.5)
			(stroke
				(width 0.05)
				(type solid)
			)
			(layer "F.CrtYd")
		)
		(fp_line
			(start -1.75 -0.5)
			(end -1.75 -1.4)
			(stroke
				(width 0.05)
				(type solid)
			)
			(layer "F.CrtYd")
		)
		(fp_line
			(start 0.688 1.519)
			(end 0.688 -1.52)
			(stroke
				(width 0.15)
				(type solid)
			)
			(layer "F.Fab")
		)
		(fp_line
			(start -0.437 -1.526)
			(end 0.688 -1.526)
			(stroke
				(width 0.15)
				(type solid)
			)
			(layer "F.Fab")
		)
		(fp_line
			(start -0.437 -1.526)
			(end -0.712 -1.325)
			(stroke
				(width 0.15)
				(type solid)
			)
			(layer "F.Fab")
		)
		(fp_line
			(start -0.712 1.519)
			(end 0.688 1.519)
			(stroke
				(width 0.15)
				(type solid)
			)
			(layer "F.Fab")
		)
		(fp_line
			(start -0.712 -1.325)
			(end -0.712 1.523)
			(stroke
				(width 0.15)
				(type solid)
			)
			(layer "F.Fab")
		)
		(fp_text user "${REFERENCE}"
			(at -0.125 0.15 0)
			(layer "F.Fab")
			(effects
				(font
					(size 0.25 0.25)
					(thickness 0.05)
				)
			)
		)
		(pad "1" smd roundrect
			(at -1.1 -0.951 180)
			(size 1 0.6)
			(layers "F.Cu" "F.Mask" "F.Paste")
			(roundrect_rratio 0.15)
			(net 1 "GND")
			(pinfunction "GND")
			(pintype "power_in")
		)
		(pad "2" smd roundrect
			(at -1.1 0.949 180)
			(size 1 0.6)
			(layers "F.Cu" "F.Mask" "F.Paste")
			(roundrect_rratio 0.15)
			(net 2 "+3V3")
			(pinfunction "VOUT")
			(pintype "power_out")
		)
		(pad "3" smd roundrect
			(at 1.1 -0.0005 180)
			(size 1 0.6)
			(layers "F.Cu" "F.Mask" "F.Paste")
			(roundrect_rratio 0.15)
			(net 26 "+5V")
			(pinfunction "VIN")
			(pintype "power_in")
		)
	)
	(footprint "antmicro-footprints:C_0402_1005Metric"
		(layer "F.Cu")
		(at 182.925 135.9)
		(descr "Capacitor SMD 0402")
		(tags "capacitor SMD 0402")
		(property "Reference" "C21"
			(at 3.175 0.35 0)
			(layer "F.SilkS")
			(effects
				(font
					(size 0.7 0.7)
					(thickness 0.15)
				)
				(justify right bottom)
			)
		)
		(property "Value" "C_10p_0402"
			(at 0 1.4 0)
			(layer "F.Fab")
			(effects
				(font
					(size 0.7 0.7)
					(thickness 0.15)
				)
				(justify left bottom)
			)
		)
		(property "Description" "SMD Multilayer Ceramic Capacitor, 10 pF, 50 V, 0402 [1005 Metric], ± 2%, C0G / NP0, GCM"
			(at 0 0 0)
			(layer "F.Fab")
			(hide yes)
			(effects
				(font
					(size 1.27 1.27)
					(thickness 0.15)
				)
			)
		)
		(property "Author" "Antmicro"
			(at 0 0 0)
			(layer "F.Fab")
			(hide yes)
			(effects
				(font
					(size 1 1)
					(thickness 0.15)
				)
			)
		)
		(property "Dielectric" "C0G"
			(at 0 0 0)
			(layer "F.Fab")
			(hide yes)
			(effects
				(font
					(size 1 1)
					(thickness 0.15)
				)
			)
		)
		(property "License" "Apache-2.0"
			(at 0 0 0)
			(layer "F.Fab")
			(hide yes)
			(effects
				(font
					(size 1 1)
					(thickness 0.15)
				)
			)
		)
		(property "MPN" "GCM1555C1H100GA16D"
			(at 0 0 0)
			(layer "F.Fab")
			(hide yes)
			(effects
				(font
					(size 1 1)
					(thickness 0.15)
				)
			)
		)
		(property "Manufacturer" "Murata"
			(at 0 0 0)
			(layer "F.Fab")
			(hide yes)
			(effects
				(font
					(size 1 1)
					(thickness 0.15)
				)
			)
		)
		(property "Public" "False"
			(at 0 0 0)
			(layer "F.Fab")
			(hide yes)
			(effects
				(font
					(size 1 1)
					(thickness 0.15)
				)
			)
		)
		(property "Val" "10p"
			(at 0 0 0)
			(layer "F.Fab")
			(hide yes)
			(effects
				(font
					(size 1 1)
					(thickness 0.15)
				)
			)
		)
		(property "Voltage" "50V"
			(at 0 0 0)
			(layer "F.Fab")
			(hide yes)
			(effects
				(font
					(size 1 1)
					(thickness 0.15)
				)
			)
		)
		(sheetfile "environment-sensor.kicad_sch")
		(attr smd)
		(fp_rect
			(start -0.925 -0.47)
			(end 0.925 0.47)
			(stroke
				(width 0.05)
				(type default)
			)
			(fill no)
			(layer "F.CrtYd")
		)
		(fp_line
			(start -0.494 -0.25)
			(end 0.504 -0.25)
			(stroke
				(width 0.15)
				(type solid)
			)
			(layer "F.Fab")
		)
		(fp_line
			(start -0.494 0.248)
			(end -0.494 -0.25)
			(stroke
				(width 0.15)
				(type solid)
			)
			(layer "F.Fab")
		)
		(fp_line
			(start 0.504 -0.25)
			(end 0.504 0.248)
			(stroke
				(width 0.15)
				(type solid)
			)
			(layer "F.Fab")
		)
		(fp_line
			(start 0.504 0.248)
			(end -0.494 0.248)
			(stroke
				(width 0.15)
				(type solid)
			)
			(layer "F.Fab")
		)
		(pad "1" smd roundrect
			(at -0.48 0)
			(size 0.59 0.64)
			(layers "F.Cu" "F.Mask" "F.Paste")
			(roundrect_rratio 0.25)
			(net 1 "GND")
			(pintype "passive")
		)
		(pad "2" smd roundrect
			(at 0.48 0)
			(size 0.59 0.64)
			(layers "F.Cu" "F.Mask" "F.Paste")
			(roundrect_rratio 0.25)
			(net 31 "Net-(U3-PF1-OSC_OUT)")
			(pintype "passive")
		)
	)
	(footprint "antmicro-footprints:R_0402_1005Metric"
		(layer "F.Cu")
		(at 182.736 121.6625 180)
		(descr "Resistor SMD 0402")
		(tags "resistor SMD 0402")
		(property "Reference" "R33"
			(at 3.136 -0.3595 0)
			(layer "F.SilkS")
			(effects
				(font
					(size 0.7 0.7)
					(thickness 0.15)
				)
				(justify left bottom)
			)
		)
		(property "Value" "R_100k_0402"
			(at 0 1.4 180)
			(layer "F.Fab")
			(effects
				(font
					(size 0.7 0.7)
					(thickness 0.15)
				)
				(justify left bottom)
			)
		)
		(property "Description" "SMD Chip Resistor, 100 kohm, ± 1%, 62.5 mW, 0402 [1005 Metric], Thick Film, General Purpose"
			(at 0 0 180)
			(layer "F.Fab")
			(hide yes)
			(effects
				(font
					(size 1.27 1.27)
					(thickness 0.15)
				)
			)
		)
		(property "Author" "Antmicro"
			(at 365.472 243.325 0)
			(layer "F.Fab")
			(hide yes)
			(effects
				(font
					(size 1 1)
					(thickness 0.15)
				)
			)
		)
		(property "License" "Apache-2.0"
			(at 365.472 243.325 0)
			(layer "F.Fab")
			(hide yes)
			(effects
				(font
					(size 1 1)
					(thickness 0.15)
				)
			)
		)
		(property "MPN" "CR0402-FX-1003GLF"
			(at 365.472 243.325 0)
			(layer "F.Fab")
			(hide yes)
			(effects
				(font
					(size 1 1)
					(thickness 0.15)
				)
			)
		)
		(property "Manufacturer" "Bourns"
			(at 365.472 243.325 0)
			(layer "F.Fab")
			(hide yes)
			(effects
				(font
					(size 1 1)
					(thickness 0.15)
				)
			)
		)
		(property "Public" "False"
			(at 365.472 243.325 0)
			(layer "F.Fab")
			(hide yes)
			(effects
				(font
					(size 1 1)
					(thickness 0.15)
				)
			)
		)
		(property "Tolerance" "1%"
			(at 365.472 243.325 0)
			(layer "F.Fab")
			(hide yes)
			(effects
				(font
					(size 1 1)
					(thickness 0.15)
				)
			)
		)
		(property "Val" "100k"
			(at 365.472 243.325 0)
			(layer "F.Fab")
			(hide yes)
			(effects
				(font
					(size 1 1)
					(thickness 0.15)
				)
			)
		)
		(sheetfile "environment-sensor.kicad_sch")
		(attr smd exclude_from_pos_files exclude_from_bom dnp)
		(fp_rect
			(start -0.925 -0.47)
			(end 0.925 0.47)
			(stroke
				(width 0.05)
				(type default)
			)
			(fill no)
			(layer "F.CrtYd")
		)
		(fp_rect
			(start -0.5 -0.25)
			(end 0.5 0.25)
			(stroke
				(width 0.15)
				(type solid)
			)
			(fill no)
			(layer "F.Fab")
		)
		(pad "1" smd roundrect
			(at -0.48 0 180)
			(size 0.59 0.64)
			(layers "F.Cu" "F.Mask" "F.Paste")
			(roundrect_rratio 0.25)
			(net 52 "Net-(U4-A2)")
			(pintype "passive")
		)
		(pad "2" smd roundrect
			(at 0.48 0 180)
			(size 0.59 0.64)
			(layers "F.Cu" "F.Mask" "F.Paste")
			(roundrect_rratio 0.25)
			(net 2 "+3V3")
			(pintype "passive")
		)
	)
	(footprint "antmicro-footprints:C_0402_1005Metric"
		(layer "F.Cu")
		(at 201.25 115.85 90)
		(descr "Capacitor SMD 0402")
		(tags "capacitor SMD 0402")
		(property "Reference" "C25"
			(at 1.06 -1.3 180)
			(layer "F.SilkS")
			(effects
				(font
					(size 0.7 0.7)
					(thickness 0.15)
				)
				(justify left bottom)
			)
		)
		(property "Value" "C_100n_0402"
			(at 0 1.4 90)
			(layer "F.Fab")
			(effects
				(font
					(size 0.7 0.7)
					(thickness 0.15)
				)
				(justify left bottom)
			)
		)
		(property "Description" "SMD Multilayer Ceramic Capacitor, 0.1 µF, 50 V, 0402 [1005 Metric], ± 10%, X5R, GRM Series"
			(at 0 0 90)
			(layer "F.Fab")
			(hide yes)
			(effects
				(font
					(size 1.27 1.27)
					(thickness 0.15)
				)
			)
		)
		(property "Author" "Antmicro"
			(at 317.1 -85.4 0)
			(layer "F.Fab")
			(hide yes)
			(effects
				(font
					(size 1 1)
					(thickness 0.15)
				)
			)
		)
		(property "Dielectric" "X5R"
			(at 317.1 -85.4 0)
			(layer "F.Fab")
			(hide yes)
			(effects
				(font
					(size 1 1)
					(thickness 0.15)
				)
			)
		)
		(property "License" "Apache-2.0"
			(at 317.1 -85.4 0)
			(layer "F.Fab")
			(hide yes)
			(effects
				(font
					(size 1 1)
					(thickness 0.15)
				)
			)
		)
		(property "MPN" "GRM155R61H104KE14D"
			(at 317.1 -85.4 0)
			(layer "F.Fab")
			(hide yes)
			(effects
				(font
					(size 1 1)
					(thickness 0.15)
				)
			)
		)
		(property "Manufacturer" "Murata"
			(at 317.1 -85.4 0)
			(layer "F.Fab")
			(hide yes)
			(effects
				(font
					(size 1 1)
					(thickness 0.15)
				)
			)
		)
		(property "Public" "False"
			(at 317.1 -85.4 0)
			(layer "F.Fab")
			(hide yes)
			(effects
				(font
					(size 1 1)
					(thickness 0.15)
				)
			)
		)
		(property "Val" "100n"
			(at 317.1 -85.4 0)
			(layer "F.Fab")
			(hide yes)
			(effects
				(font
					(size 1 1)
					(thickness 0.15)
				)
			)
		)
		(property "Voltage" "50V"
			(at 317.1 -85.4 0)
			(layer "F.Fab")
			(hide yes)
			(effects
				(font
					(size 1 1)
					(thickness 0.15)
				)
			)
		)
		(sheetfile "environment-sensor.kicad_sch")
		(attr smd)
		(fp_rect
			(start -0.925 -0.47)
			(end 0.925 0.47)
			(stroke
				(width 0.05)
				(type default)
			)
			(fill no)
			(layer "F.CrtYd")
		)
		(fp_line
			(start 0.504 -0.25)
			(end 0.504 0.248)
			(stroke
				(width 0.15)
				(type solid)
			)
			(layer "F.Fab")
		)
		(fp_line
			(start -0.494 -0.25)
			(end 0.504 -0.25)
			(stroke
				(width 0.15)
				(type solid)
			)
			(layer "F.Fab")
		)
		(fp_line
			(start 0.504 0.248)
			(end -0.494 0.248)
			(stroke
				(width 0.15)
				(type solid)
			)
			(layer "F.Fab")
		)
		(fp_line
			(start -0.494 0.248)
			(end -0.494 -0.25)
			(stroke
				(width 0.15)
				(type solid)
			)
			(layer "F.Fab")
		)
		(pad "1" smd roundrect
			(at -0.48 0 90)
			(size 0.59 0.64)
			(layers "F.Cu" "F.Mask" "F.Paste")
			(roundrect_rratio 0.25)
			(net 2 "+3V3")
			(pintype "passive")
		)
		(pad "2" smd roundrect
			(at 0.48 0 90)
			(size 0.59 0.64)
			(layers "F.Cu" "F.Mask" "F.Paste")
			(roundrect_rratio 0.25)
			(net 1 "GND")
			(pintype "passive")
		)
	)
	(footprint "antmicro-footprints:R_0402_1005Metric"
		(layer "F.Cu")
		(at 182.729 118.5625 180)
		(descr "Resistor SMD 0402")
		(tags "resistor SMD 0402")
		(property "Reference" "R31"
			(at 3.129 -0.3635 0)
			(layer "F.SilkS")
			(effects
				(font
					(size 0.7 0.7)
					(thickness 0.15)
				)
				(justify left bottom)
			)
		)
		(property "Value" "R_100k_0402"
			(at 0 1.4 180)
			(layer "F.Fab")
			(effects
				(font
					(size 0.7 0.7)
					(thickness 0.15)
				)
				(justify left bottom)
			)
		)
		(property "Description" "SMD Chip Resistor, 100 kohm, ± 1%, 62.5 mW, 0402 [1005 Metric], Thick Film, General Purpose"
			(at 0 0 180)
			(layer "F.Fab")
			(hide yes)
			(effects
				(font
					(size 1.27 1.27)
					(thickness 0.15)
				)
			)
		)
		(property "Author" "Antmicro"
			(at 365.458 237.125 0)
			(layer "F.Fab")
			(hide yes)
			(effects
				(font
					(size 1 1)
					(thickness 0.15)
				)
			)
		)
		(property "License" "Apache-2.0"
			(at 365.458 237.125 0)
			(layer "F.Fab")
			(hide yes)
			(effects
				(font
					(size 1 1)
					(thickness 0.15)
				)
			)
		)
		(property "MPN" "CR0402-FX-1003GLF"
			(at 365.458 237.125 0)
			(layer "F.Fab")
			(hide yes)
			(effects
				(font
					(size 1 1)
					(thickness 0.15)
				)
			)
		)
		(property "Manufacturer" "Bourns"
			(at 365.458 237.125 0)
			(layer "F.Fab")
			(hide yes)
			(effects
				(font
					(size 1 1)
					(thickness 0.15)
				)
			)
		)
		(property "Public" "False"
			(at 365.458 237.125 0)
			(layer "F.Fab")
			(hide yes)
			(effects
				(font
					(size 1 1)
					(thickness 0.15)
				)
			)
		)
		(property "Tolerance" "1%"
			(at 365.458 237.125 0)
			(layer "F.Fab")
			(hide yes)
			(effects
				(font
					(size 1 1)
					(thickness 0.15)
				)
			)
		)
		(property "Val" "100k"
			(at 365.458 237.125 0)
			(layer "F.Fab")
			(hide yes)
			(effects
				(font
					(size 1 1)
					(thickness 0.15)
				)
			)
		)
		(sheetfile "environment-sensor.kicad_sch")
		(attr smd exclude_from_pos_files exclude_from_bom dnp)
		(fp_rect
			(start -0.925 -0.47)
			(end 0.925 0.47)
			(stroke
				(width 0.05)
				(type default)
			)
			(fill no)
			(layer "F.CrtYd")
		)
		(fp_rect
			(start -0.5 -0.25)
			(end 0.5 0.25)
			(stroke
				(width 0.15)
				(type solid)
			)
			(fill no)
			(layer "F.Fab")
		)
		(pad "1" smd roundrect
			(at -0.48 0 180)
			(size 0.59 0.64)
			(layers "F.Cu" "F.Mask" "F.Paste")
			(roundrect_rratio 0.25)
			(net 51 "Net-(U4-A1)")
			(pintype "passive")
		)
		(pad "2" smd roundrect
			(at 0.48 0 180)
			(size 0.59 0.64)
			(layers "F.Cu" "F.Mask" "F.Paste")
			(roundrect_rratio 0.25)
			(net 2 "+3V3")
			(pintype "passive")
		)
	)
	(footprint "antmicro-footprints:LED_0603_1608Metric_G"
		(layer "F.Cu")
		(at 172.15 138.7)
		(descr "LED SMD 0603 Green")
		(tags "LED SMD 0603 Green")
		(property "Reference" "LD1"
			(at 26.6 0.9 0)
			(layer "F.SilkS")
			(effects
				(font
					(size 0.7 0.7)
					(thickness 0.15)
				)
				(justify left bottom)
			)
		)
		(property "Value" "LED_G_0603_KP-1608ZGC"
			(at 0 1.6 0)
			(layer "F.Fab")
			(effects
				(font
					(size 0.7 0.7)
					(thickness 0.15)
				)
				(justify left bottom)
			)
		)
		(property "Description" "LED, Green, SMD, 0603, 20 mA, 3.3 V, 525 nm"
			(at 0 0 0)
			(layer "F.Fab")
			(hide yes)
			(effects
				(font
					(size 1.27 1.27)
					(thickness 0.15)
				)
			)
		)
		(property "Author" "Antmicro"
			(at 0 0 0)
			(layer "F.Fab")
			(hide yes)
			(effects
				(font
					(size 1 1)
					(thickness 0.15)
				)
			)
		)
		(property "Color" "Green"
			(at 0 0 0)
			(layer "F.Fab")
			(hide yes)
			(effects
				(font
					(size 1 1)
					(thickness 0.15)
				)
			)
		)
		(property "License" "Apache-2.0"
			(at 0 0 0)
			(layer "F.Fab")
			(hide yes)
			(effects
				(font
					(size 1 1)
					(thickness 0.15)
				)
			)
		)
		(property "MPN" "KP-1608ZGC"
			(at 0 0 0)
			(layer "F.Fab")
			(hide yes)
			(effects
				(font
					(size 1 1)
					(thickness 0.15)
				)
			)
		)
		(property "Manufacturer" "Kingbright"
			(at 0 0 0)
			(layer "F.Fab")
			(hide yes)
			(effects
				(font
					(size 1 1)
					(thickness 0.15)
				)
			)
		)
		(property "Public" "False"
			(at 0 0 0)
			(layer "F.Fab")
			(hide yes)
			(effects
				(font
					(size 1 1)
					(thickness 0.15)
				)
			)
		)
		(sheetfile "environment-sensor.kicad_sch")
		(attr smd)
		(fp_line
			(start -1.18 -0.319)
			(end -1.18 0.321)
			(stroke
				(width 0.15)
				(type solid)
			)
			(layer "F.SilkS")
		)
		(fp_line
			(start -0.094672 0.001008)
			(end -0.24 0.001008)
			(stroke
				(width 0.1)
				(type solid)
			)
			(layer "F.SilkS")
		)
		(fp_line
			(start -0.094672 0.001008)
			(end 0.105328 -0.198992)
			(stroke
				(width 0.1)
				(type solid)
			)
			(layer "F.SilkS")
		)
		(fp_line
			(start -0.094672 0.201008)
			(end -0.094672 -0.198992)
			(stroke
				(width 0.1)
				(type solid)
			)
			(layer "F.SilkS")
		)
		(fp_line
			(start 0.105328 0.001008)
			(end 0.24 0.001)
			(stroke
				(width 0.1)
				(type solid)
			)
			(layer "F.SilkS")
		)
		(fp_line
			(start 0.105328 0.201008)
			(end -0.094672 0.001008)
			(stroke
				(width 0.1)
				(type solid)
			)
			(layer "F.SilkS")
		)
		(fp_line
			(start 0.105328 0.201008)
			(end 0.105328 -0.198992)
			(stroke
				(width 0.1)
				(type solid)
			)
			(layer "F.SilkS")
		)
		(fp_line
			(start 0.22 -0.35)
			(end -0.22 -0.35)
			(stroke
				(width 0.15)
				(type solid)
			)
			(layer "F.SilkS")
		)
		(fp_line
			(start 0.22 0.35)
			(end -0.22 0.35)
			(stroke
				(width 0.15)
				(type solid)
			)
			(layer "F.SilkS")
		)
		(fp_rect
			(start 1.25 0.65)
			(end -1.25 -0.65)
			(stroke
				(width 0.05)
				(type solid)
			)
			(fill no)
			(layer "F.CrtYd")
		)
		(fp_line
			(start -0.199 -0.202)
			(end -0.199 0.1)
			(stroke
				(width 0.15)
				(type solid)
			)
			(layer "F.Fab")
		)
		(fp_line
			(start -0.199 0)
			(end -0.597 0)
			(stroke
				(width 0.15)
				(type solid)
			)
			(layer "F.Fab")
		)
		(fp_line
			(start -0.199 0.2)
			(end -0.199 0.1)
			(stroke
				(width 0.15)
				(type solid)
			)
			(layer "F.Fab")
		)
		(fp_line
			(start -0.101 0)
			(end 0.201 0.2)
			(stroke
				(width 0.15)
				(type solid)
			)
			(layer "F.Fab")
		)
		(fp_line
			(start 0.201 -0.202)
			(end -0.101 0)
			(stroke
				(width 0.15)
				(type solid)
			)
			(layer "F.Fab")
		)
		(fp_line
			(start 0.201 0)
			(end 0.201 -0.202)
			(stroke
				(width 0.15)
				(type solid)
			)
			(layer "F.Fab")
		)
		(fp_line
			(start 0.201 0.2)
			(end 0.201 0)
			(stroke
				(width 0.15)
				(type solid)
			)
			(layer "F.Fab")
		)
		(fp_line
			(start 0.599 0)
			(end 0.201 0)
			(stroke
				(width 0.15)
				(type solid)
			)
			(layer "F.Fab")
		)
		(fp_rect
			(start 0.848 0.4)
			(end -0.85 -0.402)
			(stroke
				(width 0.15)
				(type solid)
			)
			(fill no)
			(layer "F.Fab")
		)
		(pad "1" smd roundrect
			(at -0.7 0 180)
			(size 0.8 1)
			(layers "F.Cu" "F.Mask" "F.Paste")
			(roundrect_rratio 0.2)
			(net 26 "+5V")
			(pinfunction "C")
			(pintype "passive")
		)
		(pad "2" smd roundrect
			(at 0.7 0 180)
			(size 0.8 1)
			(layers "F.Cu" "F.Mask" "F.Paste")
			(roundrect_rratio 0.2)
			(net 10 "Net-(LD1-A)")
			(pinfunction "A")
			(pintype "passive")
		)
	)
	(footprint "antmicro-footprints:C_0402_1005Metric"
		(layer "F.Cu")
		(at 194.05 138.4 -90)
		(descr "Capacitor SMD 0402")
		(tags "capacitor SMD 0402")
		(property "Reference" "C20"
			(at -15.757 9.2655 90)
			(layer "B.SilkS")
			(effects
				(font
					(size 0.7 0.7)
					(thickness 0.15)
				)
				(justify right bottom mirror)
			)
		)
		(property "Value" "C_2u2_0402"
			(at 0 1.4 90)
			(layer "F.Fab")
			(effects
				(font
					(size 0.7 0.7)
					(thickness 0.15)
				)
				(justify right bottom)
			)
		)
		(property "Description" "SMD Multilayer Ceramic Capacitor, 2.2 µF, 10 V, 0402 [1005 Metric], ± 10%, X5R, C"
			(at 0 0 270)
			(layer "F.Fab")
			(hide yes)
			(effects
				(font
					(size 1.27 1.27)
					(thickness 0.15)
				)
			)
		)
		(property "Author" "Antmicro"
			(at 55.65 332.45 0)
			(layer "F.Fab")
			(hide yes)
			(effects
				(font
					(size 1 1)
					(thickness 0.15)
				)
			)
		)
		(property "Dielectric" ""
			(at 55.65 332.45 0)
			(layer "F.Fab")
			(hide yes)
			(effects
				(font
					(size 1 1)
					(thickness 0.15)
				)
			)
		)
		(property "License" "Apache-2.0"
			(at 55.65 332.45 0)
			(layer "F.Fab")
			(hide yes)
			(effects
				(font
					(size 1 1)
					(thickness 0.15)
				)
			)
		)
		(property "MPN" "C1005X5R1A225K050BC"
			(at 55.65 332.45 0)
			(layer "F.Fab")
			(hide yes)
			(effects
				(font
					(size 1 1)
					(thickness 0.15)
				)
			)
		)
		(property "Manufacturer" "TDK"
			(at 55.65 332.45 0)
			(layer "F.Fab")
			(hide yes)
			(effects
				(font
					(size 1 1)
					(thickness 0.15)
				)
			)
		)
		(property "Public" "False"
			(at 55.65 332.45 0)
			(layer "F.Fab")
			(hide yes)
			(effects
				(font
					(size 1 1)
					(thickness 0.15)
				)
			)
		)
		(property "Val" "2u2"
			(at 55.65 332.45 0)
			(layer "F.Fab")
			(hide yes)
			(effects
				(font
					(size 1 1)
					(thickness 0.15)
				)
			)
		)
		(property "Voltage" ""
			(at 55.65 332.45 0)
			(layer "F.Fab")
			(hide yes)
			(effects
				(font
					(size 1 1)
					(thickness 0.15)
				)
			)
		)
		(sheetfile "environment-sensor.kicad_sch")
		(attr smd)
		(fp_rect
			(start -0.925 -0.47)
			(end 0.925 0.47)
			(stroke
				(width 0.05)
				(type default)
			)
			(fill no)
			(layer "F.CrtYd")
		)
		(fp_line
			(start -0.494 0.248)
			(end -0.494 -0.25)
			(stroke
				(width 0.15)
				(type solid)
			)
			(layer "F.Fab")
		)
		(fp_line
			(start 0.504 0.248)
			(end -0.494 0.248)
			(stroke
				(width 0.15)
				(type solid)
			)
			(layer "F.Fab")
		)
		(fp_line
			(start -0.494 -0.25)
			(end 0.504 -0.25)
			(stroke
				(width 0.15)
				(type solid)
			)
			(layer "F.Fab")
		)
		(fp_line
			(start 0.504 -0.25)
			(end 0.504 0.248)
			(stroke
				(width 0.15)
				(type solid)
			)
			(layer "F.Fab")
		)
		(pad "1" smd roundrect
			(at -0.48 0 270)
			(size 0.59 0.64)
			(layers "F.Cu" "F.Mask" "F.Paste")
			(roundrect_rratio 0.25)
			(net 1 "GND")
			(pintype "passive")
		)
		(pad "2" smd roundrect
			(at 0.48 0 270)
			(size 0.59 0.64)
			(layers "F.Cu" "F.Mask" "F.Paste")
			(roundrect_rratio 0.25)
			(net 30 "Net-(U3-VDDA)")
			(pintype "passive")
		)
	)
	(footprint "antmicro-footprints:SOT-723"
		(layer "F.Cu")
		(at 202.35 128.25)
		(property "Reference" "D6"
			(at 0.35 -1.25 180)
			(layer "F.SilkS")
			(effects
				(font
					(size 0.65 0.65)
					(thickness 0.15)
				)
			)
		)
		(property "Value" "TPD2E009_SOT-9X3"
			(at -0.025 2.975 0)
			(layer "F.Fab")
			(effects
				(font
					(size 1 1)
					(thickness 0.15)
				)
			)
		)
		(property "Description" "TVS diode array, 8 kV, SOT-723, 5.5 V, 0.9 pF"
			(at 0 0 0)
			(layer "F.Fab")
			(hide yes)
			(effects
				(font
					(size 1.27 1.27)
					(thickness 0.15)
				)
			)
		)
		(property "Author" "Antmicro"
			(at 0 0 0)
			(layer "F.Fab")
			(hide yes)
			(effects
				(font
					(size 1 1)
					(thickness 0.15)
				)
			)
		)
		(property "License" "Apache-2.0"
			(at 0 0 0)
			(layer "F.Fab")
			(hide yes)
			(effects
				(font
					(size 1 1)
					(thickness 0.15)
				)
			)
		)
		(property "MPN" "TPD2E009DRTR"
			(at 0 0 0)
			(layer "F.Fab")
			(hide yes)
			(effects
				(font
					(size 1 1)
					(thickness 0.15)
				)
			)
		)
		(property "Manufacturer" "Texas Instruments"
			(at 0 0 0)
			(layer "F.Fab")
			(hide yes)
			(effects
				(font
					(size 1 1)
					(thickness 0.15)
				)
			)
		)
		(sheetfile "environment-sensor.kicad_sch")
		(attr smd)
		(fp_line
			(start -0.43 -0.1375)
			(end -0.43 0.1375)
			(stroke
				(width 0.15)
				(type solid)
			)
			(layer "F.SilkS")
		)
		(fp_line
			(start 0.43 -0.63)
			(end -0.2175 -0.63)
			(stroke
				(width 0.15)
				(type solid)
			)
			(layer "F.SilkS")
		)
		(fp_line
			(start 0.43 -0.23)
			(end 0.43 -0.63)
			(stroke
				(width 0.15)
				(type solid)
			)
			(layer "F.SilkS")
		)
		(fp_line
			(start 0.43 0.23)
			(end 0.43 0.63)
			(stroke
				(width 0.15)
				(type solid)
			)
			(layer "F.SilkS")
		)
		(fp_line
			(start 0.43 0.63)
			(end -0.22 0.63)
			(stroke
				(width 0.15)
				(type solid)
			)
			(layer "F.SilkS")
		)
		(fp_rect
			(start -0.83 -0.83)
			(end 0.83 0.83)
			(stroke
				(width 0.05)
				(type solid)
			)
			(fill no)
			(layer "F.CrtYd")
		)
		(fp_line
			(start -0.09 -0.53)
			(end -0.43 -0.19)
			(stroke
				(width 0.15)
				(type solid)
			)
			(layer "F.Fab")
		)
		(fp_line
			(start 0.424 -0.528)
			(end 0.424 0.524)
			(stroke
				(width 0.15)
				(type solid)
			)
			(layer "F.Fab")
		)
		(fp_line
			(start 0.424 0.524)
			(end -0.424 0.524)
			(stroke
				(width 0.15)
				(type solid)
			)
			(layer "F.Fab")
		)
		(fp_rect
			(start 0.424 0.524)
			(end -0.43 -0.528)
			(stroke
				(width 0.15)
				(type solid)
			)
			(fill no)
			(layer "F.Fab")
		)
		(fp_text user "${REFERENCE}"
			(at 0 0 0)
			(layer "F.Fab")
			(effects
				(font
					(size 0.2 0.2)
					(thickness 0.025)
				)
			)
		)
		(pad "1" smd rect
			(at -0.501 -0.401 270)
			(size 0.3 0.4)
			(layers "F.Cu" "F.Mask" "F.Paste")
			(net 8 "I2C_1_SCL")
			(pinfunction "1")
			(pintype "passive")
		)
		(pad "2" smd rect
			(at -0.501 0.399 270)
			(size 0.3 0.4)
			(layers "F.Cu" "F.Mask" "F.Paste")
			(net 9 "I2C_1_SDA")
			(pinfunction "2")
			(pintype "passive")
		)
		(pad "3" smd rect
			(at 0.499 -0.001 270)
			(size 0.3 0.4)
			(layers "F.Cu" "F.Mask" "F.Paste")
			(net 1 "GND")
			(pinfunction "3")
			(pintype "passive")
		)
	)
	(footprint "antmicro-footprints:C_0402_1005Metric"
		(layer "F.Cu")
		(at 192.95 138.4 90)
		(descr "Capacitor SMD 0402")
		(tags "capacitor SMD 0402")
		(property "Reference" "C19"
			(at 17.924 -9.0695 90)
			(layer "B.SilkS")
			(effects
				(font
					(size 0.7 0.7)
					(thickness 0.15)
				)
				(justify left bottom mirror)
			)
		)
		(property "Value" "C_100n_0402"
			(at 0 1.4 90)
			(layer "F.Fab")
			(effects
				(font
					(size 0.7 0.7)
					(thickness 0.15)
				)
				(justify left bottom)
			)
		)
		(property "Description" "SMD Multilayer Ceramic Capacitor, 0.1 µF, 50 V, 0402 [1005 Metric], ± 10%, X5R, GRM Series"
			(at 0 0 90)
			(layer "F.Fab")
			(hide yes)
			(effects
				(font
					(size 1.27 1.27)
					(thickness 0.15)
				)
			)
		)
		(property "Author" "Antmicro"
			(at 331.35 -54.55 0)
			(layer "F.Fab")
			(hide yes)
			(effects
				(font
					(size 1 1)
					(thickness 0.15)
				)
			)
		)
		(property "Dielectric" "X5R"
			(at 331.35 -54.55 0)
			(layer "F.Fab")
			(hide yes)
			(effects
				(font
					(size 1 1)
					(thickness 0.15)
				)
			)
		)
		(property "License" "Apache-2.0"
			(at 331.35 -54.55 0)
			(layer "F.Fab")
			(hide yes)
			(effects
				(font
					(size 1 1)
					(thickness 0.15)
				)
			)
		)
		(property "MPN" "GRM155R61H104KE14D"
			(at 331.35 -54.55 0)
			(layer "F.Fab")
			(hide yes)
			(effects
				(font
					(size 1 1)
					(thickness 0.15)
				)
			)
		)
		(property "Manufacturer" "Murata"
			(at 331.35 -54.55 0)
			(layer "F.Fab")
			(hide yes)
			(effects
				(font
					(size 1 1)
					(thickness 0.15)
				)
			)
		)
		(property "Public" "False"
			(at 331.35 -54.55 0)
			(layer "F.Fab")
			(hide yes)
			(effects
				(font
					(size 1 1)
					(thickness 0.15)
				)
			)
		)
		(property "Val" "100n"
			(at 331.35 -54.55 0)
			(layer "F.Fab")
			(hide yes)
			(effects
				(font
					(size 1 1)
					(thickness 0.15)
				)
			)
		)
		(property "Voltage" "50V"
			(at 331.35 -54.55 0)
			(layer "F.Fab")
			(hide yes)
			(effects
				(font
					(size 1 1)
					(thickness 0.15)
				)
			)
		)
		(sheetfile "environment-sensor.kicad_sch")
		(attr smd)
		(fp_rect
			(start -0.925 -0.47)
			(end 0.925 0.47)
			(stroke
				(width 0.05)
				(type default)
			)
			(fill no)
			(layer "F.CrtYd")
		)
		(fp_line
			(start 0.504 -0.25)
			(end 0.504 0.248)
			(stroke
				(width 0.15)
				(type solid)
			)
			(layer "F.Fab")
		)
		(fp_line
			(start -0.494 -0.25)
			(end 0.504 -0.25)
			(stroke
				(width 0.15)
				(type solid)
			)
			(layer "F.Fab")
		)
		(fp_line
			(start 0.504 0.248)
			(end -0.494 0.248)
			(stroke
				(width 0.15)
				(type solid)
			)
			(layer "F.Fab")
		)
		(fp_line
			(start -0.494 0.248)
			(end -0.494 -0.25)
			(stroke
				(width 0.15)
				(type solid)
			)
			(layer "F.Fab")
		)
		(pad "1" smd roundrect
			(at -0.48 0 90)
			(size 0.59 0.64)
			(layers "F.Cu" "F.Mask" "F.Paste")
			(roundrect_rratio 0.25)
			(net 30 "Net-(U3-VDDA)")
			(pintype "passive")
		)
		(pad "2" smd roundrect
			(at 0.48 0 90)
			(size 0.59 0.64)
			(layers "F.Cu" "F.Mask" "F.Paste")
			(roundrect_rratio 0.25)
			(net 1 "GND")
			(pintype "passive")
		)
	)
	(footprint "antmicro-footprints:TP_SMD_1mm"
		(layer "F.Cu")
		(at 198.761 136.042 -90)
		(property "Reference" "TP7"
			(at 0.258 -0.439 270)
			(layer "F.SilkS")
			(hide yes)
			(effects
				(font
					(size 0.7 0.7)
					(thickness 0.15)
				)
				(justify left bottom)
			)
		)
		(property "Value" "TP_1mm_SMD"
			(at 0 1.4 270)
			(layer "F.Fab")
			(effects
				(font
					(size 0.7 0.7)
					(thickness 0.15)
				)
				(justify left bottom)
			)
		)
		(property "Description" "Test point 1mm SMD"
			(at 0 0 270)
			(layer "F.Fab")
			(hide yes)
			(effects
				(font
					(size 1.27 1.27)
					(thickness 0.15)
				)
			)
		)
		(property "Author" "Antmicro"
			(at 62.719 334.803 0)
			(layer "F.Fab")
			(hide yes)
			(effects
				(font
					(size 1 1)
					(thickness 0.15)
				)
			)
		)
		(property "License" "Apache-2.0"
			(at 62.719 334.803 0)
			(layer "F.Fab")
			(hide yes)
			(effects
				(font
					(size 1 1)
					(thickness 0.15)
				)
			)
		)
		(property "MPN" ""
			(at 62.719 334.803 0)
			(layer "F.Fab")
			(hide yes)
			(effects
				(font
					(size 1 1)
					(thickness 0.15)
				)
			)
		)
		(property "Manufacturer" ""
			(at 62.719 334.803 0)
			(layer "F.Fab")
			(hide yes)
			(effects
				(font
					(size 1 1)
					(thickness 0.15)
				)
			)
		)
		(property "Public" "False"
			(at 62.719 334.803 0)
			(layer "F.Fab")
			(hide yes)
			(effects
				(font
					(size 1 1)
					(thickness 0.15)
				)
			)
		)
		(sheetfile "environment-sensor.kicad_sch")
		(attr exclude_from_pos_files)
		(pad "1" smd circle
			(at 0 0 270)
			(size 1 1)
			(layers "F.Cu" "F.Mask")
			(net 15 "/FRAM_WP")
			(pinfunction "1")
			(pintype "passive")
		)
	)
	(footprint "antmicro-footprints:Resonator_SMD_Abracon_ABM3B_5x3.2mm"
		(layer "F.Cu")
		(at 179.81 136.35 180)
		(descr "Abracon's CERAMIC SMD CRYSTAL")
		(tags "smd ceramic xtal")
		(property "Reference" "Y2"
			(at 0.21 3.15 0)
			(layer "F.SilkS")
			(effects
				(font
					(size 0.7 0.7)
					(thickness 0.15)
				)
				(justify right bottom)
			)
		)
		(property "Value" "Resonator_8MHz_ABM3B"
			(at 0 4.2 0)
			(layer "F.Fab")
			(effects
				(font
					(size 0.7 0.7)
					(thickness 0.15)
				)
				(justify right bottom)
			)
		)
		(property "Description" "Crystal, 8 MHz, SMT, 5mm x 3.2mm, 10 ppm, 10 pF, 10 ppm"
			(at 0 0 180)
			(layer "F.Fab")
			(hide yes)
			(effects
				(font
					(size 1.27 1.27)
					(thickness 0.15)
				)
			)
		)
		(property "Author" "Antmicro"
			(at 359.62 272.7 0)
			(layer "F.Fab")
			(hide yes)
			(effects
				(font
					(size 1 1)
					(thickness 0.15)
				)
			)
		)
		(property "License" "Apache-2.0"
			(at 359.62 272.7 0)
			(layer "F.Fab")
			(hide yes)
			(effects
				(font
					(size 1 1)
					(thickness 0.15)
				)
			)
		)
		(property "MPN" "ABM3B-8.000MHZ-10-1-U-T"
			(at 359.62 272.7 0)
			(layer "F.Fab")
			(hide yes)
			(effects
				(font
					(size 1 1)
					(thickness 0.15)
				)
			)
		)
		(property "Manufacturer" "Abracon"
			(at 359.62 272.7 0)
			(layer "F.Fab")
			(hide yes)
			(effects
				(font
					(size 1 1)
					(thickness 0.15)
				)
			)
		)
		(property "Public" "False"
			(at 359.62 272.7 0)
			(layer "F.Fab")
			(hide yes)
			(effects
				(font
					(size 1 1)
					(thickness 0.15)
				)
			)
		)
		(property "Val" "8 MHz"
			(at 359.62 272.7 0)
			(layer "F.Fab")
			(hide yes)
			(effects
				(font
					(size 1 1)
					(thickness 0.15)
				)
			)
		)
		(sheetfile "environment-sensor.kicad_sch")
		(attr smd)
		(fp_line
			(start 1.6 -0.783)
			(end 1.6 0.78)
			(stroke
				(width 0.15)
				(type solid)
			)
			(layer "F.SilkS")
		)
		(fp_line
			(start -0.282 2.499)
			(end 0.281 2.499)
			(stroke
				(width 0.15)
				(type solid)
			)
			(layer "F.SilkS")
		)
		(fp_line
			(start -0.282 -2.5)
			(end 0.281 -2.5)
			(stroke
				(width 0.15)
				(type solid)
			)
			(layer "F.SilkS")
		)
		(fp_line
			(start -1.601 -0.783)
			(end -1.601 0.78)
			(stroke
				(width 0.15)
				(type solid)
			)
			(layer "F.SilkS")
		)
		(fp_circle
			(center -1.8 -0.95)
			(end -1.75 -0.95)
			(stroke
				(width 0.15)
				(type solid)
			)
			(fill yes)
			(layer "F.SilkS")
		)
		(fp_rect
			(start -2.089 -3.175)
			(end 2.086 3.175)
			(stroke
				(width 0.05)
				(type solid)
			)
			(fill no)
			(layer "F.CrtYd")
		)
		(fp_line
			(start 1.6 2.499)
			(end -1.599 2.499)
			(stroke
				(width 0.15)
				(type solid)
			)
			(layer "F.Fab")
		)
		(fp_line
			(start 1.6 -2.5)
			(end 1.6 2.499)
			(stroke
				(width 0.15)
				(type solid)
			)
			(layer "F.Fab")
		)
		(fp_line
			(start -0.999 -2.5)
			(end 1.6 -2.5)
			(stroke
				(width 0.15)
				(type solid)
			)
			(layer "F.Fab")
		)
		(fp_line
			(start -1.599 2.499)
			(end -1.599 -1.901)
			(stroke
				(width 0.15)
				(type solid)
			)
			(layer "F.Fab")
		)
		(fp_line
			(start -1.599 -1.901)
			(end -0.999 -2.5)
			(stroke
				(width 0.15)
				(type solid)
			)
			(layer "F.Fab")
		)
		(pad "1" smd rect
			(at -1.2 -2 180)
			(size 1.2 1.8)
			(layers "F.Cu" "F.Mask" "F.Paste")
			(net 31 "Net-(U3-PF1-OSC_OUT)")
			(pintype "passive")
		)
		(pad "2" smd rect
			(at -1.2 1.999 180)
			(size 1.2 1.8)
			(layers "F.Cu" "F.Mask" "F.Paste")
			(net 1 "GND")
			(pinfunction "SH")
			(pintype "passive")
		)
		(pad "3" smd rect
			(at 1.199 1.999 180)
			(size 1.2 1.8)
			(layers "F.Cu" "F.Mask" "F.Paste")
			(net 33 "Net-(U3-PF0-OSC_IN)")
			(pintype "passive")
		)
		(pad "4" smd rect
			(at 1.199 -2 180)
			(size 1.2 1.8)
			(layers "F.Cu" "F.Mask" "F.Paste")
			(net 1 "GND")
			(pinfunction "SH")
			(pintype "passive")
		)
	)
	(footprint "antmicro-footprints:C_0402_1005Metric"
		(layer "F.Cu")
		(at 185.994 125.087 90)
		(descr "Capacitor SMD 0402")
		(tags "capacitor SMD 0402")
		(property "Reference" "C9"
			(at 7.838 9.132 0)
			(layer "F.SilkS")
			(effects
				(font
					(size 0.7 0.7)
					(thickness 0.15)
				)
				(justify left bottom)
			)
		)
		(property "Value" "C_4u7_0402"
			(at 0 1.4 90)
			(layer "F.Fab")
			(effects
				(font
					(size 0.7 0.7)
					(thickness 0.15)
				)
				(justify left bottom)
			)
		)
		(property "Description" "SMD Multilayer Ceramic Capacitor, 4.7 µF, 10 V, 0402 [1005 Metric], ± 20%, X5R, GRM Series"
			(at 0 0 90)
			(layer "F.Fab")
			(hide yes)
			(effects
				(font
					(size 1.27 1.27)
					(thickness 0.15)
				)
			)
		)
		(property "Author" "Antmicro"
			(at 311.081 -60.907 0)
			(layer "F.Fab")
			(hide yes)
			(effects
				(font
					(size 1 1)
					(thickness 0.15)
				)
			)
		)
		(property "Dielectric" ""
			(at 311.081 -60.907 0)
			(layer "F.Fab")
			(hide yes)
			(effects
				(font
					(size 1 1)
					(thickness 0.15)
				)
			)
		)
		(property "License" "Apache-2.0"
			(at 311.081 -60.907 0)
			(layer "F.Fab")
			(hide yes)
			(effects
				(font
					(size 1 1)
					(thickness 0.15)
				)
			)
		)
		(property "MPN" "GRM155R61A475MEAAD"
			(at 311.081 -60.907 0)
			(layer "F.Fab")
			(hide yes)
			(effects
				(font
					(size 1 1)
					(thickness 0.15)
				)
			)
		)
		(property "Manufacturer" "Murata"
			(at 311.081 -60.907 0)
			(layer "F.Fab")
			(hide yes)
			(effects
				(font
					(size 1 1)
					(thickness 0.15)
				)
			)
		)
		(property "Public" "False"
			(at 311.081 -60.907 0)
			(layer "F.Fab")
			(hide yes)
			(effects
				(font
					(size 1 1)
					(thickness 0.15)
				)
			)
		)
		(property "Val" "4u7"
			(at 311.081 -60.907 0)
			(layer "F.Fab")
			(hide yes)
			(effects
				(font
					(size 1 1)
					(thickness 0.15)
				)
			)
		)
		(property "Voltage" ""
			(at 311.081 -60.907 0)
			(layer "F.Fab")
			(hide yes)
			(effects
				(font
					(size 1 1)
					(thickness 0.15)
				)
			)
		)
		(sheetfile "environment-sensor.kicad_sch")
		(attr smd)
		(fp_rect
			(start -0.925 -0.47)
			(end 0.925 0.47)
			(stroke
				(width 0.05)
				(type default)
			)
			(fill no)
			(layer "F.CrtYd")
		)
		(fp_line
			(start 0.504 -0.25)
			(end 0.504 0.248)
			(stroke
				(width 0.15)
				(type solid)
			)
			(layer "F.Fab")
		)
		(fp_line
			(start -0.494 -0.25)
			(end 0.504 -0.25)
			(stroke
				(width 0.15)
				(type solid)
			)
			(layer "F.Fab")
		)
		(fp_line
			(start 0.504 0.248)
			(end -0.494 0.248)
			(stroke
				(width 0.15)
				(type solid)
			)
			(layer "F.Fab")
		)
		(fp_line
			(start -0.494 0.248)
			(end -0.494 -0.25)
			(stroke
				(width 0.15)
				(type solid)
			)
			(layer "F.Fab")
		)
		(pad "1" smd roundrect
			(at -0.48 0 90)
			(size 0.59 0.64)
			(layers "F.Cu" "F.Mask" "F.Paste")
			(roundrect_rratio 0.25)
			(net 1 "GND")
			(pintype "passive")
		)
		(pad "2" smd roundrect
			(at 0.48 0 90)
			(size 0.59 0.64)
			(layers "F.Cu" "F.Mask" "F.Paste")
			(roundrect_rratio 0.25)
			(net 2 "+3V3")
			(pintype "passive")
		)
	)
	(footprint "antmicro-footprints:R_0402_1005Metric"
		(layer "F.Cu")
		(at 182.925 134.8 180)
		(descr "Resistor SMD 0402")
		(tags "resistor SMD 0402")
		(property "Reference" "R25"
			(at -3.125 -0.4 0)
			(layer "F.SilkS")
			(effects
				(font
					(size 0.7 0.7)
					(thickness 0.15)
				)
				(justify right bottom)
			)
		)
		(property "Value" "R_1M_0402"
			(at -1.011843 1.772047 0)
			(layer "F.Fab")
			(effects
				(font
					(size 0.7 0.7)
					(thickness 0.15)
				)
				(justify right bottom)
			)
		)
		(property "Description" "SMD Chip Resistor, 1 Mohm, ± 1%, 62.5 mW, 0402 [1005 Metric], Thick Film, General Purpose"
			(at 0 0 180)
			(layer "F.Fab")
			(hide yes)
			(effects
				(font
					(size 1.27 1.27)
					(thickness 0.15)
				)
			)
		)
		(property "Author" "Antmicro"
			(at 365.85 269.6 0)
			(layer "F.Fab")
			(hide yes)
			(effects
				(font
					(size 1 1)
					(thickness 0.15)
				)
			)
		)
		(property "License" "Apache-2.0"
			(at 365.85 269.6 0)
			(layer "F.Fab")
			(hide yes)
			(effects
				(font
					(size 1 1)
					(thickness 0.15)
				)
			)
		)
		(property "MPN" "CR0402-FX-1004GLF"
			(at 365.85 269.6 0)
			(layer "F.Fab")
			(hide yes)
			(effects
				(font
					(size 1 1)
					(thickness 0.15)
				)
			)
		)
		(property "Manufacturer" "Bourns"
			(at 365.85 269.6 0)
			(layer "F.Fab")
			(hide yes)
			(effects
				(font
					(size 1 1)
					(thickness 0.15)
				)
			)
		)
		(property "Public" "False"
			(at 365.85 269.6 0)
			(layer "F.Fab")
			(hide yes)
			(effects
				(font
					(size 1 1)
					(thickness 0.15)
				)
			)
		)
		(property "Tolerance" "1%"
			(at 365.85 269.6 0)
			(layer "F.Fab")
			(hide yes)
			(effects
				(font
					(size 1 1)
					(thickness 0.15)
				)
			)
		)
		(property "Val" "1M"
			(at 365.85 269.6 0)
			(layer "F.Fab")
			(hide yes)
			(effects
				(font
					(size 1 1)
					(thickness 0.15)
				)
			)
		)
		(sheetfile "environment-sensor.kicad_sch")
		(attr smd exclude_from_pos_files exclude_from_bom dnp)
		(fp_rect
			(start -0.925 -0.47)
			(end 0.925 0.47)
			(stroke
				(width 0.05)
				(type default)
			)
			(fill no)
			(layer "F.CrtYd")
		)
		(fp_rect
			(start -0.5 -0.25)
			(end 0.5 0.25)
			(stroke
				(width 0.15)
				(type solid)
			)
			(fill no)
			(layer "F.Fab")
		)
		(pad "1" smd roundrect
			(at -0.48 0 180)
			(size 0.59 0.64)
			(layers "F.Cu" "F.Mask" "F.Paste")
			(roundrect_rratio 0.25)
			(net 31 "Net-(U3-PF1-OSC_OUT)")
			(pintype "passive")
		)
		(pad "2" smd roundrect
			(at 0.48 0 180)
			(size 0.59 0.64)
			(layers "F.Cu" "F.Mask" "F.Paste")
			(roundrect_rratio 0.25)
			(net 33 "Net-(U3-PF0-OSC_IN)")
			(pintype "passive")
		)
	)
	(footprint "antmicro-footprints:C_0402_1005Metric"
		(layer "F.Cu")
		(at 201.985 130.15 -90)
		(descr "Capacitor SMD 0402")
		(tags "capacitor SMD 0402")
		(property "Reference" "C13"
			(at 0.85 -0.415 90)
			(layer "F.SilkS")
			(effects
				(font
					(size 0.7 0.7)
					(thickness 0.15)
				)
				(justify right bottom)
			)
		)
		(property "Value" "C_100n_0402"
			(at 0 1.4 90)
			(layer "F.Fab")
			(effects
				(font
					(size 0.7 0.7)
					(thickness 0.15)
				)
				(justify right bottom)
			)
		)
		(property "Description" "SMD Multilayer Ceramic Capacitor, 0.1 µF, 50 V, 0402 [1005 Metric], ± 10%, X5R, GRM Series"
			(at 0 0 270)
			(layer "F.Fab")
			(hide yes)
			(effects
				(font
					(size 1.27 1.27)
					(thickness 0.15)
				)
			)
		)
		(property "Author" "Antmicro"
			(at 71.835 332.135 0)
			(layer "F.Fab")
			(hide yes)
			(effects
				(font
					(size 1 1)
					(thickness 0.15)
				)
			)
		)
		(property "Dielectric" "X5R"
			(at 71.835 332.135 0)
			(layer "F.Fab")
			(hide yes)
			(effects
				(font
					(size 1 1)
					(thickness 0.15)
				)
			)
		)
		(property "License" "Apache-2.0"
			(at 71.835 332.135 0)
			(layer "F.Fab")
			(hide yes)
			(effects
				(font
					(size 1 1)
					(thickness 0.15)
				)
			)
		)
		(property "MPN" "GRM155R61H104KE14D"
			(at 71.835 332.135 0)
			(layer "F.Fab")
			(hide yes)
			(effects
				(font
					(size 1 1)
					(thickness 0.15)
				)
			)
		)
		(property "Manufacturer" "Murata"
			(at 71.835 332.135 0)
			(layer "F.Fab")
			(hide yes)
			(effects
				(font
					(size 1 1)
					(thickness 0.15)
				)
			)
		)
		(property "Public" "False"
			(at 71.835 332.135 0)
			(layer "F.Fab")
			(hide yes)
			(effects
				(font
					(size 1 1)
					(thickness 0.15)
				)
			)
		)
		(property "Val" "100n"
			(at 71.835 332.135 0)
			(layer "F.Fab")
			(hide yes)
			(effects
				(font
					(size 1 1)
					(thickness 0.15)
				)
			)
		)
		(property "Voltage" "50V"
			(at 71.835 332.135 0)
			(layer "F.Fab")
			(hide yes)
			(effects
				(font
					(size 1 1)
					(thickness 0.15)
				)
			)
		)
		(sheetfile "environment-sensor.kicad_sch")
		(attr smd)
		(fp_rect
			(start -0.925 -0.47)
			(end 0.925 0.47)
			(stroke
				(width 0.05)
				(type default)
			)
			(fill no)
			(layer "F.CrtYd")
		)
		(fp_line
			(start -0.494 0.248)
			(end -0.494 -0.25)
			(stroke
				(width 0.15)
				(type solid)
			)
			(layer "F.Fab")
		)
		(fp_line
			(start 0.504 0.248)
			(end -0.494 0.248)
			(stroke
				(width 0.15)
				(type solid)
			)
			(layer "F.Fab")
		)
		(fp_line
			(start -0.494 -0.25)
			(end 0.504 -0.25)
			(stroke
				(width 0.15)
				(type solid)
			)
			(layer "F.Fab")
		)
		(fp_line
			(start 0.504 -0.25)
			(end 0.504 0.248)
			(stroke
				(width 0.15)
				(type solid)
			)
			(layer "F.Fab")
		)
		(pad "1" smd roundrect
			(at -0.48 0 270)
			(size 0.59 0.64)
			(layers "F.Cu" "F.Mask" "F.Paste")
			(roundrect_rratio 0.25)
			(net 2 "+3V3")
			(pintype "passive")
		)
		(pad "2" smd roundrect
			(at 0.48 0 270)
			(size 0.59 0.64)
			(layers "F.Cu" "F.Mask" "F.Paste")
			(roundrect_rratio 0.25)
			(net 1 "GND")
			(pintype "passive")
		)
	)
	(footprint "antmicro-footprints:TP_SMD_1.5mm"
		(locked yes)
		(layer "F.Cu")
		(at 186 116)
		(property "Reference" "TP3"
			(at -1.696 -1.061 0)
			(layer "F.SilkS")
			(hide yes)
			(effects
				(font
					(size 0.7 0.7)
					(thickness 0.15)
				)
				(justify left bottom)
			)
		)
		(property "Value" "TP_1.5mm_SMD"
			(at 0 1.7 0)
			(layer "F.Fab")
			(effects
				(font
					(size 0.7 0.7)
					(thickness 0.15)
				)
				(justify left bottom)
			)
		)
		(property "Description" "test point, SMT"
			(at 0 0 0)
			(layer "F.Fab")
			(hide yes)
			(effects
				(font
					(size 1.27 1.27)
					(thickness 0.15)
				)
			)
		)
		(property "Author" "Antmicro"
			(at 0 0 0)
			(layer "F.Fab")
			(hide yes)
			(effects
				(font
					(size 1 1)
					(thickness 0.15)
				)
			)
		)
		(property "License" "Apache-2.0"
			(at 0 0 0)
			(layer "F.Fab")
			(hide yes)
			(effects
				(font
					(size 1 1)
					(thickness 0.15)
				)
			)
		)
		(property "MPN" ""
			(at 0 0 0)
			(layer "F.Fab")
			(hide yes)
			(effects
				(font
					(size 1 1)
					(thickness 0.15)
				)
			)
		)
		(property "Manufacturer" ""
			(at 0 0 0)
			(layer "F.Fab")
			(hide yes)
			(effects
				(font
					(size 1 1)
					(thickness 0.15)
				)
			)
		)
		(property "Public" "False"
			(at 0 0 0)
			(layer "F.Fab")
			(hide yes)
			(effects
				(font
					(size 1 1)
					(thickness 0.15)
				)
			)
		)
		(sheetfile "environment-sensor.kicad_sch")
		(attr exclude_from_pos_files)
		(pad "1" smd circle
			(at 0 0 270)
			(size 1.5 1.5)
			(layers "F.Cu" "F.Mask")
			(net 20 "SWDIO-JTMS")
			(pinfunction "1")
			(pintype "passive")
		)
	)
	(footprint "antmicro-footprints:C_0402_1005Metric"
		(layer "F.Cu")
		(at 182.925 133.7)
		(descr "Capacitor SMD 0402")
		(tags "capacitor SMD 0402")
		(property "Reference" "C23"
			(at 3.075 0.4 0)
			(layer "F.SilkS")
			(effects
				(font
					(size 0.7 0.7)
					(thickness 0.15)
				)
				(justify right bottom)
			)
		)
		(property "Value" "C_10p_0402"
			(at 0 1.4 0)
			(layer "F.Fab")
			(effects
				(font
					(size 0.7 0.7)
					(thickness 0.15)
				)
				(justify left bottom)
			)
		)
		(property "Description" "SMD Multilayer Ceramic Capacitor, 10 pF, 50 V, 0402 [1005 Metric], ± 2%, C0G / NP0, GCM"
			(at 0 0 0)
			(layer "F.Fab")
			(hide yes)
			(effects
				(font
					(size 1.27 1.27)
					(thickness 0.15)
				)
			)
		)
		(property "Author" "Antmicro"
			(at 0 0 0)
			(layer "F.Fab")
			(hide yes)
			(effects
				(font
					(size 1 1)
					(thickness 0.15)
				)
			)
		)
		(property "Dielectric" "C0G"
			(at 0 0 0)
			(layer "F.Fab")
			(hide yes)
			(effects
				(font
					(size 1 1)
					(thickness 0.15)
				)
			)
		)
		(property "License" "Apache-2.0"
			(at 0 0 0)
			(layer "F.Fab")
			(hide yes)
			(effects
				(font
					(size 1 1)
					(thickness 0.15)
				)
			)
		)
		(property "MPN" "GCM1555C1H100GA16D"
			(at 0 0 0)
			(layer "F.Fab")
			(hide yes)
			(effects
				(font
					(size 1 1)
					(thickness 0.15)
				)
			)
		)
		(property "Manufacturer" "Murata"
			(at 0 0 0)
			(layer "F.Fab")
			(hide yes)
			(effects
				(font
					(size 1 1)
					(thickness 0.15)
				)
			)
		)
		(property "Public" "False"
			(at 0 0 0)
			(layer "F.Fab")
			(hide yes)
			(effects
				(font
					(size 1 1)
					(thickness 0.15)
				)
			)
		)
		(property "Val" "10p"
			(at 0 0 0)
			(layer "F.Fab")
			(hide yes)
			(effects
				(font
					(size 1 1)
					(thickness 0.15)
				)
			)
		)
		(property "Voltage" "50V"
			(at 0 0 0)
			(layer "F.Fab")
			(hide yes)
			(effects
				(font
					(size 1 1)
					(thickness 0.15)
				)
			)
		)
		(sheetfile "environment-sensor.kicad_sch")
		(attr smd)
		(fp_rect
			(start -0.925 -0.47)
			(end 0.925 0.47)
			(stroke
				(width 0.05)
				(type default)
			)
			(fill no)
			(layer "F.CrtYd")
		)
		(fp_line
			(start -0.494 -0.25)
			(end 0.504 -0.25)
			(stroke
				(width 0.15)
				(type solid)
			)
			(layer "F.Fab")
		)
		(fp_line
			(start -0.494 0.248)
			(end -0.494 -0.25)
			(stroke
				(width 0.15)
				(type solid)
			)
			(layer "F.Fab")
		)
		(fp_line
			(start 0.504 -0.25)
			(end 0.504 0.248)
			(stroke
				(width 0.15)
				(type solid)
			)
			(layer "F.Fab")
		)
		(fp_line
			(start 0.504 0.248)
			(end -0.494 0.248)
			(stroke
				(width 0.15)
				(type solid)
			)
			(layer "F.Fab")
		)
		(pad "1" smd roundrect
			(at -0.48 0)
			(size 0.59 0.64)
			(layers "F.Cu" "F.Mask" "F.Paste")
			(roundrect_rratio 0.25)
			(net 1 "GND")
			(pintype "passive")
		)
		(pad "2" smd roundrect
			(at 0.48 0)
			(size 0.59 0.64)
			(layers "F.Cu" "F.Mask" "F.Paste")
			(roundrect_rratio 0.25)
			(net 33 "Net-(U3-PF0-OSC_IN)")
			(pintype "passive")
		)
	)
	(footprint "antmicro-footprints:TP_SMD_1.5mm"
		(locked yes)
		(layer "F.Cu")
		(at 188.5 116)
		(property "Reference" "TP4"
			(at -1.705 -1.138 0)
			(layer "F.SilkS")
			(hide yes)
			(effects
				(font
					(size 0.7 0.7)
					(thickness 0.15)
				)
				(justify left bottom)
			)
		)
		(property "Value" "TP_1.5mm_SMD"
			(at 0 1.7 0)
			(layer "F.Fab")
			(effects
				(font
					(size 0.7 0.7)
					(thickness 0.15)
				)
				(justify left bottom)
			)
		)
		(property "Description" "test point, SMT"
			(at 0 0 0)
			(layer "F.Fab")
			(hide yes)
			(effects
				(font
					(size 1.27 1.27)
					(thickness 0.15)
				)
			)
		)
		(property "Author" "Antmicro"
			(at 0 0 0)
			(layer "F.Fab")
			(hide yes)
			(effects
				(font
					(size 1 1)
					(thickness 0.15)
				)
			)
		)
		(property "License" "Apache-2.0"
			(at 0 0 0)
			(layer "F.Fab")
			(hide yes)
			(effects
				(font
					(size 1 1)
					(thickness 0.15)
				)
			)
		)
		(property "MPN" ""
			(at 0 0 0)
			(layer "F.Fab")
			(hide yes)
			(effects
				(font
					(size 1 1)
					(thickness 0.15)
				)
			)
		)
		(property "Manufacturer" ""
			(at 0 0 0)
			(layer "F.Fab")
			(hide yes)
			(effects
				(font
					(size 1 1)
					(thickness 0.15)
				)
			)
		)
		(property "Public" "False"
			(at 0 0 0)
			(layer "F.Fab")
			(hide yes)
			(effects
				(font
					(size 1 1)
					(thickness 0.15)
				)
			)
		)
		(sheetfile "environment-sensor.kicad_sch")
		(attr exclude_from_pos_files)
		(pad "1" smd circle
			(at 0 0 270)
			(size 1.5 1.5)
			(layers "F.Cu" "F.Mask")
			(net 18 "SWCLK-JTCK")
			(pinfunction "1")
			(pintype "passive")
		)
	)
	(footprint "antmicro-footprints:C_0402_1005Metric"
		(layer "F.Cu")
		(at 178.524 115.223 180)
		(descr "Capacitor SMD 0402")
		(tags "capacitor SMD 0402")
		(property "Reference" "C6"
			(at 0.054 0.546 0)
			(layer "F.SilkS")
			(effects
				(font
					(size 0.7 0.7)
					(thickness 0.15)
				)
				(justify right bottom)
			)
		)
		(property "Value" "C_100n_0402"
			(at 0 1.4 0)
			(layer "F.Fab")
			(effects
				(font
					(size 0.7 0.7)
					(thickness 0.15)
				)
				(justify right bottom)
			)
		)
		(property "Description" "SMD Multilayer Ceramic Capacitor, 0.1 µF, 50 V, 0402 [1005 Metric], ± 10%, X5R, GRM Series"
			(at 0 0 180)
			(layer "F.Fab")
			(hide yes)
			(effects
				(font
					(size 1.27 1.27)
					(thickness 0.15)
				)
			)
		)
		(property "Author" "Antmicro"
			(at 357.048 230.446 0)
			(layer "F.Fab")
			(hide yes)
			(effects
				(font
					(size 1 1)
					(thickness 0.15)
				)
			)
		)
		(property "Dielectric" "X5R"
			(at 357.048 230.446 0)
			(layer "F.Fab")
			(hide yes)
			(effects
				(font
					(size 1 1)
					(thickness 0.15)
				)
			)
		)
		(property "License" "Apache-2.0"
			(at 357.048 230.446 0)
			(layer "F.Fab")
			(hide yes)
			(effects
				(font
					(size 1 1)
					(thickness 0.15)
				)
			)
		)
		(property "MPN" "GRM155R61H104KE14D"
			(at 357.048 230.446 0)
			(layer "F.Fab")
			(hide yes)
			(effects
				(font
					(size 1 1)
					(thickness 0.15)
				)
			)
		)
		(property "Manufacturer" "Murata"
			(at 357.048 230.446 0)
			(layer "F.Fab")
			(hide yes)
			(effects
				(font
					(size 1 1)
					(thickness 0.15)
				)
			)
		)
		(property "Public" "False"
			(at 357.048 230.446 0)
			(layer "F.Fab")
			(hide yes)
			(effects
				(font
					(size 1 1)
					(thickness 0.15)
				)
			)
		)
		(property "Val" "100n"
			(at 357.048 230.446 0)
			(layer "F.Fab")
			(hide yes)
			(effects
				(font
					(size 1 1)
					(thickness 0.15)
				)
			)
		)
		(property "Voltage" "50V"
			(at 357.048 230.446 0)
			(layer "F.Fab")
			(hide yes)
			(effects
				(font
					(size 1 1)
					(thickness 0.15)
				)
			)
		)
		(sheetfile "environment-sensor.kicad_sch")
		(attr smd)
		(fp_rect
			(start -0.925 -0.47)
			(end 0.925 0.47)
			(stroke
				(width 0.05)
				(type default)
			)
			(fill no)
			(layer "F.CrtYd")
		)
		(fp_line
			(start 0.504 0.248)
			(end -0.494 0.248)
			(stroke
				(width 0.15)
				(type solid)
			)
			(layer "F.Fab")
		)
		(fp_line
			(start 0.504 -0.25)
			(end 0.504 0.248)
			(stroke
				(width 0.15)
				(type solid)
			)
			(layer "F.Fab")
		)
		(fp_line
			(start -0.494 0.248)
			(end -0.494 -0.25)
			(stroke
				(width 0.15)
				(type solid)
			)
			(layer "F.Fab")
		)
		(fp_line
			(start -0.494 -0.25)
			(end 0.504 -0.25)
			(stroke
				(width 0.15)
				(type solid)
			)
			(layer "F.Fab")
		)
		(pad "1" smd roundrect
			(at -0.48 0 180)
			(size 0.59 0.64)
			(layers "F.Cu" "F.Mask" "F.Paste")
			(roundrect_rratio 0.25)
			(net 1 "GND")
			(pintype "passive")
		)
		(pad "2" smd roundrect
			(at 0.48 0 180)
			(size 0.59 0.64)
			(layers "F.Cu" "F.Mask" "F.Paste")
			(roundrect_rratio 0.25)
			(net 29 "Net-(U1-3V3OUT)")
			(pintype "passive")
		)
	)
	(footprint "antmicro-footprints:SOD-923"
		(layer "F.Cu")
		(at 169.985 128.45)
		(property "Reference" "D4"
			(at 1.315 -0.007 0)
			(unlocked yes)
			(layer "F.SilkS")
			(effects
				(font
					(size 0.65 0.65)
					(thickness 0.15)
				)
			)
		)
		(property "Value" "ESD9X5.0ST5G"
			(at 0 2.4 0)
			(unlocked yes)
			(layer "F.Fab")
			(effects
				(font
					(size 1 1)
					(thickness 0.15)
				)
			)
		)
		(property "Description" "Unidirectional TVS, 30 kV,  SOD-923, 5 V, 65 pF"
			(at 0 0 0)
			(layer "F.Fab")
			(hide yes)
			(effects
				(font
					(size 1.27 1.27)
					(thickness 0.15)
				)
			)
		)
		(property "Author" "Antmicro"
			(at 0 0 0)
			(layer "F.Fab")
			(hide yes)
			(effects
				(font
					(size 1 1)
					(thickness 0.15)
				)
			)
		)
		(property "License" "Apache-2.0"
			(at 0 0 0)
			(layer "F.Fab")
			(hide yes)
			(effects
				(font
					(size 1 1)
					(thickness 0.15)
				)
			)
		)
		(property "MPN" "ESD9X5.0ST5G"
			(at 0 0 0)
			(layer "F.Fab")
			(hide yes)
			(effects
				(font
					(size 1 1)
					(thickness 0.15)
				)
			)
		)
		(property "Manufacturer" "ON Semiconductor"
			(at 0 0 0)
			(layer "F.Fab")
			(hide yes)
			(effects
				(font
					(size 1 1)
					(thickness 0.15)
				)
			)
		)
		(property "Public" "False"
			(at 0 0 0)
			(layer "F.Fab")
			(hide yes)
			(effects
				(font
					(size 1 1)
					(thickness 0.15)
				)
			)
		)
		(sheetfile "environment-sensor.kicad_sch")
		(attr smd)
		(fp_line
			(start -0.5 -0.4)
			(end 0.5 -0.4)
			(stroke
				(width 0.15)
				(type solid)
			)
			(layer "F.SilkS")
		)
		(fp_line
			(start -0.5 -0.3)
			(end -0.5 -0.4)
			(stroke
				(width 0.15)
				(type solid)
			)
			(layer "F.SilkS")
		)
		(fp_line
			(start -0.5 0.4)
			(end -0.5 0.3)
			(stroke
				(width 0.15)
				(type solid)
			)
			(layer "F.SilkS")
		)
		(fp_line
			(start -0.5 0.4)
			(end 0.5 0.4)
			(stroke
				(width 0.15)
				(type solid)
			)
			(layer "F.SilkS")
		)
		(fp_line
			(start -0.16 -0.4)
			(end -0.16 0.4)
			(stroke
				(width 0.15)
				(type solid)
			)
			(layer "F.SilkS")
		)
		(fp_line
			(start 0.5 -0.4)
			(end 0.5 -0.3)
			(stroke
				(width 0.15)
				(type solid)
			)
			(layer "F.SilkS")
		)
		(fp_line
			(start 0.5 0.4)
			(end 0.5 0.3)
			(stroke
				(width 0.15)
				(type solid)
			)
			(layer "F.SilkS")
		)
		(fp_rect
			(start -0.68 -0.41)
			(end 0.68 0.41)
			(stroke
				(width 0.05)
				(type solid)
			)
			(fill no)
			(layer "F.CrtYd")
		)
		(fp_line
			(start -0.202 -0.3)
			(end -0.202 0.298)
			(stroke
				(width 0.15)
				(type solid)
			)
			(layer "F.Fab")
		)
		(fp_rect
			(start -0.402 -0.3)
			(end 0.4 0.298)
			(stroke
				(width 0.15)
				(type solid)
			)
			(fill no)
			(layer "F.Fab")
		)
		(fp_text user "${REFERENCE}"
			(at 0 1.1 0)
			(unlocked yes)
			(layer "F.Fab")
			(effects
				(font
					(size 1 1)
					(thickness 0.15)
				)
			)
		)
		(pad "1" smd roundrect
			(at -0.438 0)
			(size 0.4 0.325)
			(layers "F.Cu" "F.Mask" "F.Paste")
			(roundrect_rratio 0.25)
			(net 1 "GND")
			(pinfunction "C")
			(pintype "passive")
		)
		(pad "2" smd roundrect
			(at 0.436 0)
			(size 0.4 0.325)
			(layers "F.Cu" "F.Mask" "F.Paste")
			(roundrect_rratio 0.25)
			(net 5 "/USB_CC2")
			(pinfunction "A")
			(pintype "passive")
		)
	)
	(footprint "antmicro-footprints:SOD-923"
		(layer "F.Cu")
		(at 169.985 125.05)
		(property "Reference" "D3"
			(at 1.315 0 0)
			(unlocked yes)
			(layer "F.SilkS")
			(effects
				(font
					(size 0.65 0.65)
					(thickness 0.15)
				)
			)
		)
		(property "Value" "ESD9X5.0ST5G"
			(at 0 2.4 0)
			(unlocked yes)
			(layer "F.Fab")
			(effects
				(font
					(size 1 1)
					(thickness 0.15)
				)
			)
		)
		(property "Description" "Unidirectional TVS, 30 kV,  SOD-923, 5 V, 65 pF"
			(at 0 0 0)
			(layer "F.Fab")
			(hide yes)
			(effects
				(font
					(size 1.27 1.27)
					(thickness 0.15)
				)
			)
		)
		(property "Author" "Antmicro"
			(at 0 0 0)
			(layer "F.Fab")
			(hide yes)
			(effects
				(font
					(size 1 1)
					(thickness 0.15)
				)
			)
		)
		(property "License" "Apache-2.0"
			(at 0 0 0)
			(layer "F.Fab")
			(hide yes)
			(effects
				(font
					(size 1 1)
					(thickness 0.15)
				)
			)
		)
		(property "MPN" "ESD9X5.0ST5G"
			(at 0 0 0)
			(layer "F.Fab")
			(hide yes)
			(effects
				(font
					(size 1 1)
					(thickness 0.15)
				)
			)
		)
		(property "Manufacturer" "ON Semiconductor"
			(at 0 0 0)
			(layer "F.Fab")
			(hide yes)
			(effects
				(font
					(size 1 1)
					(thickness 0.15)
				)
			)
		)
		(property "Public" "False"
			(at 0 0 0)
			(layer "F.Fab")
			(hide yes)
			(effects
				(font
					(size 1 1)
					(thickness 0.15)
				)
			)
		)
		(sheetfile "environment-sensor.kicad_sch")
		(attr smd)
		(fp_line
			(start -0.5 -0.4)
			(end 0.5 -0.4)
			(stroke
				(width 0.15)
				(type solid)
			)
			(layer "F.SilkS")
		)
		(fp_line
			(start -0.5 -0.3)
			(end -0.5 -0.4)
			(stroke
				(width 0.15)
				(type solid)
			)
			(layer "F.SilkS")
		)
		(fp_line
			(start -0.5 0.4)
			(end -0.5 0.3)
			(stroke
				(width 0.15)
				(type solid)
			)
			(layer "F.SilkS")
		)
		(fp_line
			(start -0.5 0.4)
			(end 0.5 0.4)
			(stroke
				(width 0.15)
				(type solid)
			)
			(layer "F.SilkS")
		)
		(fp_line
			(start -0.16 -0.4)
			(end -0.16 0.4)
			(stroke
				(width 0.15)
				(type solid)
			)
			(layer "F.SilkS")
		)
		(fp_line
			(start 0.5 -0.4)
			(end 0.5 -0.3)
			(stroke
				(width 0.15)
				(type solid)
			)
			(layer "F.SilkS")
		)
		(fp_line
			(start 0.5 0.4)
			(end 0.5 0.3)
			(stroke
				(width 0.15)
				(type solid)
			)
			(layer "F.SilkS")
		)
		(fp_rect
			(start -0.68 -0.41)
			(end 0.68 0.41)
			(stroke
				(width 0.05)
				(type solid)
			)
			(fill no)
			(layer "F.CrtYd")
		)
		(fp_line
			(start -0.202 -0.3)
			(end -0.202 0.298)
			(stroke
				(width 0.15)
				(type solid)
			)
			(layer "F.Fab")
		)
		(fp_rect
			(start -0.402 -0.3)
			(end 0.4 0.298)
			(stroke
				(width 0.15)
				(type solid)
			)
			(fill no)
			(layer "F.Fab")
		)
		(fp_text user "${REFERENCE}"
			(at 0 1.1 0)
			(unlocked yes)
			(layer "F.Fab")
			(effects
				(font
					(size 1 1)
					(thickness 0.15)
				)
			)
		)
		(pad "1" smd roundrect
			(at -0.438 0)
			(size 0.4 0.325)
			(layers "F.Cu" "F.Mask" "F.Paste")
			(roundrect_rratio 0.25)
			(net 1 "GND")
			(pinfunction "C")
			(pintype "passive")
		)
		(pad "2" smd roundrect
			(at 0.436 0)
			(size 0.4 0.325)
			(layers "F.Cu" "F.Mask" "F.Paste")
			(roundrect_rratio 0.25)
			(net 4 "/USB_CC1")
			(pinfunction "A")
			(pintype "passive")
		)
	)
	(footprint "antmicro-footprints:FB_0603_1608Metric"
		(layer "F.Cu")
		(at 169.25 138.7)
		(property "Reference" "FB2"
			(at -3.45 0.45 0)
			(layer "F.SilkS")
			(effects
				(font
					(size 0.7 0.7)
					(thickness 0.15)
				)
				(justify left bottom)
			)
		)
		(property "Value" "FB_120Z_2A_Murata-BLM18PG_0603"
			(at 0 1.5 0)
			(layer "F.Fab")
			(effects
				(font
					(size 0.7 0.7)
					(thickness 0.15)
				)
				(justify left bottom)
			)
		)
		(property "Description" "Ferrite Bead, 0603 [1608 Metric], 120 ohm, 2 A, BLM18P, 0.05 ohm, ± 25%, DC power line"
			(at 0 0 0)
			(layer "F.Fab")
			(hide yes)
			(effects
				(font
					(size 1.27 1.27)
					(thickness 0.15)
				)
			)
		)
		(property "Author" "Antmicro"
			(at 0 0 0)
			(layer "F.Fab")
			(hide yes)
			(effects
				(font
					(size 1 1)
					(thickness 0.15)
				)
			)
		)
		(property "Current" ""
			(at 0 0 0)
			(layer "F.Fab")
			(hide yes)
			(effects
				(font
					(size 1 1)
					(thickness 0.15)
				)
			)
		)
		(property "License" "Apache-2.0"
			(at 0 0 0)
			(layer "F.Fab")
			(hide yes)
			(effects
				(font
					(size 1 1)
					(thickness 0.15)
				)
			)
		)
		(property "MPN" "BLM18PG121SN1D"
			(at 0 0 0)
			(layer "F.Fab")
			(hide yes)
			(effects
				(font
					(size 1 1)
					(thickness 0.15)
				)
			)
		)
		(property "Manufacturer" "Murata"
			(at 0 0 0)
			(layer "F.Fab")
			(hide yes)
			(effects
				(font
					(size 1 1)
					(thickness 0.15)
				)
			)
		)
		(property "Public" "False"
			(at 0 0 0)
			(layer "F.Fab")
			(hide yes)
			(effects
				(font
					(size 1 1)
					(thickness 0.15)
				)
			)
		)
		(property "Val" "120Z/2A"
			(at 0 0 0)
			(layer "F.Fab")
			(hide yes)
			(effects
				(font
					(size 1 1)
					(thickness 0.15)
				)
			)
		)
		(sheetfile "environment-sensor.kicad_sch")
		(attr smd)
		(fp_line
			(start -0.15 -0.4)
			(end 0.15 -0.4)
			(stroke
				(width 0.15)
				(type solid)
			)
			(layer "F.SilkS")
		)
		(fp_line
			(start -0.15 0.4)
			(end 0.15 0.4)
			(stroke
				(width 0.15)
				(type solid)
			)
			(layer "F.SilkS")
		)
		(fp_rect
			(start -1.25 -0.65)
			(end 1.25 0.65)
			(stroke
				(width 0.05)
				(type solid)
			)
			(fill no)
			(layer "F.CrtYd")
		)
		(fp_line
			(start -0.803 0.406)
			(end -0.803 -0.408)
			(stroke
				(width 0.15)
				(type solid)
			)
			(layer "F.Fab")
		)
		(fp_line
			(start 0.8 -0.408)
			(end -0.803 -0.408)
			(stroke
				(width 0.15)
				(type solid)
			)
			(layer "F.Fab")
		)
		(fp_line
			(start 0.8 -0.408)
			(end 0.8 0.406)
			(stroke
				(width 0.15)
				(type solid)
			)
			(layer "F.Fab")
		)
		(fp_line
			(start 0.8 0.406)
			(end -0.803 0.406)
			(stroke
				(width 0.15)
				(type solid)
			)
			(layer "F.Fab")
		)
		(pad "1" smd roundrect
			(at -0.7 0)
			(size 0.8 1)
			(layers "F.Cu" "F.Mask" "F.Paste")
			(roundrect_rratio 0.2)
			(net 27 "/VBUS")
			(pintype "passive")
		)
		(pad "2" smd roundrect
			(at 0.7 0)
			(size 0.8 1)
			(layers "F.Cu" "F.Mask" "F.Paste")
			(roundrect_rratio 0.2)
			(net 26 "+5V")
			(pintype "passive")
		)
	)
	(footprint "antmicro-footprints:TP_SMD_1.5mm"
		(locked yes)
		(layer "F.Cu")
		(at 191 116)
		(property "Reference" "TP1"
			(at -1.588 -1.193 0)
			(layer "F.SilkS")
			(hide yes)
			(effects
				(font
					(size 0.7 0.7)
					(thickness 0.15)
				)
				(justify left bottom)
			)
		)
		(property "Value" "TP_1.5mm_SMD"
			(at 0 1.7 0)
			(layer "F.Fab")
			(effects
				(font
					(size 0.7 0.7)
					(thickness 0.15)
				)
				(justify left bottom)
			)
		)
		(property "Description" "test point, SMT"
			(at 0 0 0)
			(layer "F.Fab")
			(hide yes)
			(effects
				(font
					(size 1.27 1.27)
					(thickness 0.15)
				)
			)
		)
		(property "Author" "Antmicro"
			(at 0 0 0)
			(layer "F.Fab")
			(hide yes)
			(effects
				(font
					(size 1 1)
					(thickness 0.15)
				)
			)
		)
		(property "License" "Apache-2.0"
			(at 0 0 0)
			(layer "F.Fab")
			(hide yes)
			(effects
				(font
					(size 1 1)
					(thickness 0.15)
				)
			)
		)
		(property "MPN" ""
			(at 0 0 0)
			(layer "F.Fab")
			(hide yes)
			(effects
				(font
					(size 1 1)
					(thickness 0.15)
				)
			)
		)
		(property "Manufacturer" ""
			(at 0 0 0)
			(layer "F.Fab")
			(hide yes)
			(effects
				(font
					(size 1 1)
					(thickness 0.15)
				)
			)
		)
		(property "Public" "False"
			(at 0 0 0)
			(layer "F.Fab")
			(hide yes)
			(effects
				(font
					(size 1 1)
					(thickness 0.15)
				)
			)
		)
		(sheetfile "environment-sensor.kicad_sch")
		(attr exclude_from_pos_files)
		(pad "1" smd circle
			(at 0 0 270)
			(size 1.5 1.5)
			(layers "F.Cu" "F.Mask")
			(net 14 "NRST")
			(pinfunction "1")
			(pintype "passive")
		)
	)
	(footprint "antmicro-footprints:LQFP-48_7x7mm_P0.5mm"
		(layer "F.Cu")
		(at 191.6 131.95)
		(property "Reference" "U3"
			(at 3.6 -3.536 0)
			(layer "F.SilkS")
			(effects
				(font
					(size 0.7 0.7)
					(thickness 0.15)
				)
				(justify left bottom)
			)
		)
		(property "Value" "STM32G474CET6"
			(at 0 6 0)
			(layer "F.Fab")
			(effects
				(font
					(size 0.7 0.7)
					(thickness 0.15)
				)
				(justify left bottom)
			)
		)
		(property "Description" "ARM MCU, STM32 Family STM32G4 Series Microcontrollers, ARM Cortex-M4F, 32 bit, 170 MHz, 512 KB"
			(at 0 0 0)
			(layer "F.Fab")
			(hide yes)
			(effects
				(font
					(size 1.27 1.27)
					(thickness 0.15)
				)
			)
		)
		(property "Author" "Antmicro"
			(at 0 0 0)
			(layer "F.Fab")
			(hide yes)
			(effects
				(font
					(size 1 1)
					(thickness 0.15)
				)
			)
		)
		(property "License" "Apache-2.0"
			(at 0 0 0)
			(layer "F.Fab")
			(hide yes)
			(effects
				(font
					(size 1 1)
					(thickness 0.15)
				)
			)
		)
		(property "MPN" "STM32G474CET6"
			(at 0 0 0)
			(layer "F.Fab")
			(hide yes)
			(effects
				(font
					(size 1 1)
					(thickness 0.15)
				)
			)
		)
		(property "Manufacturer" "STMicroelectronics"
			(at 0 0 0)
			(layer "F.Fab")
			(hide yes)
			(effects
				(font
					(size 1 1)
					(thickness 0.15)
				)
			)
		)
		(sheetfile "environment-sensor.kicad_sch")
		(attr smd)
		(fp_line
			(start -3.6 3.164)
			(end -3.6 3.664)
			(stroke
				(width 0.15)
				(type solid)
			)
			(layer "F.SilkS")
		)
		(fp_line
			(start -3.6 3.664)
			(end -3.1 3.664)
			(stroke
				(width 0.15)
				(type solid)
			)
			(layer "F.SilkS")
		)
		(fp_line
			(start -3.1 -3.536)
			(end -3.6 -3.036)
			(stroke
				(width 0.15)
				(type solid)
			)
			(layer "F.SilkS")
		)
		(fp_line
			(start 3.1 -3.536)
			(end 3.6 -3.536)
			(stroke
				(width 0.15)
				(type solid)
			)
			(layer "F.SilkS")
		)
		(fp_line
			(start 3.6 -3.536)
			(end 3.6 -3.036)
			(stroke
				(width 0.15)
				(type solid)
			)
			(layer "F.SilkS")
		)
		(fp_line
			(start 3.6 3.164)
			(end 3.6 3.664)
			(stroke
				(width 0.15)
				(type solid)
			)
			(layer "F.SilkS")
		)
		(fp_line
			(start 3.6 3.664)
			(end 3.1 3.664)
			(stroke
				(width 0.15)
				(type solid)
			)
			(layer "F.SilkS")
		)
		(fp_circle
			(center -4.15 -3.035)
			(end -4.1 -3.035)
			(stroke
				(width 0.15)
				(type solid)
			)
			(fill yes)
			(layer "F.SilkS")
		)
		(fp_rect
			(start -4.85 -4.8)
			(end 4.85 4.9)
			(stroke
				(width 0.05)
				(type solid)
			)
			(fill no)
			(layer "F.CrtYd")
		)
		(fp_line
			(start -3.5 -2.936)
			(end -3.5 3.564)
			(stroke
				(width 0.15)
				(type solid)
			)
			(layer "F.Fab")
		)
		(fp_line
			(start -3.5 3.564)
			(end 3.5 3.564)
			(stroke
				(width 0.15)
				(type solid)
			)
			(layer "F.Fab")
		)
		(fp_line
			(start -3 -3.436)
			(end -3.5 -2.936)
			(stroke
				(width 0.15)
				(type solid)
			)
			(layer "F.Fab")
		)
		(fp_line
			(start -3 -3.436)
			(end 3.5 -3.436)
			(stroke
				(width 0.15)
				(type solid)
			)
			(layer "F.Fab")
		)
		(fp_line
			(start 3.5 -3.436)
			(end 3.5 3.564)
			(stroke
				(width 0.15)
				(type solid)
			)
			(layer "F.Fab")
		)
		(pad "1" smd rect
			(at -4.2 -2.685)
			(size 1.2 0.35)
			(layers "F.Cu" "F.Mask" "F.Paste")
			(net 28 "Net-(U3-VBAT)")
			(pinfunction "VBAT")
			(pintype "power_in")
		)
		(pad "2" smd rect
			(at -4.2 -2.185)
			(size 1.2 0.35)
			(layers "F.Cu" "F.Mask" "F.Paste")
			(net 21 "/FTDI_USER_PB")
			(pinfunction "PC13")
			(pintype "bidirectional")
		)
		(pad "3" smd rect
			(at -4.2 -1.685)
			(size 1.2 0.35)
			(layers "F.Cu" "F.Mask" "F.Paste")
			(net 86 "/OSC32_IN")
			(pinfunction "PC14-OSC32_IN")
			(pintype "bidirectional")
		)
		(pad "4" smd rect
			(at -4.2 -1.185)
			(size 1.2 0.35)
			(layers "F.Cu" "F.Mask" "F.Paste")
			(net 87 "/OSC32_OUT")
			(pinfunction "PC15-OSC32_OUT")
			(pintype "bidirectional")
		)
		(pad "5" smd rect
			(at -4.2 -0.685)
			(size 1.2 0.35)
			(layers "F.Cu" "F.Mask" "F.Paste")
			(net 33 "Net-(U3-PF0-OSC_IN)")
			(pinfunction "PF0-OSC_IN")
			(pintype "bidirectional")
		)
		(pad "6" smd rect
			(at -4.2 -0.185)
			(size 1.2 0.35)
			(layers "F.Cu" "F.Mask" "F.Paste")
			(net 31 "Net-(U3-PF1-OSC_OUT)")
			(pinfunction "PF1-OSC_OUT")
			(pintype "bidirectional")
		)
		(pad "7" smd rect
			(at -4.2 0.315)
			(size 1.2 0.35)
			(layers "F.Cu" "F.Mask" "F.Paste")
			(net 14 "NRST")
			(pinfunction "PG10-NRST")
			(pintype "bidirectional")
		)
		(pad "8" smd rect
			(at -4.2 0.815)
			(size 1.2 0.35)
			(layers "F.Cu" "F.Mask" "F.Paste")
			(net 84 "unconnected-(U3-PA0-Pad8)")
			(pinfunction "PA0")
			(pintype "bidirectional+no_connect")
		)
		(pad "9" smd rect
			(at -4.2 1.315)
			(size 1.2 0.35)
			(layers "F.Cu" "F.Mask" "F.Paste")
			(net 83 "unconnected-(U3-PA1-Pad9)")
			(pinfunction "PA1")
			(pintype "bidirectional+no_connect")
		)
		(pad "10" smd rect
			(at -4.2 1.815)
			(size 1.2 0.35)
			(layers "F.Cu" "F.Mask" "F.Paste")
			(net 17 "LPUART_1_STM_TX")
			(pinfunction "PA2")
			(pintype "bidirectional")
		)
		(pad "11" smd rect
			(at -4.2 2.315)
			(size 1.2 0.35)
			(layers "F.Cu" "F.Mask" "F.Paste")
			(net 16 "LPUART_1_STM_RX")
			(pinfunction "PA3")
			(pintype "bidirectional")
		)
		(pad "12" smd rect
			(at -4.2 2.815)
			(size 1.2 0.35)
			(layers "F.Cu" "F.Mask" "F.Paste")
			(net 82 "unconnected-(U3-PA4-Pad12)")
			(pinfunction "PA4")
			(pintype "bidirectional+no_connect")
		)
		(pad "13" smd rect
			(at -2.75 4.265)
			(size 0.35 1.2)
			(layers "F.Cu" "F.Mask" "F.Paste")
			(net 12 "/LD2")
			(pinfunction "PA5")
			(pintype "bidirectional")
		)
		(pad "14" smd rect
			(at -2.25 4.265)
			(size 0.35 1.2)
			(layers "F.Cu" "F.Mask" "F.Paste")
			(net 81 "unconnected-(U3-PA6-Pad14)")
			(pinfunction "PA6")
			(pintype "bidirectional+no_connect")
		)
		(pad "15" smd rect
			(at -1.75 4.265)
			(size 0.35 1.2)
			(layers "F.Cu" "F.Mask" "F.Paste")
			(net 80 "unconnected-(U3-PA7-Pad15)")
			(pinfunction "PA7")
			(pintype "bidirectional+no_connect")
		)
		(pad "16" smd rect
			(at -1.25 4.265)
			(size 0.35 1.2)
			(layers "F.Cu" "F.Mask" "F.Paste")
			(net 79 "unconnected-(U3-PB0-Pad16)")
			(pinfunction "PB0")
			(pintype "bidirectional+no_connect")
		)
		(pad "17" smd rect
			(at -0.75 4.265)
			(size 0.35 1.2)
			(layers "F.Cu" "F.Mask" "F.Paste")
			(net 78 "unconnected-(U3-PB1-Pad17)")
			(pinfunction "PB1")
			(pintype "bidirectional+no_connect")
		)
		(pad "18" smd rect
			(at -0.25 4.265)
			(size 0.35 1.2)
			(layers "F.Cu" "F.Mask" "F.Paste")
			(net 77 "unconnected-(U3-PB2-Pad18)")
			(pinfunction "PB2")
			(pintype "bidirectional+no_connect")
		)
		(pad "19" smd rect
			(at 0.25 4.265)
			(size 0.35 1.2)
			(layers "F.Cu" "F.Mask" "F.Paste")
			(net 1 "GND")
			(pinfunction "VSSA")
			(pintype "power_in")
		)
		(pad "20" smd rect
			(at 0.75 4.265)
			(size 0.35 1.2)
			(layers "F.Cu" "F.Mask" "F.Paste")
			(net 32 "Net-(U3-VREF+)")
			(pinfunction "VREF+")
			(pintype "passive")
		)
		(pad "21" smd rect
			(at 1.25 4.265)
			(size 0.35 1.2)
			(layers "F.Cu" "F.Mask" "F.Paste")
			(net 30 "Net-(U3-VDDA)")
			(pinfunction "VDDA")
			(pintype "power_in")
		)
		(pad "22" smd rect
			(at 1.75 4.265)
			(size 0.35 1.2)
			(layers "F.Cu" "F.Mask" "F.Paste")
			(net 76 "unconnected-(U3-PB10-Pad22)")
			(pinfunction "PB10")
			(pintype "bidirectional+no_connect")
		)
		(pad "23" smd rect
			(at 2.25 4.265)
			(size 0.35 1.2)
			(layers "F.Cu" "F.Mask" "F.Paste")
			(net 1 "GND")
			(pinfunction "VSS")
			(pintype "power_in")
		)
		(pad "24" smd rect
			(at 2.75 4.265)
			(size 0.35 1.2)
			(layers "F.Cu" "F.Mask" "F.Paste")
			(net 2 "+3V3")
			(pinfunction "VDD")
			(pintype "power_in")
		)
		(pad "25" smd rect
			(at 4.2 2.815)
			(size 1.2 0.35)
			(layers "F.Cu" "F.Mask" "F.Paste")
			(net 15 "/FRAM_WP")
			(pinfunction "PB11")
			(pintype "bidirectional")
		)
		(pad "26" smd rect
			(at 4.2 2.315)
			(size 1.2 0.35)
			(layers "F.Cu" "F.Mask" "F.Paste")
			(net 75 "unconnected-(U3-PB12-Pad26)")
			(pinfunction "PB12")
			(pintype "bidirectional+no_connect")
		)
		(pad "27" smd rect
			(at 4.2 1.815)
			(size 1.2 0.35)
			(layers "F.Cu" "F.Mask" "F.Paste")
			(net 74 "unconnected-(U3-PB13-Pad27)")
			(pinfunction "PB13")
			(pintype "bidirectional+no_connect")
		)
		(pad "28" smd rect
			(at 4.2 1.315)
			(size 1.2 0.35)
			(layers "F.Cu" "F.Mask" "F.Paste")
			(net 73 "unconnected-(U3-PB14-Pad28)")
			(pinfunction "PB14")
			(pintype "bidirectional+no_connect")
		)
		(pad "29" smd rect
			(at 4.2 0.815)
			(size 1.2 0.35)
			(layers "F.Cu" "F.Mask" "F.Paste")
			(net 72 "unconnected-(U3-PB15-Pad29)")
			(pinfunction "PB15")
			(pintype "bidirectional+no_connect")
		)
		(pad "30" smd rect
			(at 4.2 0.315)
			(size 1.2 0.35)
			(layers "F.Cu" "F.Mask" "F.Paste")
			(net 47 "Net-(U3-PA8)")
			(pinfunction "PA8")
			(pintype "bidirectional")
		)
		(pad "31" smd rect
			(at 4.2 -0.185)
			(size 1.2 0.35)
			(layers "F.Cu" "F.Mask" "F.Paste")
			(net 48 "Net-(U3-PA9)")
			(pinfunction "PA9")
			(pintype "bidirectional")
		)
		(pad "32" smd rect
			(at 4.2 -0.685)
			(size 1.2 0.35)
			(layers "F.Cu" "F.Mask" "F.Paste")
			(net 71 "unconnected-(U3-PA10-Pad32)")
			(pinfunction "PA10")
			(pintype "bidirectional+no_connect")
		)
		(pad "33" smd rect
			(at 4.2 -1.185)
			(size 1.2 0.35)
			(layers "F.Cu" "F.Mask" "F.Paste")
			(net 70 "unconnected-(U3-PA11-Pad33)")
			(pinfunction "PA11")
			(pintype "bidirectional+no_connect")
		)
		(pad "34" smd rect
			(at 4.2 -1.685)
			(size 1.2 0.35)
			(layers "F.Cu" "F.Mask" "F.Paste")
			(net 69 "unconnected-(U3-PA12-Pad34)")
			(pinfunction "PA12")
			(pintype "bidirectional+no_connect")
		)
		(pad "35" smd rect
			(at 4.2 -2.185)
			(size 1.2 0.35)
			(layers "F.Cu" "F.Mask" "F.Paste")
			(net 1 "GND")
			(pinfunction "VSS")
			(pintype "passive")
		)
		(pad "36" smd rect
			(at 4.2 -2.685)
			(size 1.2 0.35)
			(layers "F.Cu" "F.Mask" "F.Paste")
			(net 2 "+3V3")
			(pinfunction "VDD")
			(pintype "passive")
		)
		(pad "37" smd rect
			(at 2.75 -4.135)
			(size 0.35 1.2)
			(layers "F.Cu" "F.Mask" "F.Paste")
			(net 20 "SWDIO-JTMS")
			(pinfunction "PA13")
			(pintype "bidirectional")
		)
		(pad "38" smd rect
			(at 2.25 -4.135)
			(size 0.35 1.2)
			(layers "F.Cu" "F.Mask" "F.Paste")
			(net 18 "SWCLK-JTCK")
			(pinfunction "PA14")
			(pintype "bidirectional")
		)
		(pad "39" smd rect
			(at 1.75 -4.135)
			(size 0.35 1.2)
			(layers "F.Cu" "F.Mask" "F.Paste")
			(net 46 "Net-(U3-PA15)")
			(pinfunction "PA15")
			(pintype "bidirectional")
		)
		(pad "40" smd rect
			(at 1.25 -4.135)
			(size 0.35 1.2)
			(layers "F.Cu" "F.Mask" "F.Paste")
			(net 19 "JTDO")
			(pinfunction "PB3")
			(pintype "bidirectional")
		)
		(pad "41" smd rect
			(at 0.75 -4.135)
			(size 0.35 1.2)
			(layers "F.Cu" "F.Mask" "F.Paste")
			(net 13 "JTRST")
			(pinfunction "PB4")
			(pintype "bidirectional")
		)
		(pad "42" smd rect
			(at 0.25 -4.135)
			(size 0.35 1.2)
			(layers "F.Cu" "F.Mask" "F.Paste")
			(net 68 "unconnected-(U3-PB5-Pad42)")
			(pinfunction "PB5")
			(pintype "bidirectional+no_connect")
		)
		(pad "43" smd rect
			(at -0.25 -4.135)
			(size 0.35 1.2)
			(layers "F.Cu" "F.Mask" "F.Paste")
			(net 67 "unconnected-(U3-PB6-Pad43)")
			(pinfunction "PB6")
			(pintype "bidirectional+no_connect")
		)
		(pad "44" smd rect
			(at -0.75 -4.135)
			(size 0.35 1.2)
			(layers "F.Cu" "F.Mask" "F.Paste")
			(net 66 "unconnected-(U3-PB7-Pad44)")
			(pinfunction "PB7")
			(pintype "bidirectional+no_connect")
		)
		(pad "45" smd rect
			(at -1.25 -4.135)
			(size 0.35 1.2)
			(layers "F.Cu" "F.Mask" "F.Paste")
			(net 49 "Net-(U3-PB8-BOOT0)")
			(pinfunction "PB8-BOOT0")
			(pintype "bidirectional")
		)
		(pad "46" smd rect
			(at -1.75 -4.135)
			(size 0.35 1.2)
			(layers "F.Cu" "F.Mask" "F.Paste")
			(net 50 "Net-(U3-PB9)")
			(pinfunction "PB9")
			(pintype "bidirectional")
		)
		(pad "47" smd rect
			(at -2.25 -4.135)
			(size 0.35 1.2)
			(layers "F.Cu" "F.Mask" "F.Paste")
			(net 1 "GND")
			(pinfunction "VSS")
			(pintype "passive")
		)
		(pad "48" smd rect
			(at -2.75 -4.135)
			(size 0.35 1.2)
			(layers "F.Cu" "F.Mask" "F.Paste")
			(net 2 "+3V3")
			(pinfunction "VDD")
			(pintype "passive")
		)
	)
	(footprint "antmicro-footprints:R_0402_1005Metric"
		(layer "F.Cu")
		(at 185.854 117.597 180)
		(descr "Resistor SMD 0402")
		(tags "resistor SMD 0402")
		(property "Reference" "R26"
			(at -0.846 -0.503 180)
			(layer "F.SilkS")
			(effects
				(font
					(size 0.7 0.7)
					(thickness 0.15)
				)
				(justify left bottom)
			)
		)
		(property "Value" "R_1k_0402"
			(at 0 1.4 180)
			(layer "F.Fab")
			(effects
				(font
					(size 0.7 0.7)
					(thickness 0.15)
				)
				(justify left bottom)
			)
		)
		(property "Description" "SMD Chip Resistor, 1 kohm, ± 1%, 63 mW, 0402 [1005 Metric], Thick Film, General Purpose"
			(at 0 0 180)
			(layer "F.Fab")
			(hide yes)
			(effects
				(font
					(size 1.27 1.27)
					(thickness 0.15)
				)
			)
		)
		(property "Author" "Antmicro"
			(at 371.708 235.194 0)
			(layer "F.Fab")
			(hide yes)
			(effects
				(font
					(size 1 1)
					(thickness 0.15)
				)
			)
		)
		(property "License" "Apache-2.0"
			(at 371.708 235.194 0)
			(layer "F.Fab")
			(hide yes)
			(effects
				(font
					(size 1 1)
					(thickness 0.15)
				)
			)
		)
		(property "MPN" "CR0402-FX-1001GLF"
			(at 371.708 235.194 0)
			(layer "F.Fab")
			(hide yes)
			(effects
				(font
					(size 1 1)
					(thickness 0.15)
				)
			)
		)
		(property "Manufacturer" "Bourns"
			(at 371.708 235.194 0)
			(layer "F.Fab")
			(hide yes)
			(effects
				(font
					(size 1 1)
					(thickness 0.15)
				)
			)
		)
		(property "Public" "False"
			(at 371.708 235.194 0)
			(layer "F.Fab")
			(hide yes)
			(effects
				(font
					(size 1 1)
					(thickness 0.15)
				)
			)
		)
		(property "Tolerance" "1%"
			(at 371.708 235.194 0)
			(layer "F.Fab")
			(hide yes)
			(effects
				(font
					(size 1 1)
					(thickness 0.15)
				)
			)
		)
		(property "Val" "1k"
			(at 371.708 235.194 0)
			(layer "F.Fab")
			(hide yes)
			(effects
				(font
					(size 1 1)
					(thickness 0.15)
				)
			)
		)
		(sheetfile "environment-sensor.kicad_sch")
		(attr smd)
		(fp_rect
			(start -0.925 -0.47)
			(end 0.925 0.47)
			(stroke
				(width 0.05)
				(type default)
			)
			(fill no)
			(layer "F.CrtYd")
		)
		(fp_rect
			(start -0.5 -0.25)
			(end 0.5 0.25)
			(stroke
				(width 0.15)
				(type solid)
			)
			(fill no)
			(layer "F.Fab")
		)
		(pad "1" smd roundrect
			(at -0.48 0 180)
			(size 0.59 0.64)
			(layers "F.Cu" "F.Mask" "F.Paste")
			(roundrect_rratio 0.25)
			(net 15 "/FRAM_WP")
			(pintype "passive")
		)
		(pad "2" smd roundrect
			(at 0.48 0 180)
			(size 0.59 0.64)
			(layers "F.Cu" "F.Mask" "F.Paste")
			(roundrect_rratio 0.25)
			(net 2 "+3V3")
			(pintype "passive")
		)
	)
	(footprint "antmicro-footprints:SOT-723"
		(layer "F.Cu")
		(at 201.6 117.95 180)
		(property "Reference" "D8"
			(at 1.1 -0.05 90)
			(layer "F.SilkS")
			(effects
				(font
					(size 0.65 0.65)
					(thickness 0.15)
				)
			)
		)
		(property "Value" "TPD2E009_SOT-9X3"
			(at -0.025 2.975 0)
			(layer "F.Fab")
			(effects
				(font
					(size 1 1)
					(thickness 0.15)
				)
			)
		)
		(property "Description" "TVS diode array, 8 kV, SOT-723, 5.5 V, 0.9 pF"
			(at 0 0 180)
			(layer "F.Fab")
			(hide yes)
			(effects
				(font
					(size 1.27 1.27)
					(thickness 0.15)
				)
			)
		)
		(property "Author" "Antmicro"
			(at 403.2 235.9 0)
			(layer "F.Fab")
			(hide yes)
			(effects
				(font
					(size 1 1)
					(thickness 0.15)
				)
			)
		)
		(property "License" "Apache-2.0"
			(at 403.2 235.9 0)
			(layer "F.Fab")
			(hide yes)
			(effects
				(font
					(size 1 1)
					(thickness 0.15)
				)
			)
		)
		(property "MPN" "TPD2E009DRTR"
			(at 403.2 235.9 0)
			(layer "F.Fab")
			(hide yes)
			(effects
				(font
					(size 1 1)
					(thickness 0.15)
				)
			)
		)
		(property "Manufacturer" "Texas Instruments"
			(at 403.2 235.9 0)
			(layer "F.Fab")
			(hide yes)
			(effects
				(font
					(size 1 1)
					(thickness 0.15)
				)
			)
		)
		(sheetfile "environment-sensor.kicad_sch")
		(attr smd)
		(fp_line
			(start 0.43 0.63)
			(end -0.22 0.63)
			(stroke
				(width 0.15)
				(type solid)
			)
			(layer "F.SilkS")
		)
		(fp_line
			(start 0.43 0.23)
			(end 0.43 0.63)
			(stroke
				(width 0.15)
				(type solid)
			)
			(layer "F.SilkS")
		)
		(fp_line
			(start 0.43 -0.23)
			(end 0.43 -0.63)
			(stroke
				(width 0.15)
				(type solid)
			)
			(layer "F.SilkS")
		)
		(fp_line
			(start 0.43 -0.63)
			(end -0.2175 -0.63)
			(stroke
				(width 0.15)
				(type solid)
			)
			(layer "F.SilkS")
		)
		(fp_line
			(start -0.43 -0.1375)
			(end -0.43 0.1375)
			(stroke
				(width 0.15)
				(type solid)
			)
			(layer "F.SilkS")
		)
		(fp_rect
			(start -0.83 -0.83)
			(end 0.83 0.83)
			(stroke
				(width 0.05)
				(type solid)
			)
			(fill no)
			(layer "F.CrtYd")
		)
		(fp_line
			(start 0.424 0.524)
			(end -0.424 0.524)
			(stroke
				(width 0.15)
				(type solid)
			)
			(layer "F.Fab")
		)
		(fp_line
			(start 0.424 -0.528)
			(end 0.424 0.524)
			(stroke
				(width 0.15)
				(type solid)
			)
			(layer "F.Fab")
		)
		(fp_line
			(start -0.09 -0.53)
			(end -0.43 -0.19)
			(stroke
				(width 0.15)
				(type solid)
			)
			(layer "F.Fab")
		)
		(fp_rect
			(start 0.424 0.524)
			(end -0.43 -0.528)
			(stroke
				(width 0.15)
				(type solid)
			)
			(fill no)
			(layer "F.Fab")
		)
		(fp_text user "${REFERENCE}"
			(at 0 0 0)
			(layer "F.Fab")
			(effects
				(font
					(size 0.2 0.2)
					(thickness 0.025)
				)
			)
		)
		(pad "1" smd rect
			(at -0.501 -0.401 90)
			(size 0.3 0.4)
			(layers "F.Cu" "F.Mask" "F.Paste")
			(net 8 "I2C_1_SCL")
			(pinfunction "1")
			(pintype "passive")
		)
		(pad "2" smd rect
			(at -0.501 0.399 90)
			(size 0.3 0.4)
			(layers "F.Cu" "F.Mask" "F.Paste")
			(net 9 "I2C_1_SDA")
			(pinfunction "2")
			(pintype "passive")
		)
		(pad "3" smd rect
			(at 0.499 -0.001 90)
			(size 0.3 0.4)
			(layers "F.Cu" "F.Mask" "F.Paste")
			(net 1 "GND")
			(pinfunction "3")
			(pintype "passive")
		)
	)
	(footprint "antmicro-footprints:C_0402_1005Metric"
		(layer "F.Cu")
		(at 198.479 128.999 180)
		(descr "Capacitor SMD 0402")
		(tags "capacitor SMD 0402")
		(property "Reference" "C15"
			(at -0.921 -0.301 180)
			(layer "F.SilkS")
			(effects
				(font
					(size 0.7 0.7)
					(thickness 0.15)
				)
				(justify left bottom)
			)
		)
		(property "Value" "C_100n_0402"
			(at 0 1.4 180)
			(layer "F.Fab")
			(effects
				(font
					(size 0.7 0.7)
					(thickness 0.15)
				)
				(justify left bottom)
			)
		)
		(property "Description" "SMD Multilayer Ceramic Capacitor, 0.1 µF, 50 V, 0402 [1005 Metric], ± 10%, X5R, GRM Series"
			(at 0 0 180)
			(layer "F.Fab")
			(hide yes)
			(effects
				(font
					(size 1.27 1.27)
					(thickness 0.15)
				)
			)
		)
		(property "Author" "Antmicro"
			(at 396.958 257.998 0)
			(layer "F.Fab")
			(hide yes)
			(effects
				(font
					(size 1 1)
					(thickness 0.15)
				)
			)
		)
		(property "Dielectric" "X5R"
			(at 396.958 257.998 0)
			(layer "F.Fab")
			(hide yes)
			(effects
				(font
					(size 1 1)
					(thickness 0.15)
				)
			)
		)
		(property "License" "Apache-2.0"
			(at 396.958 257.998 0)
			(layer "F.Fab")
			(hide yes)
			(effects
				(font
					(size 1 1)
					(thickness 0.15)
				)
			)
		)
		(property "MPN" "GRM155R61H104KE14D"
			(at 396.958 257.998 0)
			(layer "F.Fab")
			(hide yes)
			(effects
				(font
					(size 1 1)
					(thickness 0.15)
				)
			)
		)
		(property "Manufacturer" "Murata"
			(at 396.958 257.998 0)
			(layer "F.Fab")
			(hide yes)
			(effects
				(font
					(size 1 1)
					(thickness 0.15)
				)
			)
		)
		(property "Public" "False"
			(at 396.958 257.998 0)
			(layer "F.Fab")
			(hide yes)
			(effects
				(font
					(size 1 1)
					(thickness 0.15)
				)
			)
		)
		(property "Val" "100n"
			(at 396.958 257.998 0)
			(layer "F.Fab")
			(hide yes)
			(effects
				(font
					(size 1 1)
					(thickness 0.15)
				)
			)
		)
		(property "Voltage" "50V"
			(at 396.958 257.998 0)
			(layer "F.Fab")
			(hide yes)
			(effects
				(font
					(size 1 1)
					(thickness 0.15)
				)
			)
		)
		(sheetfile "environment-sensor.kicad_sch")
		(attr smd)
		(fp_rect
			(start -0.925 -0.47)
			(end 0.925 0.47)
			(stroke
				(width 0.05)
				(type default)
			)
			(fill no)
			(layer "F.CrtYd")
		)
		(fp_line
			(start 0.504 0.248)
			(end -0.494 0.248)
			(stroke
				(width 0.15)
				(type solid)
			)
			(layer "F.Fab")
		)
		(fp_line
			(start 0.504 -0.25)
			(end 0.504 0.248)
			(stroke
				(width 0.15)
				(type solid)
			)
			(layer "F.Fab")
		)
		(fp_line
			(start -0.494 0.248)
			(end -0.494 -0.25)
			(stroke
				(width 0.15)
				(type solid)
			)
			(layer "F.Fab")
		)
		(fp_line
			(start -0.494 -0.25)
			(end 0.504 -0.25)
			(stroke
				(width 0.15)
				(type solid)
			)
			(layer "F.Fab")
		)
		(pad "1" smd roundrect
			(at -0.48 0 180)
			(size 0.59 0.64)
			(layers "F.Cu" "F.Mask" "F.Paste")
			(roundrect_rratio 0.25)
			(net 1 "GND")
			(pintype "passive")
		)
		(pad "2" smd roundrect
			(at 0.48 0 180)
			(size 0.59 0.64)
			(layers "F.Cu" "F.Mask" "F.Paste")
			(roundrect_rratio 0.25)
			(net 2 "+3V3")
			(pintype "passive")
		)
	)
	(footprint "antmicro-footprints:USB-C_Receptacle_GCT_USB4105-GF-A"
		(layer "F.Cu")
		(at 162.652 126.75 -90)
		(property "Reference" "J1"
			(at -1.05 -5.198 90)
			(layer "F.SilkS")
			(effects
				(font
					(size 0.7 0.7)
					(thickness 0.15)
				)
				(justify right bottom)
			)
		)
		(property "Value" "USB-C_GCT_USB4105-GF-A"
			(at 0 5 90)
			(layer "F.Fab")
			(effects
				(font
					(size 0.7 0.7)
					(thickness 0.15)
				)
				(justify right bottom)
			)
		)
		(property "Description" "USB-C (USB TYPE-C) USB 2.0 Receptacle Connector 24 (16+8 Dummy) Position Surface Mount, Right Angle"
			(at 0 0 270)
			(layer "F.Fab")
			(hide yes)
			(effects
				(font
					(size 1.27 1.27)
					(thickness 0.15)
				)
			)
		)
		(property "Author" "Antmicro"
			(at 35.902 289.402 0)
			(layer "F.Fab")
			(hide yes)
			(effects
				(font
					(size 1 1)
					(thickness 0.15)
				)
			)
		)
		(property "License" "Apache-2.0"
			(at 35.902 289.402 0)
			(layer "F.Fab")
			(hide yes)
			(effects
				(font
					(size 1 1)
					(thickness 0.15)
				)
			)
		)
		(property "MPN" "USB4105-GF-A"
			(at 35.902 289.402 0)
			(layer "F.Fab")
			(hide yes)
			(effects
				(font
					(size 1 1)
					(thickness 0.15)
				)
			)
		)
		(property "Manufacturer" "GCT"
			(at 35.902 289.402 0)
			(layer "F.Fab")
			(hide yes)
			(effects
				(font
					(size 1 1)
					(thickness 0.15)
				)
			)
		)
		(property "VSD_Class" "USB-C"
			(at 35.902 289.402 0)
			(layer "F.Fab")
			(hide yes)
			(effects
				(font
					(size 1 1)
					(thickness 0.15)
				)
			)
		)
		(sheetfile "environment-sensor.kicad_sch")
		(attr smd)
		(fp_line
			(start -4.79 3.854)
			(end 4.788 3.854)
			(stroke
				(width 0.15)
				(type solid)
			)
			(layer "F.SilkS")
		)
		(fp_line
			(start 4.788 3.854)
			(end 4.788 2.575)
			(stroke
				(width 0.15)
				(type solid)
			)
			(layer "F.SilkS")
		)
		(fp_line
			(start -4.79 2.575)
			(end -4.79 3.854)
			(stroke
				(width 0.15)
				(type solid)
			)
			(layer "F.SilkS")
		)
		(fp_line
			(start -4.79 -1.395)
			(end -4.79 -0.145)
			(stroke
				(width 0.15)
				(type solid)
			)
			(layer "F.SilkS")
		)
		(fp_line
			(start 4.788 -1.395)
			(end 4.788 -0.145)
			(stroke
				(width 0.15)
				(type solid)
			)
			(layer "F.SilkS")
		)
		(fp_circle
			(center -3.8 -4.27071)
			(end -3.75 -4.22071)
			(stroke
				(width 0.15)
				(type solid)
			)
			(fill yes)
			(layer "F.SilkS")
		)
		(fp_rect
			(start -5.1 -4.4)
			(end 5.1 3.9)
			(stroke
				(width 0.05)
				(type solid)
			)
			(fill no)
			(layer "F.CrtYd")
		)
		(fp_line
			(start -4.79 3.854)
			(end -4.79 -3.676)
			(stroke
				(width 0.15)
				(type solid)
			)
			(layer "F.Fab")
		)
		(fp_line
			(start -4.702 3.854)
			(end 4.788 3.854)
			(stroke
				(width 0.15)
				(type solid)
			)
			(layer "F.Fab")
		)
		(fp_line
			(start 4.788 3.854)
			(end -4.79 3.854)
			(stroke
				(width 0.15)
				(type solid)
			)
			(layer "F.Fab")
		)
		(fp_line
			(start -4.79 -3.676)
			(end 4.788 -3.676)
			(stroke
				(width 0.15)
				(type solid)
			)
			(layer "F.Fab")
		)
		(fp_line
			(start 4.788 -3.676)
			(end 4.788 3.854)
			(stroke
				(width 0.15)
				(type solid)
			)
			(layer "F.Fab")
		)
		(pad "" np_thru_hole circle
			(at -2.891 -2.426 270)
			(size 0.65 0.65)
			(drill 0.65)
			(layers "*.Cu" "*.Mask")
		)
		(pad "" np_thru_hole circle
			(at 2.89 -2.426 270)
			(size 0.65 0.65)
			(drill 0.65)
			(layers "*.Cu" "*.Mask")
		)
		(pad "A1" smd roundrect
			(at -3.202 -3.5 270)
			(size 0.6 1.15)
			(layers "F.Cu" "F.Mask" "F.Paste")
			(roundrect_rratio 0.25)
			(net 1 "GND")
			(pinfunction "GND")
			(pintype "power_in")
		)
		(pad "A4" smd roundrect
			(at -2.4 -3.5 270)
			(size 0.6 1.15)
			(layers "F.Cu" "F.Mask" "F.Paste")
			(roundrect_rratio 0.25)
			(net 27 "/VBUS")
			(pinfunction "VBUS")
			(pintype "passive")
		)
		(pad "A5" smd roundrect
			(at -1.25 -3.5 270)
			(size 0.3 1.15)
			(layers "F.Cu" "F.Mask" "F.Paste")
			(roundrect_rratio 0.25)
			(net 4 "/USB_CC1")
			(pinfunction "CC_{1}")
			(pintype "bidirectional")
		)
		(pad "A6" smd roundrect
			(at -0.25 -3.5 270)
			(size 0.3 1.15)
			(layers "F.Cu" "F.Mask" "F.Paste")
			(roundrect_rratio 0.25)
			(net 6 "/USB_D_P")
			(pinfunction "D_{A}+")
			(pintype "bidirectional")
		)
		(pad "A7" smd roundrect
			(at 0.248 -3.5 270)
			(size 0.3 1.15)
			(layers "F.Cu" "F.Mask" "F.Paste")
			(roundrect_rratio 0.25)
			(net 7 "/USB_D_N")
			(pinfunction "D_{A}-")
			(pintype "bidirectional")
		)
		(pad "A8" smd roundrect
			(at 1.249 -3.5 270)
			(size 0.3 1.15)
			(layers "F.Cu" "F.Mask" "F.Paste")
			(roundrect_rratio 0.25)
			(net 34 "unconnected-(J1-SBU_{1}-PadA8)")
			(pinfunction "SBU_{1}")
			(pintype "bidirectional+no_connect")
		)
		(pad "A9" smd roundrect
			(at 2.398 -3.5 270)
			(size 0.6 1.15)
			(layers "F.Cu" "F.Mask" "F.Paste")
			(roundrect_rratio 0.25)
			(net 27 "/VBUS")
			(pinfunction "VBUS")
			(pintype "passive")
		)
		(pad "A12" smd roundrect
			(at 3.2 -3.5 270)
			(size 0.6 1.15)
			(layers "F.Cu" "F.Mask" "F.Paste")
			(roundrect_rratio 0.25)
			(net 1 "GND")
			(pinfunction "GND")
			(pintype "passive")
		)
		(pad "B1" smd roundrect
			(at 3.2 -3.5 270)
			(size 0.6 1.15)
			(layers "F.Cu" "F.Mask" "F.Paste")
			(roundrect_rratio 0.25)
			(net 1 "GND")
			(pinfunction "GND")
			(pintype "passive")
		)
		(pad "B4" smd roundrect
			(at 2.398 -3.5 270)
			(size 0.6 1.15)
			(layers "F.Cu" "F.Mask" "F.Paste")
			(roundrect_rratio 0.25)
			(net 27 "/VBUS")
			(pinfunction "VBUS")
			(pintype "passive")
		)
		(pad "B5" smd roundrect
			(at 1.749 -3.5 270)
			(size 0.3 1.15)
			(layers "F.Cu" "F.Mask" "F.Paste")
			(roundrect_rratio 0.25)
			(net 5 "/USB_CC2")
			(pinfunction "CC_{2}")
			(pintype "bidirectional")
		)
		(pad "B6" smd roundrect
			(at 0.748 -3.5 270)
			(size 0.3 1.15)
			(layers "F.Cu" "F.Mask" "F.Paste")
			(roundrect_rratio 0.25)
			(net 6 "/USB_D_P")
			(pinfunction "D_{B}+")
			(pintype "bidirectional")
		)
		(pad "B7" smd roundrect
			(at -0.75 -3.5 270)
			(size 0.3 1.15)
			(layers "F.Cu" "F.Mask" "F.Paste")
			(roundrect_rratio 0.25)
			(net 7 "/USB_D_N")
			(pinfunction "D_{B}-")
			(pintype "bidirectional")
		)
		(pad "B8" smd roundrect
			(at -1.75 -3.5 270)
			(size 0.3 1.15)
			(layers "F.Cu" "F.Mask" "F.Paste")
			(roundrect_rratio 0.25)
			(net 35 "unconnected-(J1-SBU_{2}-PadB8)")
			(pinfunction "SBU_{2}")
			(pintype "bidirectional+no_connect")
		)
		(pad "B9" smd roundrect
			(at -2.4 -3.5 270)
			(size 0.6 1.15)
			(layers "F.Cu" "F.Mask" "F.Paste")
			(roundrect_rratio 0.25)
			(net 27 "/VBUS")
			(pinfunction "VBUS")
			(pintype "passive")
		)
		(pad "B12" smd roundrect
			(at -3.202 -3.5 270)
			(size 0.6 1.15)
			(layers "F.Cu" "F.Mask" "F.Paste")
			(roundrect_rratio 0.25)
			(net 1 "GND")
			(pinfunction "GND")
			(pintype "passive")
		)
		(pad "SH" thru_hole oval
			(at -4.321 -2.926 270)
			(size 1.05 2.1)
			(drill oval 0.6 1.7)
			(layers "*.Cu" "*.Mask")
			(remove_unused_layers no)
			(net 3 "GNDREF")
			(pinfunction "SH")
			(pintype "passive")
		)
		(pad "SH" thru_hole oval
			(at -4.321 1.255 270)
			(size 1 2)
			(drill oval 0.6 1.4)
			(layers "*.Cu" "*.Mask")
			(remove_unused_layers no)
			(net 3 "GNDREF")
			(pinfunction "SH")
			(pintype "passive")
		)
		(pad "SH" thru_hole oval
			(at 4.32 -2.926 270)
			(size 1.05 2.1)
			(drill oval 0.6 1.7)
			(layers "*.Cu" "*.Mask")
			(remove_unused_layers no)
			(net 3 "GNDREF")
			(pinfunction "SH")
			(pintype "passive")
		)
		(pad "SH" thru_hole oval
			(at 4.32 1.255 270)
			(size 1 2)
			(drill oval 0.6 1.4)
			(layers "*.Cu" "*.Mask")
			(remove_unused_layers no)
			(net 3 "GNDREF")
			(pinfunction "SH")
			(pintype "passive")
		)
	)
	(footprint "antmicro-footprints:R_0402_1005Metric"
		(layer "F.Cu")
		(at 169.985 123.7)
		(descr "Resistor SMD 0402")
		(tags "resistor SMD 0402")
		(property "Reference" "R3"
			(at 0.865 0.35 0)
			(layer "F.SilkS")
			(effects
				(font
					(size 0.7 0.7)
					(thickness 0.15)
				)
				(justify left bottom)
			)
		)
		(property "Value" "R_5k1_0402"
			(at 0 1.4 0)
			(layer "F.Fab")
			(effects
				(font
					(size 0.7 0.7)
					(thickness 0.15)
				)
				(justify left bottom)
			)
		)
		(property "Description" "SMD Chip Resistor, 5.1 kohm, ± 1%, 63 mW, 0402 [1005 Metric], Thick Film, General Purpose"
			(at 0 0 0)
			(layer "F.Fab")
			(hide yes)
			(effects
				(font
					(size 1.27 1.27)
					(thickness 0.15)
				)
			)
		)
		(property "Author" "Antmicro"
			(at 0 0 0)
			(layer "F.Fab")
			(hide yes)
			(effects
				(font
					(size 1 1)
					(thickness 0.15)
				)
			)
		)
		(property "License" "Apache-2.0"
			(at 0 0 0)
			(layer "F.Fab")
			(hide yes)
			(effects
				(font
					(size 1 1)
					(thickness 0.15)
				)
			)
		)
		(property "MPN" "CR0402-FX-5101GLF"
			(at 0 0 0)
			(layer "F.Fab")
			(hide yes)
			(effects
				(font
					(size 1 1)
					(thickness 0.15)
				)
			)
		)
		(property "Manufacturer" "Bourns"
			(at 0 0 0)
			(layer "F.Fab")
			(hide yes)
			(effects
				(font
					(size 1 1)
					(thickness 0.15)
				)
			)
		)
		(property "Public" "False"
			(at 0 0 0)
			(layer "F.Fab")
			(hide yes)
			(effects
				(font
					(size 1 1)
					(thickness 0.15)
				)
			)
		)
		(property "Tolerance" "1%"
			(at 0 0 0)
			(layer "F.Fab")
			(hide yes)
			(effects
				(font
					(size 1 1)
					(thickness 0.15)
				)
			)
		)
		(property "Val" "5k1"
			(at 0 0 0)
			(layer "F.Fab")
			(hide yes)
			(effects
				(font
					(size 1 1)
					(thickness 0.15)
				)
			)
		)
		(sheetfile "environment-sensor.kicad_sch")
		(attr smd)
		(fp_rect
			(start -0.925 -0.47)
			(end 0.925 0.47)
			(stroke
				(width 0.05)
				(type default)
			)
			(fill no)
			(layer "F.CrtYd")
		)
		(fp_rect
			(start -0.5 -0.25)
			(end 0.5 0.25)
			(stroke
				(width 0.15)
				(type solid)
			)
			(fill no)
			(layer "F.Fab")
		)
		(pad "1" smd roundrect
			(at -0.48 0)
			(size 0.59 0.64)
			(layers "F.Cu" "F.Mask" "F.Paste")
			(roundrect_rratio 0.25)
			(net 1 "GND")
			(pintype "passive")
		)
		(pad "2" smd roundrect
			(at 0.48 0)
			(size 0.59 0.64)
			(layers "F.Cu" "F.Mask" "F.Paste")
			(roundrect_rratio 0.25)
			(net 4 "/USB_CC1")
			(pintype "passive")
		)
	)
	(footprint "antmicro-footprints:R_0402_1005Metric"
		(layer "F.Cu")
		(at 182.5 138.4 90)
		(descr "Resistor SMD 0402")
		(tags "resistor SMD 0402")
		(property "Reference" "R19"
			(at 20.346 -0.4185 90)
			(layer "B.SilkS")
			(effects
				(font
					(size 0.7 0.7)
					(thickness 0.15)
				)
				(justify left bottom mirror)
			)
		)
		(property "Value" "R_100k_0402"
			(at 0 1.4 90)
			(layer "F.Fab")
			(effects
				(font
					(size 0.7 0.7)
					(thickness 0.15)
				)
				(justify left bottom)
			)
		)
		(property "Description" "SMD Chip Resistor, 100 kohm, ± 1%, 62.5 mW, 0402 [1005 Metric], Thick Film, General Purpose"
			(at 0 0 90)
			(layer "F.Fab")
			(hide yes)
			(effects
				(font
					(size 1.27 1.27)
					(thickness 0.15)
				)
			)
		)
		(property "Author" "Antmicro"
			(at 320.9 -44.1 0)
			(layer "F.Fab")
			(hide yes)
			(effects
				(font
					(size 1 1)
					(thickness 0.15)
				)
			)
		)
		(property "License" "Apache-2.0"
			(at 320.9 -44.1 0)
			(layer "F.Fab")
			(hide yes)
			(effects
				(font
					(size 1 1)
					(thickness 0.15)
				)
			)
		)
		(property "MPN" "CR0402-FX-1003GLF"
			(at 320.9 -44.1 0)
			(layer "F.Fab")
			(hide yes)
			(effects
				(font
					(size 1 1)
					(thickness 0.15)
				)
			)
		)
		(property "Manufacturer" "Bourns"
			(at 320.9 -44.1 0)
			(layer "F.Fab")
			(hide yes)
			(effects
				(font
					(size 1 1)
					(thickness 0.15)
				)
			)
		)
		(property "Public" "False"
			(at 320.9 -44.1 0)
			(layer "F.Fab")
			(hide yes)
			(effects
				(font
					(size 1 1)
					(thickness 0.15)
				)
			)
		)
		(property "Tolerance" "1%"
			(at 320.9 -44.1 0)
			(layer "F.Fab")
			(hide yes)
			(effects
				(font
					(size 1 1)
					(thickness 0.15)
				)
			)
		)
		(property "Val" "100k"
			(at 320.9 -44.1 0)
			(layer "F.Fab")
			(hide yes)
			(effects
				(font
					(size 1 1)
					(thickness 0.15)
				)
			)
		)
		(sheetfile "environment-sensor.kicad_sch")
		(attr smd)
		(fp_rect
			(start -0.925 -0.47)
			(end 0.925 0.47)
			(stroke
				(width 0.05)
				(type default)
			)
			(fill no)
			(layer "F.CrtYd")
		)
		(fp_rect
			(start -0.5 -0.25)
			(end 0.5 0.25)
			(stroke
				(width 0.15)
				(type solid)
			)
			(fill no)
			(layer "F.Fab")
		)
		(pad "1" smd roundrect
			(at -0.48 0 90)
			(size 0.59 0.64)
			(layers "F.Cu" "F.Mask" "F.Paste")
			(roundrect_rratio 0.25)
			(net 14 "NRST")
			(pintype "passive")
		)
		(pad "2" smd roundrect
			(at 0.48 0 90)
			(size 0.59 0.64)
			(layers "F.Cu" "F.Mask" "F.Paste")
			(roundrect_rratio 0.25)
			(net 2 "+3V3")
			(pintype "passive")
		)
	)
	(footprint "antmicro-footprints:R_0402_1005Metric"
		(layer "F.Cu")
		(at 182.729 120.6235)
		(descr "Resistor SMD 0402")
		(tags "resistor SMD 0402")
		(property "Reference" "R34"
			(at -3.129 0.3765 180)
			(layer "F.SilkS")
			(effects
				(font
					(size 0.7 0.7)
					(thickness 0.15)
				)
				(justify left bottom)
			)
		)
		(property "Value" "R_100k_0402"
			(at 0 1.4 0)
			(layer "F.Fab")
			(effects
				(font
					(size 0.7 0.7)
					(thickness 0.15)
				)
				(justify left bottom)
			)
		)
		(property "Description" "SMD Chip Resistor, 100 kohm, ± 1%, 62.5 mW, 0402 [1005 Metric], Thick Film, General Purpose"
			(at 0 0 0)
			(layer "F.Fab")
			(hide yes)
			(effects
				(font
					(size 1.27 1.27)
					(thickness 0.15)
				)
			)
		)
		(property "Author" "Antmicro"
			(at 0 0 0)
			(layer "F.Fab")
			(hide yes)
			(effects
				(font
					(size 1 1)
					(thickness 0.15)
				)
			)
		)
		(property "License" "Apache-2.0"
			(at 0 0 0)
			(layer "F.Fab")
			(hide yes)
			(effects
				(font
					(size 1 1)
					(thickness 0.15)
				)
			)
		)
		(property "MPN" "CR0402-FX-1003GLF"
			(at 0 0 0)
			(layer "F.Fab")
			(hide yes)
			(effects
				(font
					(size 1 1)
					(thickness 0.15)
				)
			)
		)
		(property "Manufacturer" "Bourns"
			(at 0 0 0)
			(layer "F.Fab")
			(hide yes)
			(effects
				(font
					(size 1 1)
					(thickness 0.15)
				)
			)
		)
		(property "Public" "False"
			(at 0 0 0)
			(layer "F.Fab")
			(hide yes)
			(effects
				(font
					(size 1 1)
					(thickness 0.15)
				)
			)
		)
		(property "Tolerance" "1%"
			(at 0 0 0)
			(layer "F.Fab")
			(hide yes)
			(effects
				(font
					(size 1 1)
					(thickness 0.15)
				)
			)
		)
		(property "Val" "100k"
			(at 0 0 0)
			(layer "F.Fab")
			(hide yes)
			(effects
				(font
					(size 1 1)
					(thickness 0.15)
				)
			)
		)
		(sheetfile "environment-sensor.kicad_sch")
		(attr smd)
		(fp_rect
			(start -0.925 -0.47)
			(end 0.925 0.47)
			(stroke
				(width 0.05)
				(type default)
			)
			(fill no)
			(layer "F.CrtYd")
		)
		(fp_rect
			(start -0.5 -0.25)
			(end 0.5 0.25)
			(stroke
				(width 0.15)
				(type solid)
			)
			(fill no)
			(layer "F.Fab")
		)
		(pad "1" smd roundrect
			(at -0.48 0)
			(size 0.59 0.64)
			(layers "F.Cu" "F.Mask" "F.Paste")
			(roundrect_rratio 0.25)
			(net 1 "GND")
			(pintype "passive")
		)
		(pad "2" smd roundrect
			(at 0.48 0)
			(size 0.59 0.64)
			(layers "F.Cu" "F.Mask" "F.Paste")
			(roundrect_rratio 0.25)
			(net 52 "Net-(U4-A2)")
			(pintype "passive")
		)
	)
	(footprint "antmicro-footprints:R_0402_1005Metric"
		(layer "F.Cu")
		(at 181.744 126.25 90)
		(descr "Resistor SMD 0402")
		(tags "resistor SMD 0402")
		(property "Reference" "R10"
			(at 11.75 1.156 90)
			(layer "B.SilkS")
			(effects
				(font
					(size 0.7 0.7)
					(thickness 0.15)
				)
				(justify left bottom mirror)
			)
		)
		(property "Value" "R_0R_0402"
			(at 0 1.4 90)
			(layer "F.Fab")
			(effects
				(font
					(size 0.7 0.7)
					(thickness 0.15)
				)
				(justify left bottom)
			)
		)
		(property "Description" "SMD Chip Resistor, Jumper, 0 ohm, 100 mW, 0402 [1005 Metric], Thick Film, General Purpose"
			(at 0 0 90)
			(layer "F.Fab")
			(hide yes)
			(effects
				(font
					(size 1.27 1.27)
					(thickness 0.15)
				)
			)
		)
		(property "Author" "Antmicro"
			(at 307.994 -55.494 0)
			(layer "F.Fab")
			(hide yes)
			(effects
				(font
					(size 1 1)
					(thickness 0.15)
				)
			)
		)
		(property "Current" "1A"
			(at 307.994 -55.494 0)
			(layer "F.Fab")
			(hide yes)
			(effects
				(font
					(size 1 1)
					(thickness 0.15)
				)
			)
		)
		(property "License" "Apache-2.0"
			(at 307.994 -55.494 0)
			(layer "F.Fab")
			(hide yes)
			(effects
				(font
					(size 1 1)
					(thickness 0.15)
				)
			)
		)
		(property "MPN" "ERJ2GE0R00X"
			(at 307.994 -55.494 0)
			(layer "F.Fab")
			(hide yes)
			(effects
				(font
					(size 1 1)
					(thickness 0.15)
				)
			)
		)
		(property "Manufacturer" "Panasonic"
			(at 307.994 -55.494 0)
			(layer "F.Fab")
			(hide yes)
			(effects
				(font
					(size 1 1)
					(thickness 0.15)
				)
			)
		)
		(property "Public" "False"
			(at 307.994 -55.494 0)
			(layer "F.Fab")
			(hide yes)
			(effects
				(font
					(size 1 1)
					(thickness 0.15)
				)
			)
		)
		(property "Tolerance" ""
			(at 307.994 -55.494 0)
			(layer "F.Fab")
			(hide yes)
			(effects
				(font
					(size 1 1)
					(thickness 0.15)
				)
			)
		)
		(property "Val" "0R"
			(at 307.994 -55.494 0)
			(layer "F.Fab")
			(hide yes)
			(effects
				(font
					(size 1 1)
					(thickness 0.15)
				)
			)
		)
		(sheetfile "environment-sensor.kicad_sch")
		(attr smd)
		(fp_rect
			(start -0.925 -0.47)
			(end 0.925 0.47)
			(stroke
				(width 0.05)
				(type default)
			)
			(fill no)
			(layer "F.CrtYd")
		)
		(fp_rect
			(start -0.5 -0.25)
			(end 0.5 0.25)
			(stroke
				(width 0.15)
				(type solid)
			)
			(fill no)
			(layer "F.Fab")
		)
		(pad "1" smd roundrect
			(at -0.48 0 90)
			(size 0.59 0.64)
			(layers "F.Cu" "F.Mask" "F.Paste")
			(roundrect_rratio 0.25)
			(net 42 "Net-(U1-RI#)")
			(pintype "passive")
		)
		(pad "2" smd roundrect
			(at 0.48 0 90)
			(size 0.59 0.64)
			(layers "F.Cu" "F.Mask" "F.Paste")
			(roundrect_rratio 0.25)
			(net 25 "JTDI")
			(pintype "passive")
		)
	)
	(footprint "antmicro-footprints:R_0402_1005Metric"
		(layer "F.Cu")
		(at 198.5 130.3 180)
		(descr "Resistor SMD 0402")
		(tags "resistor SMD 0402")
		(property "Reference" "R37"
			(at -0.85 -0.5 180)
			(layer "F.SilkS")
			(effects
				(font
					(size 0.7 0.7)
					(thickness 0.15)
				)
				(justify left bottom)
			)
		)
		(property "Value" "R_5k1_0402"
			(at 0 1.4 180)
			(layer "F.Fab")
			(effects
				(font
					(size 0.7 0.7)
					(thickness 0.15)
				)
				(justify left bottom)
			)
		)
		(property "Description" "SMD Chip Resistor, 5.1 kohm, ± 1%, 63 mW, 0402 [1005 Metric], Thick Film, General Purpose"
			(at 0 0 180)
			(layer "F.Fab")
			(hide yes)
			(effects
				(font
					(size 1.27 1.27)
					(thickness 0.15)
				)
			)
		)
		(property "Author" "Antmicro"
			(at 397 260.6 0)
			(layer "F.Fab")
			(hide yes)
			(effects
				(font
					(size 1 1)
					(thickness 0.15)
				)
			)
		)
		(property "License" "Apache-2.0"
			(at 397 260.6 0)
			(layer "F.Fab")
			(hide yes)
			(effects
				(font
					(size 1 1)
					(thickness 0.15)
				)
			)
		)
		(property "MPN" "CR0402-FX-5101GLF"
			(at 397 260.6 0)
			(layer "F.Fab")
			(hide yes)
			(effects
				(font
					(size 1 1)
					(thickness 0.15)
				)
			)
		)
		(property "Manufacturer" "Bourns"
			(at 397 260.6 0)
			(layer "F.Fab")
			(hide yes)
			(effects
				(font
					(size 1 1)
					(thickness 0.15)
				)
			)
		)
		(property "Public" "False"
			(at 397 260.6 0)
			(layer "F.Fab")
			(hide yes)
			(effects
				(font
					(size 1 1)
					(thickness 0.15)
				)
			)
		)
		(property "Tolerance" "1%"
			(at 397 260.6 0)
			(layer "F.Fab")
			(hide yes)
			(effects
				(font
					(size 1 1)
					(thickness 0.15)
				)
			)
		)
		(property "Val" "5k1"
			(at 397 260.6 0)
			(layer "F.Fab")
			(hide yes)
			(effects
				(font
					(size 1 1)
					(thickness 0.15)
				)
			)
		)
		(sheetfile "environment-sensor.kicad_sch")
		(attr smd)
		(fp_rect
			(start -0.925 -0.47)
			(end 0.925 0.47)
			(stroke
				(width 0.05)
				(type default)
			)
			(fill no)
			(layer "F.CrtYd")
		)
		(fp_rect
			(start -0.5 -0.25)
			(end 0.5 0.25)
			(stroke
				(width 0.15)
				(type solid)
			)
			(fill no)
			(layer "F.Fab")
		)
		(pad "1" smd roundrect
			(at -0.48 0 180)
			(size 0.59 0.64)
			(layers "F.Cu" "F.Mask" "F.Paste")
			(roundrect_rratio 0.25)
			(net 8 "I2C_1_SCL")
			(pintype "passive")
		)
		(pad "2" smd roundrect
			(at 0.48 0 180)
			(size 0.59 0.64)
			(layers "F.Cu" "F.Mask" "F.Paste")
			(roundrect_rratio 0.25)
			(net 2 "+3V3")
			(pintype "passive")
		)
	)
	(footprint "antmicro-footprints:SOD-923"
		(layer "F.Cu")
		(at 202.5 115.6 -90)
		(property "Reference" "D9"
			(at -1.3 0 90)
			(unlocked yes)
			(layer "F.SilkS")
			(effects
				(font
					(size 0.65 0.65)
					(thickness 0.15)
				)
			)
		)
		(property "Value" "ESD9X5.0ST5G"
			(at 0 2.4 270)
			(unlocked yes)
			(layer "F.Fab")
			(effects
				(font
					(size 1 1)
					(thickness 0.15)
				)
			)
		)
		(property "Description" "Unidirectional TVS, 30 kV,  SOD-923, 5 V, 65 pF"
			(at 0 0 270)
			(layer "F.Fab")
			(hide yes)
			(effects
				(font
					(size 1.27 1.27)
					(thickness 0.15)
				)
			)
		)
		(property "Author" "Antmicro"
			(at 86.9 318.1 0)
			(layer "F.Fab")
			(hide yes)
			(effects
				(font
					(size 1 1)
					(thickness 0.15)
				)
			)
		)
		(property "License" "Apache-2.0"
			(at 86.9 318.1 0)
			(layer "F.Fab")
			(hide yes)
			(effects
				(font
					(size 1 1)
					(thickness 0.15)
				)
			)
		)
		(property "MPN" "ESD9X5.0ST5G"
			(at 86.9 318.1 0)
			(layer "F.Fab")
			(hide yes)
			(effects
				(font
					(size 1 1)
					(thickness 0.15)
				)
			)
		)
		(property "Manufacturer" "ON Semiconductor"
			(at 86.9 318.1 0)
			(layer "F.Fab")
			(hide yes)
			(effects
				(font
					(size 1 1)
					(thickness 0.15)
				)
			)
		)
		(property "Public" "False"
			(at 86.9 318.1 0)
			(layer "F.Fab")
			(hide yes)
			(effects
				(font
					(size 1 1)
					(thickness 0.15)
				)
			)
		)
		(sheetfile "environment-sensor.kicad_sch")
		(attr smd)
		(fp_line
			(start -0.5 0.4)
			(end 0.5 0.4)
			(stroke
				(width 0.15)
				(type solid)
			)
			(layer "F.SilkS")
		)
		(fp_line
			(start -0.5 0.4)
			(end -0.5 0.3)
			(stroke
				(width 0.15)
				(type solid)
			)
			(layer "F.SilkS")
		)
		(fp_line
			(start 0.5 0.4)
			(end 0.5 0.3)
			(stroke
				(width 0.15)
				(type solid)
			)
			(layer "F.SilkS")
		)
		(fp_line
			(start -0.5 -0.3)
			(end -0.5 -0.4)
			(stroke
				(width 0.15)
				(type solid)
			)
			(layer "F.SilkS")
		)
		(fp_line
			(start -0.5 -0.4)
			(end 0.5 -0.4)
			(stroke
				(width 0.15)
				(type solid)
			)
			(layer "F.SilkS")
		)
		(fp_line
			(start -0.16 -0.4)
			(end -0.16 0.4)
			(stroke
				(width 0.15)
				(type solid)
			)
			(layer "F.SilkS")
		)
		(fp_line
			(start 0.5 -0.4)
			(end 0.5 -0.3)
			(stroke
				(width 0.15)
				(type solid)
			)
			(layer "F.SilkS")
		)
		(fp_rect
			(start -0.68 -0.41)
			(end 0.68 0.41)
			(stroke
				(width 0.05)
				(type solid)
			)
			(fill no)
			(layer "F.CrtYd")
		)
		(fp_line
			(start -0.202 -0.3)
			(end -0.202 0.298)
			(stroke
				(width 0.15)
				(type solid)
			)
			(layer "F.Fab")
		)
		(fp_rect
			(start -0.402 -0.3)
			(end 0.4 0.298)
			(stroke
				(width 0.15)
				(type solid)
			)
			(fill no)
			(layer "F.Fab")
		)
		(fp_text user "${REFERENCE}"
			(at 0 1.1 270)
			(unlocked yes)
			(layer "F.Fab")
			(effects
				(font
					(size 1 1)
					(thickness 0.15)
				)
			)
		)
		(pad "1" smd roundrect
			(at -0.438 0 270)
			(size 0.4 0.325)
			(layers "F.Cu" "F.Mask" "F.Paste")
			(roundrect_rratio 0.25)
			(net 1 "GND")
			(pinfunction "C")
			(pintype "passive")
		)
		(pad "2" smd roundrect
			(at 0.436 0 270)
			(size 0.4 0.325)
			(layers "F.Cu" "F.Mask" "F.Paste")
			(roundrect_rratio 0.25)
			(net 2 "+3V3")
			(pinfunction "A")
			(pintype "passive")
		)
	)
	(footprint "antmicro-footprints:R_0402_1005Metric"
		(layer "F.Cu")
		(at 179.75 126.25 -90)
		(descr "Resistor SMD 0402")
		(tags "resistor SMD 0402")
		(property "Reference" "R24"
			(at -9.6 -1.35 90)
			(layer "B.SilkS")
			(effects
				(font
					(size 0.7 0.7)
					(thickness 0.15)
				)
				(justify right bottom mirror)
			)
		)
		(property "Value" "R_100k_0402"
			(at 0 1.4 90)
			(layer "F.Fab")
			(effects
				(font
					(size 0.7 0.7)
					(thickness 0.15)
				)
				(justify right bottom)
			)
		)
		(property "Description" "SMD Chip Resistor, 100 kohm, ± 1%, 62.5 mW, 0402 [1005 Metric], Thick Film, General Purpose"
			(at 0 0 270)
			(layer "F.Fab")
			(hide yes)
			(effects
				(font
					(size 1.27 1.27)
					(thickness 0.15)
				)
			)
		)
		(property "Author" "Antmicro"
			(at 53.5 306 0)
			(layer "F.Fab")
			(hide yes)
			(effects
				(font
					(size 1 1)
					(thickness 0.15)
				)
			)
		)
		(property "License" "Apache-2.0"
			(at 53.5 306 0)
			(layer "F.Fab")
			(hide yes)
			(effects
				(font
					(size 1 1)
					(thickness 0.15)
				)
			)
		)
		(property "MPN" "CR0402-FX-1003GLF"
			(at 53.5 306 0)
			(layer "F.Fab")
			(hide yes)
			(effects
				(font
					(size 1 1)
					(thickness 0.15)
				)
			)
		)
		(property "Manufacturer" "Bourns"
			(at 53.5 306 0)
			(layer "F.Fab")
			(hide yes)
			(effects
				(font
					(size 1 1)
					(thickness 0.15)
				)
			)
		)
		(property "Public" "False"
			(at 53.5 306 0)
			(layer "F.Fab")
			(hide yes)
			(effects
				(font
					(size 1 1)
					(thickness 0.15)
				)
			)
		)
		(property "Tolerance" "1%"
			(at 53.5 306 0)
			(layer "F.Fab")
			(hide yes)
			(effects
				(font
					(size 1 1)
					(thickness 0.15)
				)
			)
		)
		(property "Val" "100k"
			(at 53.5 306 0)
			(layer "F.Fab")
			(hide yes)
			(effects
				(font
					(size 1 1)
					(thickness 0.15)
				)
			)
		)
		(sheetfile "environment-sensor.kicad_sch")
		(attr smd)
		(fp_rect
			(start -0.925 -0.47)
			(end 0.925 0.47)
			(stroke
				(width 0.05)
				(type default)
			)
			(fill no)
			(layer "F.CrtYd")
		)
		(fp_rect
			(start -0.5 -0.25)
			(end 0.5 0.25)
			(stroke
				(width 0.15)
				(type solid)
			)
			(fill no)
			(layer "F.Fab")
		)
		(pad "1" smd roundrect
			(at -0.48 0 270)
			(size 0.59 0.64)
			(layers "F.Cu" "F.Mask" "F.Paste")
			(roundrect_rratio 0.25)
			(net 13 "JTRST")
			(pintype "passive")
		)
		(pad "2" smd roundrect
			(at 0.48 0 270)
			(size 0.59 0.64)
			(layers "F.Cu" "F.Mask" "F.Paste")
			(roundrect_rratio 0.25)
			(net 2 "+3V3")
			(pintype "passive")
		)
	)
	(footprint "antmicro-footprints:C_0402_1005Metric"
		(layer "F.Cu")
		(at 188.194 125.087 90)
		(descr "Capacitor SMD 0402")
		(tags "capacitor SMD 0402")
		(property "Reference" "C12"
			(at 5.91 6.906 180)
			(layer "F.SilkS")
			(effects
				(font
					(size 0.7 0.7)
					(thickness 0.15)
				)
				(justify left bottom)
			)
		)
		(property "Value" "C_100n_0402"
			(at 0 1.4 90)
			(layer "F.Fab")
			(effects
				(font
					(size 0.7 0.7)
					(thickness 0.15)
				)
				(justify left bottom)
			)
		)
		(property "Description" "SMD Multilayer Ceramic Capacitor, 0.1 µF, 50 V, 0402 [1005 Metric], ± 10%, X5R, GRM Series"
			(at 0 0 90)
			(layer "F.Fab")
			(hide yes)
			(effects
				(font
					(size 1.27 1.27)
					(thickness 0.15)
				)
			)
		)
		(property "Author" "Antmicro"
			(at 313.281 -63.107 0)
			(layer "F.Fab")
			(hide yes)
			(effects
				(font
					(size 1 1)
					(thickness 0.15)
				)
			)
		)
		(property "Dielectric" "X5R"
			(at 313.281 -63.107 0)
			(layer "F.Fab")
			(hide yes)
			(effects
				(font
					(size 1 1)
					(thickness 0.15)
				)
			)
		)
		(property "License" "Apache-2.0"
			(at 313.281 -63.107 0)
			(layer "F.Fab")
			(hide yes)
			(effects
				(font
					(size 1 1)
					(thickness 0.15)
				)
			)
		)
		(property "MPN" "GRM155R61H104KE14D"
			(at 313.281 -63.107 0)
			(layer "F.Fab")
			(hide yes)
			(effects
				(font
					(size 1 1)
					(thickness 0.15)
				)
			)
		)
		(property "Manufacturer" "Murata"
			(at 313.281 -63.107 0)
			(layer "F.Fab")
			(hide yes)
			(effects
				(font
					(size 1 1)
					(thickness 0.15)
				)
			)
		)
		(property "Public" "False"
			(at 313.281 -63.107 0)
			(layer "F.Fab")
			(hide yes)
			(effects
				(font
					(size 1 1)
					(thickness 0.15)
				)
			)
		)
		(property "Val" "100n"
			(at 313.281 -63.107 0)
			(layer "F.Fab")
			(hide yes)
			(effects
				(font
					(size 1 1)
					(thickness 0.15)
				)
			)
		)
		(property "Voltage" "50V"
			(at 313.281 -63.107 0)
			(layer "F.Fab")
			(hide yes)
			(effects
				(font
					(size 1 1)
					(thickness 0.15)
				)
			)
		)
		(sheetfile "environment-sensor.kicad_sch")
		(attr smd)
		(fp_rect
			(start -0.925 -0.47)
			(end 0.925 0.47)
			(stroke
				(width 0.05)
				(type default)
			)
			(fill no)
			(layer "F.CrtYd")
		)
		(fp_line
			(start 0.504 -0.25)
			(end 0.504 0.248)
			(stroke
				(width 0.15)
				(type solid)
			)
			(layer "F.Fab")
		)
		(fp_line
			(start -0.494 -0.25)
			(end 0.504 -0.25)
			(stroke
				(width 0.15)
				(type solid)
			)
			(layer "F.Fab")
		)
		(fp_line
			(start 0.504 0.248)
			(end -0.494 0.248)
			(stroke
				(width 0.15)
				(type solid)
			)
			(layer "F.Fab")
		)
		(fp_line
			(start -0.494 0.248)
			(end -0.494 -0.25)
			(stroke
				(width 0.15)
				(type solid)
			)
			(layer "F.Fab")
		)
		(pad "1" smd roundrect
			(at -0.48 0 90)
			(size 0.59 0.64)
			(layers "F.Cu" "F.Mask" "F.Paste")
			(roundrect_rratio 0.25)
			(net 1 "GND")
			(pintype "passive")
		)
		(pad "2" smd roundrect
			(at 0.48 0 90)
			(size 0.59 0.64)
			(layers "F.Cu" "F.Mask" "F.Paste")
			(roundrect_rratio 0.25)
			(net 2 "+3V3")
			(pintype "passive")
		)
	)
	(footprint "antmicro-footprints:FB_0603_1608Metric"
		(layer "F.Cu")
		(at 197.759 138.115 90)
		(property "Reference" "FB3"
			(at 1.25 0.35 90)
			(layer "F.SilkS")
			(effects
				(font
					(size 0.7 0.7)
					(thickness 0.15)
				)
				(justify left bottom)
			)
		)
		(property "Value" "FB_120Z_2A_Murata-BLM18PG_0603"
			(at 0 1.5 90)
			(layer "F.Fab")
			(effects
				(font
					(size 0.7 0.7)
					(thickness 0.15)
				)
				(justify left bottom)
			)
		)
		(property "Description" "Ferrite Bead, 0603 [1608 Metric], 120 ohm, 2 A, BLM18P, 0.05 ohm, ± 25%, DC power line"
			(at 0 0 90)
			(layer "F.Fab")
			(hide yes)
			(effects
				(font
					(size 1.27 1.27)
					(thickness 0.15)
				)
			)
		)
		(property "Author" "Antmicro"
			(at 335.874 -59.644 0)
			(layer "F.Fab")
			(hide yes)
			(effects
				(font
					(size 1 1)
					(thickness 0.15)
				)
			)
		)
		(property "Current" ""
			(at 335.874 -59.644 0)
			(layer "F.Fab")
			(hide yes)
			(effects
				(font
					(size 1 1)
					(thickness 0.15)
				)
			)
		)
		(property "License" "Apache-2.0"
			(at 335.874 -59.644 0)
			(layer "F.Fab")
			(hide yes)
			(effects
				(font
					(size 1 1)
					(thickness 0.15)
				)
			)
		)
		(property "MPN" "BLM18PG121SN1D"
			(at 335.874 -59.644 0)
			(layer "F.Fab")
			(hide yes)
			(effects
				(font
					(size 1 1)
					(thickness 0.15)
				)
			)
		)
		(property "Manufacturer" "Murata"
			(at 335.874 -59.644 0)
			(layer "F.Fab")
			(hide yes)
			(effects
				(font
					(size 1 1)
					(thickness 0.15)
				)
			)
		)
		(property "Public" "False"
			(at 335.874 -59.644 0)
			(layer "F.Fab")
			(hide yes)
			(effects
				(font
					(size 1 1)
					(thickness 0.15)
				)
			)
		)
		(property "Val" "120Z/2A"
			(at 335.874 -59.644 0)
			(layer "F.Fab")
			(hide yes)
			(effects
				(font
					(size 1 1)
					(thickness 0.15)
				)
			)
		)
		(sheetfile "environment-sensor.kicad_sch")
		(attr smd)
		(fp_line
			(start -0.15 -0.4)
			(end 0.15 -0.4)
			(stroke
				(width 0.15)
				(type solid)
			)
			(layer "F.SilkS")
		)
		(fp_line
			(start -0.15 0.4)
			(end 0.15 0.4)
			(stroke
				(width 0.15)
				(type solid)
			)
			(layer "F.SilkS")
		)
		(fp_rect
			(start -1.25 -0.65)
			(end 1.25 0.65)
			(stroke
				(width 0.05)
				(type solid)
			)
			(fill no)
			(layer "F.CrtYd")
		)
		(fp_line
			(start 0.8 -0.408)
			(end -0.803 -0.408)
			(stroke
				(width 0.15)
				(type solid)
			)
			(layer "F.Fab")
		)
		(fp_line
			(start 0.8 -0.408)
			(end 0.8 0.406)
			(stroke
				(width 0.15)
				(type solid)
			)
			(layer "F.Fab")
		)
		(fp_line
			(start 0.8 0.406)
			(end -0.803 0.406)
			(stroke
				(width 0.15)
				(type solid)
			)
			(layer "F.Fab")
		)
		(fp_line
			(start -0.803 0.406)
			(end -0.803 -0.408)
			(stroke
				(width 0.15)
				(type solid)
			)
			(layer "F.Fab")
		)
		(pad "1" smd roundrect
			(at -0.7 0 90)
			(size 0.8 1)
			(layers "F.Cu" "F.Mask" "F.Paste")
			(roundrect_rratio 0.2)
			(net 30 "Net-(U3-VDDA)")
			(pintype "passive")
		)
		(pad "2" smd roundrect
			(at 0.7 0 90)
			(size 0.8 1)
			(layers "F.Cu" "F.Mask" "F.Paste")
			(roundrect_rratio 0.2)
			(net 2 "+3V3")
			(pintype "passive")
		)
	)
	(footprint "antmicro-footprints:R_0402_1005Metric"
		(layer "F.Cu")
		(at 183.75 126.25 -90)
		(descr "Resistor SMD 0402")
		(tags "resistor SMD 0402")
		(property "Reference" "R6"
			(at -10.25 -1 90)
			(layer "B.SilkS")
			(effects
				(font
					(size 0.7 0.7)
					(thickness 0.15)
				)
				(justify right bottom mirror)
			)
		)
		(property "Value" "R_0R_0402"
			(at 0 1.4 90)
			(layer "F.Fab")
			(effects
				(font
					(size 0.7 0.7)
					(thickness 0.15)
				)
				(justify right bottom)
			)
		)
		(property "Description" "SMD Chip Resistor, Jumper, 0 ohm, 100 mW, 0402 [1005 Metric], Thick Film, General Purpose"
			(at 0 0 270)
			(layer "F.Fab")
			(hide yes)
			(effects
				(font
					(size 1.27 1.27)
					(thickness 0.15)
				)
			)
		)
		(property "Author" "Antmicro"
			(at 57.5 310 0)
			(layer "F.Fab")
			(hide yes)
			(effects
				(font
					(size 1 1)
					(thickness 0.15)
				)
			)
		)
		(property "Current" "1A"
			(at 57.5 310 0)
			(layer "F.Fab")
			(hide yes)
			(effects
				(font
					(size 1 1)
					(thickness 0.15)
				)
			)
		)
		(property "License" "Apache-2.0"
			(at 57.5 310 0)
			(layer "F.Fab")
			(hide yes)
			(effects
				(font
					(size 1 1)
					(thickness 0.15)
				)
			)
		)
		(property "MPN" "ERJ2GE0R00X"
			(at 57.5 310 0)
			(layer "F.Fab")
			(hide yes)
			(effects
				(font
					(size 1 1)
					(thickness 0.15)
				)
			)
		)
		(property "Manufacturer" "Panasonic"
			(at 57.5 310 0)
			(layer "F.Fab")
			(hide yes)
			(effects
				(font
					(size 1 1)
					(thickness 0.15)
				)
			)
		)
		(property "Public" "False"
			(at 57.5 310 0)
			(layer "F.Fab")
			(hide yes)
			(effects
				(font
					(size 1 1)
					(thickness 0.15)
				)
			)
		)
		(property "Tolerance" ""
			(at 57.5 310 0)
			(layer "F.Fab")
			(hide yes)
			(effects
				(font
					(size 1 1)
					(thickness 0.15)
				)
			)
		)
		(property "Val" "0R"
			(at 57.5 310 0)
			(layer "F.Fab")
			(hide yes)
			(effects
				(font
					(size 1 1)
					(thickness 0.15)
				)
			)
		)
		(sheetfile "environment-sensor.kicad_sch")
		(attr smd)
		(fp_rect
			(start -0.925 -0.47)
			(end 0.925 0.47)
			(stroke
				(width 0.05)
				(type default)
			)
			(fill no)
			(layer "F.CrtYd")
		)
		(fp_rect
			(start -0.5 -0.25)
			(end 0.5 0.25)
			(stroke
				(width 0.15)
				(type solid)
			)
			(fill no)
			(layer "F.Fab")
		)
		(pad "1" smd roundrect
			(at -0.48 0 270)
			(size 0.59 0.64)
			(layers "F.Cu" "F.Mask" "F.Paste")
			(roundrect_rratio 0.25)
			(net 38 "Net-(U1-RTS#)")
			(pintype "passive")
		)
		(pad "2" smd roundrect
			(at 0.48 0 270)
			(size 0.59 0.64)
			(layers "F.Cu" "F.Mask" "F.Paste")
			(roundrect_rratio 0.25)
			(net 18 "SWCLK-JTCK")
			(pintype "passive")
		)
	)
	(footprint "antmicro-footprints:R_0402_1005Metric"
		(layer "F.Cu")
		(at 169.55 135)
		(descr "Resistor SMD 0402")
		(tags "resistor SMD 0402")
		(property "Reference" "R1"
			(at -2.45 0.4 0)
			(layer "F.SilkS")
			(effects
				(font
					(size 0.7 0.7)
					(thickness 0.15)
				)
				(justify left bottom)
			)
		)
		(property "Value" "R_1M_0402"
			(at -1.011843 1.772047 0)
			(layer "F.Fab")
			(effects
				(font
					(size 0.7 0.7)
					(thickness 0.15)
				)
				(justify left bottom)
			)
		)
		(property "Description" "SMD Chip Resistor, 1 Mohm, ± 1%, 62.5 mW, 0402 [1005 Metric], Thick Film, General Purpose"
			(at 0 0 0)
			(layer "F.Fab")
			(hide yes)
			(effects
				(font
					(size 1.27 1.27)
					(thickness 0.15)
				)
			)
		)
		(property "Author" "Antmicro"
			(at 0 0 0)
			(layer "F.Fab")
			(hide yes)
			(effects
				(font
					(size 1 1)
					(thickness 0.15)
				)
			)
		)
		(property "License" "Apache-2.0"
			(at 0 0 0)
			(layer "F.Fab")
			(hide yes)
			(effects
				(font
					(size 1 1)
					(thickness 0.15)
				)
			)
		)
		(property "MPN" "CR0402-FX-1004GLF"
			(at 0 0 0)
			(layer "F.Fab")
			(hide yes)
			(effects
				(font
					(size 1 1)
					(thickness 0.15)
				)
			)
		)
		(property "Manufacturer" "Bourns"
			(at 0 0 0)
			(layer "F.Fab")
			(hide yes)
			(effects
				(font
					(size 1 1)
					(thickness 0.15)
				)
			)
		)
		(property "Public" "False"
			(at 0 0 0)
			(layer "F.Fab")
			(hide yes)
			(effects
				(font
					(size 1 1)
					(thickness 0.15)
				)
			)
		)
		(property "Tolerance" "1%"
			(at 0 0 0)
			(layer "F.Fab")
			(hide yes)
			(effects
				(font
					(size 1 1)
					(thickness 0.15)
				)
			)
		)
		(property "Val" "1M"
			(at 0 0 0)
			(layer "F.Fab")
			(hide yes)
			(effects
				(font
					(size 1 1)
					(thickness 0.15)
				)
			)
		)
		(sheetfile "environment-sensor.kicad_sch")
		(attr smd exclude_from_pos_files exclude_from_bom dnp)
		(fp_rect
			(start -0.925 -0.47)
			(end 0.925 0.47)
			(stroke
				(width 0.05)
				(type default)
			)
			(fill no)
			(layer "F.CrtYd")
		)
		(fp_rect
			(start -0.5 -0.25)
			(end 0.5 0.25)
			(stroke
				(width 0.15)
				(type solid)
			)
			(fill no)
			(layer "F.Fab")
		)
		(pad "1" smd roundrect
			(at -0.48 0)
			(size 0.59 0.64)
			(layers "F.Cu" "F.Mask" "F.Paste")
			(roundrect_rratio 0.25)
			(net 3 "GNDREF")
			(pintype "passive")
		)
		(pad "2" smd roundrect
			(at 0.48 0)
			(size 0.59 0.64)
			(layers "F.Cu" "F.Mask" "F.Paste")
			(roundrect_rratio 0.25)
			(net 1 "GND")
			(pintype "passive")
		)
	)
	(footprint "antmicro-footprints:C_0402_1005Metric"
		(layer "F.Cu")
		(at 175.209 123.684 90)
		(descr "Capacitor SMD 0402")
		(tags "capacitor SMD 0402")
		(property "Reference" "C3"
			(at -2.445 0.407 90)
			(layer "F.SilkS")
			(effects
				(font
					(size 0.7 0.7)
					(thickness 0.15)
				)
				(justify left bottom)
			)
		)
		(property "Value" "C_100n_0402"
			(at 0 1.4 90)
			(layer "F.Fab")
			(effects
				(font
					(size 0.7 0.7)
					(thickness 0.15)
				)
				(justify left bottom)
			)
		)
		(property "Description" "SMD Multilayer Ceramic Capacitor, 0.1 µF, 50 V, 0402 [1005 Metric], ± 10%, X5R, GRM Series"
			(at 0 0 90)
			(layer "F.Fab")
			(hide yes)
			(effects
				(font
					(size 1.27 1.27)
					(thickness 0.15)
				)
			)
		)
		(property "Author" "Antmicro"
			(at 298.893 -51.525 0)
			(layer "F.Fab")
			(hide yes)
			(effects
				(font
					(size 1 1)
					(thickness 0.15)
				)
			)
		)
		(property "Dielectric" "X5R"
			(at 298.893 -51.525 0)
			(layer "F.Fab")
			(hide yes)
			(effects
				(font
					(size 1 1)
					(thickness 0.15)
				)
			)
		)
		(property "License" "Apache-2.0"
			(at 298.893 -51.525 0)
			(layer "F.Fab")
			(hide yes)
			(effects
				(font
					(size 1 1)
					(thickness 0.15)
				)
			)
		)
		(property "MPN" "GRM155R61H104KE14D"
			(at 298.893 -51.525 0)
			(layer "F.Fab")
			(hide yes)
			(effects
				(font
					(size 1 1)
					(thickness 0.15)
				)
			)
		)
		(property "Manufacturer" "Murata"
			(at 298.893 -51.525 0)
			(layer "F.Fab")
			(hide yes)
			(effects
				(font
					(size 1 1)
					(thickness 0.15)
				)
			)
		)
		(property "Public" "False"
			(at 298.893 -51.525 0)
			(layer "F.Fab")
			(hide yes)
			(effects
				(font
					(size 1 1)
					(thickness 0.15)
				)
			)
		)
		(property "Val" "100n"
			(at 298.893 -51.525 0)
			(layer "F.Fab")
			(hide yes)
			(effects
				(font
					(size 1 1)
					(thickness 0.15)
				)
			)
		)
		(property "Voltage" "50V"
			(at 298.893 -51.525 0)
			(layer "F.Fab")
			(hide yes)
			(effects
				(font
					(size 1 1)
					(thickness 0.15)
				)
			)
		)
		(sheetfile "environment-sensor.kicad_sch")
		(attr smd)
		(fp_rect
			(start -0.925 -0.47)
			(end 0.925 0.47)
			(stroke
				(width 0.05)
				(type default)
			)
			(fill no)
			(layer "F.CrtYd")
		)
		(fp_line
			(start 0.504 -0.25)
			(end 0.504 0.248)
			(stroke
				(width 0.15)
				(type solid)
			)
			(layer "F.Fab")
		)
		(fp_line
			(start -0.494 -0.25)
			(end 0.504 -0.25)
			(stroke
				(width 0.15)
				(type solid)
			)
			(layer "F.Fab")
		)
		(fp_line
			(start 0.504 0.248)
			(end -0.494 0.248)
			(stroke
				(width 0.15)
				(type solid)
			)
			(layer "F.Fab")
		)
		(fp_line
			(start -0.494 0.248)
			(end -0.494 -0.25)
			(stroke
				(width 0.15)
				(type solid)
			)
			(layer "F.Fab")
		)
		(pad "1" smd roundrect
			(at -0.48 0 90)
			(size 0.59 0.64)
			(layers "F.Cu" "F.Mask" "F.Paste")
			(roundrect_rratio 0.25)
			(net 1 "GND")
			(pintype "passive")
		)
		(pad "2" smd roundrect
			(at 0.48 0 90)
			(size 0.59 0.64)
			(layers "F.Cu" "F.Mask" "F.Paste")
			(roundrect_rratio 0.25)
			(net 26 "+5V")
			(pintype "passive")
		)
	)
	(footprint "antmicro-footprints:FB_0603_1608Metric"
		(layer "F.Cu")
		(at 169.25 133.6)
		(property "Reference" "FB1"
			(at -3.4 0.4 0)
			(layer "F.SilkS")
			(effects
				(font
					(size 0.7 0.7)
					(thickness 0.15)
				)
				(justify left bottom)
			)
		)
		(property "Value" "FB_120Z_2A_Murata-BLM18PG_0603"
			(at 0 1.5 0)
			(layer "F.Fab")
			(effects
				(font
					(size 0.7 0.7)
					(thickness 0.15)
				)
				(justify left bottom)
			)
		)
		(property "Description" "Ferrite Bead, 0603 [1608 Metric], 120 ohm, 2 A, BLM18P, 0.05 ohm, ± 25%, DC power line"
			(at 0 0 0)
			(layer "F.Fab")
			(hide yes)
			(effects
				(font
					(size 1.27 1.27)
					(thickness 0.15)
				)
			)
		)
		(property "Author" "Antmicro"
			(at 0 0 0)
			(layer "F.Fab")
			(hide yes)
			(effects
				(font
					(size 1 1)
					(thickness 0.15)
				)
			)
		)
		(property "Current" ""
			(at 0 0 0)
			(layer "F.Fab")
			(hide yes)
			(effects
				(font
					(size 1 1)
					(thickness 0.15)
				)
			)
		)
		(property "License" "Apache-2.0"
			(at 0 0 0)
			(layer "F.Fab")
			(hide yes)
			(effects
				(font
					(size 1 1)
					(thickness 0.15)
				)
			)
		)
		(property "MPN" "BLM18PG121SN1D"
			(at 0 0 0)
			(layer "F.Fab")
			(hide yes)
			(effects
				(font
					(size 1 1)
					(thickness 0.15)
				)
			)
		)
		(property "Manufacturer" "Murata"
			(at 0 0 0)
			(layer "F.Fab")
			(hide yes)
			(effects
				(font
					(size 1 1)
					(thickness 0.15)
				)
			)
		)
		(property "Public" "False"
			(at 0 0 0)
			(layer "F.Fab")
			(hide yes)
			(effects
				(font
					(size 1 1)
					(thickness 0.15)
				)
			)
		)
		(property "Val" "120Z/2A"
			(at 0 0 0)
			(layer "F.Fab")
			(hide yes)
			(effects
				(font
					(size 1 1)
					(thickness 0.15)
				)
			)
		)
		(sheetfile "environment-sensor.kicad_sch")
		(attr smd)
		(fp_line
			(start -0.15 -0.4)
			(end 0.15 -0.4)
			(stroke
				(width 0.15)
				(type solid)
			)
			(layer "F.SilkS")
		)
		(fp_line
			(start -0.15 0.4)
			(end 0.15 0.4)
			(stroke
				(width 0.15)
				(type solid)
			)
			(layer "F.SilkS")
		)
		(fp_rect
			(start -1.25 -0.65)
			(end 1.25 0.65)
			(stroke
				(width 0.05)
				(type solid)
			)
			(fill no)
			(layer "F.CrtYd")
		)
		(fp_line
			(start -0.803 0.406)
			(end -0.803 -0.408)
			(stroke
				(width 0.15)
				(type solid)
			)
			(layer "F.Fab")
		)
		(fp_line
			(start 0.8 -0.408)
			(end -0.803 -0.408)
			(stroke
				(width 0.15)
				(type solid)
			)
			(layer "F.Fab")
		)
		(fp_line
			(start 0.8 -0.408)
			(end 0.8 0.406)
			(stroke
				(width 0.15)
				(type solid)
			)
			(layer "F.Fab")
		)
		(fp_line
			(start 0.8 0.406)
			(end -0.803 0.406)
			(stroke
				(width 0.15)
				(type solid)
			)
			(layer "F.Fab")
		)
		(pad "1" smd roundrect
			(at -0.7 0)
			(size 0.8 1)
			(layers "F.Cu" "F.Mask" "F.Paste")
			(roundrect_rratio 0.2)
			(net 3 "GNDREF")
			(pintype "passive")
		)
		(pad "2" smd roundrect
			(at 0.7 0)
			(size 0.8 1)
			(layers "F.Cu" "F.Mask" "F.Paste")
			(roundrect_rratio 0.2)
			(net 1 "GND")
			(pintype "passive")
		)
	)
	(footprint "antmicro-footprints:C_0402_1005Metric"
		(layer "F.Cu")
		(at 169.55 136.15 180)
		(descr "Capacitor SMD 0402")
		(tags "capacitor SMD 0402")
		(property "Reference" "C2"
			(at 0.95 -0.35 0)
			(layer "F.SilkS")
			(effects
				(font
					(size 0.7 0.7)
					(thickness 0.15)
				)
				(justify right bottom)
			)
		)
		(property "Value" "C_100n_0402"
			(at 0 1.4 0)
			(layer "F.Fab")
			(effects
				(font
					(size 0.7 0.7)
					(thickness 0.15)
				)
				(justify right bottom)
			)
		)
		(property "Description" "SMD Multilayer Ceramic Capacitor, 0.1 µF, 50 V, 0402 [1005 Metric], ± 10%, X5R, GRM Series"
			(at 0 0 180)
			(layer "F.Fab")
			(hide yes)
			(effects
				(font
					(size 1.27 1.27)
					(thickness 0.15)
				)
			)
		)
		(property "Author" "Antmicro"
			(at 339.1 272.3 0)
			(layer "F.Fab")
			(hide yes)
			(effects
				(font
					(size 1 1)
					(thickness 0.15)
				)
			)
		)
		(property "Dielectric" "X5R"
			(at 339.1 272.3 0)
			(layer "F.Fab")
			(hide yes)
			(effects
				(font
					(size 1 1)
					(thickness 0.15)
				)
			)
		)
		(property "License" "Apache-2.0"
			(at 339.1 272.3 0)
			(layer "F.Fab")
			(hide yes)
			(effects
				(font
					(size 1 1)
					(thickness 0.15)
				)
			)
		)
		(property "MPN" "GRM155R61H104KE14D"
			(at 339.1 272.3 0)
			(layer "F.Fab")
			(hide yes)
			(effects
				(font
					(size 1 1)
					(thickness 0.15)
				)
			)
		)
		(property "Manufacturer" "Murata"
			(at 339.1 272.3 0)
			(layer "F.Fab")
			(hide yes)
			(effects
				(font
					(size 1 1)
					(thickness 0.15)
				)
			)
		)
		(property "Public" "False"
			(at 339.1 272.3 0)
			(layer "F.Fab")
			(hide yes)
			(effects
				(font
					(size 1 1)
					(thickness 0.15)
				)
			)
		)
		(property "Val" "100n"
			(at 339.1 272.3 0)
			(layer "F.Fab")
			(hide yes)
			(effects
				(font
					(size 1 1)
					(thickness 0.15)
				)
			)
		)
		(property "Voltage" "50V"
			(at 339.1 272.3 0)
			(layer "F.Fab")
			(hide yes)
			(effects
				(font
					(size 1 1)
					(thickness 0.15)
				)
			)
		)
		(sheetfile "environment-sensor.kicad_sch")
		(attr smd)
		(fp_rect
			(start -0.925 -0.47)
			(end 0.925 0.47)
			(stroke
				(width 0.05)
				(type default)
			)
			(fill no)
			(layer "F.CrtYd")
		)
		(fp_line
			(start 0.504 0.248)
			(end -0.494 0.248)
			(stroke
				(width 0.15)
				(type solid)
			)
			(layer "F.Fab")
		)
		(fp_line
			(start 0.504 -0.25)
			(end 0.504 0.248)
			(stroke
				(width 0.15)
				(type solid)
			)
			(layer "F.Fab")
		)
		(fp_line
			(start -0.494 0.248)
			(end -0.494 -0.25)
			(stroke
				(width 0.15)
				(type solid)
			)
			(layer "F.Fab")
		)
		(fp_line
			(start -0.494 -0.25)
			(end 0.504 -0.25)
			(stroke
				(width 0.15)
				(type solid)
			)
			(layer "F.Fab")
		)
		(pad "1" smd roundrect
			(at -0.48 0 180)
			(size 0.59 0.64)
			(layers "F.Cu" "F.Mask" "F.Paste")
			(roundrect_rratio 0.25)
			(net 1 "GND")
			(pintype "passive")
		)
		(pad "2" smd roundrect
			(at 0.48 0 180)
			(size 0.59 0.64)
			(layers "F.Cu" "F.Mask" "F.Paste")
			(roundrect_rratio 0.25)
			(net 3 "GNDREF")
			(pintype "passive")
		)
	)
	(footprint "antmicro-footprints:R_0402_1005Metric"
		(layer "F.Cu")
		(at 178.75 126.25 90)
		(descr "Resistor SMD 0402")
		(tags "resistor SMD 0402")
		(property "Reference" "R7"
			(at 11.75 1.45 270)
			(layer "B.SilkS")
			(effects
				(font
					(size 0.7 0.7)
					(thickness 0.15)
				)
				(justify left bottom mirror)
			)
		)
		(property "Value" "R_0R_0402"
			(at 0 1.4 90)
			(layer "F.Fab")
			(effects
				(font
					(size 0.7 0.7)
					(thickness 0.15)
				)
				(justify left bottom)
			)
		)
		(property "Description" "SMD Chip Resistor, Jumper, 0 ohm, 100 mW, 0402 [1005 Metric], Thick Film, General Purpose"
			(at 0 0 90)
			(layer "F.Fab")
			(hide yes)
			(effects
				(font
					(size 1.27 1.27)
					(thickness 0.15)
				)
			)
		)
		(property "Author" "Antmicro"
			(at 305 -52.5 0)
			(layer "F.Fab")
			(hide yes)
			(effects
				(font
					(size 1 1)
					(thickness 0.15)
				)
			)
		)
		(property "Current" "1A"
			(at 305 -52.5 0)
			(layer "F.Fab")
			(hide yes)
			(effects
				(font
					(size 1 1)
					(thickness 0.15)
				)
			)
		)
		(property "License" "Apache-2.0"
			(at 305 -52.5 0)
			(layer "F.Fab")
			(hide yes)
			(effects
				(font
					(size 1 1)
					(thickness 0.15)
				)
			)
		)
		(property "MPN" "ERJ2GE0R00X"
			(at 305 -52.5 0)
			(layer "F.Fab")
			(hide yes)
			(effects
				(font
					(size 1 1)
					(thickness 0.15)
				)
			)
		)
		(property "Manufacturer" "Panasonic"
			(at 305 -52.5 0)
			(layer "F.Fab")
			(hide yes)
			(effects
				(font
					(size 1 1)
					(thickness 0.15)
				)
			)
		)
		(property "Public" "False"
			(at 305 -52.5 0)
			(layer "F.Fab")
			(hide yes)
			(effects
				(font
					(size 1 1)
					(thickness 0.15)
				)
			)
		)
		(property "Tolerance" ""
			(at 305 -52.5 0)
			(layer "F.Fab")
			(hide yes)
			(effects
				(font
					(size 1 1)
					(thickness 0.15)
				)
			)
		)
		(property "Val" "0R"
			(at 305 -52.5 0)
			(layer "F.Fab")
			(hide yes)
			(effects
				(font
					(size 1 1)
					(thickness 0.15)
				)
			)
		)
		(sheetfile "environment-sensor.kicad_sch")
		(attr smd)
		(fp_rect
			(start -0.925 -0.47)
			(end 0.925 0.47)
			(stroke
				(width 0.05)
				(type default)
			)
			(fill no)
			(layer "F.CrtYd")
		)
		(fp_rect
			(start -0.5 -0.25)
			(end 0.5 0.25)
			(stroke
				(width 0.15)
				(type solid)
			)
			(fill no)
			(layer "F.Fab")
		)
		(pad "1" smd roundrect
			(at -0.48 0 90)
			(size 0.59 0.64)
			(layers "F.Cu" "F.Mask" "F.Paste")
			(roundrect_rratio 0.25)
			(net 39 "Net-(U1-DSR#)")
			(pintype "passive")
		)
		(pad "2" smd roundrect
			(at 0.48 0 90)
			(size 0.59 0.64)
			(layers "F.Cu" "F.Mask" "F.Paste")
			(roundrect_rratio 0.25)
			(net 13 "JTRST")
			(pintype "passive")
		)
	)
	(footprint "antmicro-footprints:MP_Pad5.4mm_Drill2.7mm"
		(layer "F.Cu")
		(at 206.4 136.4)
		(descr "Mounting Hole 2.7mm, M2.5")
		(tags "mounting hole 2.7mm m2.5")
		(property "Reference" "MP3"
			(at 1.2 3.4 0)
			(layer "F.SilkS")
			(effects
				(font
					(size 0.7 0.7)
					(thickness 0.15)
				)
				(justify left bottom)
			)
		)
		(property "Value" "MP_Pad5.4mm_Drill2.7mm"
			(at 0 3.6 0)
			(layer "F.Fab")
			(effects
				(font
					(size 0.7 0.7)
					(thickness 0.15)
				)
				(justify left bottom)
			)
		)
		(property "Description" "Mechanical part"
			(at 0 0 0)
			(layer "F.Fab")
			(hide yes)
			(effects
				(font
					(size 1.27 1.27)
					(thickness 0.15)
				)
			)
		)
		(property "Author" "Antmicro"
			(at 0 0 0)
			(layer "F.Fab")
			(hide yes)
			(effects
				(font
					(size 1 1)
					(thickness 0.15)
				)
			)
		)
		(property "License" "Apache-2.0"
			(at 0 0 0)
			(layer "F.Fab")
			(hide yes)
			(effects
				(font
					(size 1 1)
					(thickness 0.15)
				)
			)
		)
		(property "Public" "False"
			(at 0 0 0)
			(layer "F.Fab")
			(hide yes)
			(effects
				(font
					(size 1 1)
					(thickness 0.15)
				)
			)
		)
		(sheetfile "environment-sensor.kicad_sch")
		(attr exclude_from_pos_files exclude_from_bom)
		(pad "1" thru_hole circle
			(at 0 0)
			(size 5.4 5.4)
			(drill 2.7)
			(layers "*.Cu" "*.Mask")
			(remove_unused_layers no)
			(net 24 "unconnected-(MP3-Pad1)")
			(pintype "passive+no_connect")
		)
	)
	(footprint "antmicro-footprints:R_0402_1005Metric"
		(layer "F.Cu")
		(at 191.544 125.087 90)
		(descr "Resistor SMD 0402")
		(tags "resistor SMD 0402")
		(property "Reference" "R30"
			(at 2.887 3.556 0)
			(layer "F.SilkS")
			(effects
				(font
					(size 0.7 0.7)
					(thickness 0.15)
				)
				(justify left bottom)
			)
		)
		(property "Value" "R_100k_0402"
			(at 0 1.4 90)
			(layer "F.Fab")
			(effects
				(font
					(size 0.7 0.7)
					(thickness 0.15)
				)
				(justify left bottom)
			)
		)
		(property "Description" "SMD Chip Resistor, 100 kohm, ± 1%, 62.5 mW, 0402 [1005 Metric], Thick Film, General Purpose"
			(at 0 0 90)
			(layer "F.Fab")
			(hide yes)
			(effects
				(font
					(size 1.27 1.27)
					(thickness 0.15)
				)
			)
		)
		(property "Author" "Antmicro"
			(at 316.631 -66.457 0)
			(layer "F.Fab")
			(hide yes)
			(effects
				(font
					(size 1 1)
					(thickness 0.15)
				)
			)
		)
		(property "License" "Apache-2.0"
			(at 316.631 -66.457 0)
			(layer "F.Fab")
			(hide yes)
			(effects
				(font
					(size 1 1)
					(thickness 0.15)
				)
			)
		)
		(property "MPN" "CR0402-FX-1003GLF"
			(at 316.631 -66.457 0)
			(layer "F.Fab")
			(hide yes)
			(effects
				(font
					(size 1 1)
					(thickness 0.15)
				)
			)
		)
		(property "Manufacturer" "Bourns"
			(at 316.631 -66.457 0)
			(layer "F.Fab")
			(hide yes)
			(effects
				(font
					(size 1 1)
					(thickness 0.15)
				)
			)
		)
		(property "Public" "False"
			(at 316.631 -66.457 0)
			(layer "F.Fab")
			(hide yes)
			(effects
				(font
					(size 1 1)
					(thickness 0.15)
				)
			)
		)
		(property "Tolerance" "1%"
			(at 316.631 -66.457 0)
			(layer "F.Fab")
			(hide yes)
			(effects
				(font
					(size 1 1)
					(thickness 0.15)
				)
			)
		)
		(property "Val" "100k"
			(at 316.631 -66.457 0)
			(layer "F.Fab")
			(hide yes)
			(effects
				(font
					(size 1 1)
					(thickness 0.15)
				)
			)
		)
		(sheetfile "environment-sensor.kicad_sch")
		(attr smd exclude_from_pos_files exclude_from_bom dnp)
		(fp_rect
			(start -0.925 -0.47)
			(end 0.925 0.47)
			(stroke
				(width 0.05)
				(type default)
			)
			(fill no)
			(layer "F.CrtYd")
		)
		(fp_rect
			(start -0.5 -0.25)
			(end 0.5 0.25)
			(stroke
				(width 0.15)
				(type solid)
			)
			(fill no)
			(layer "F.Fab")
		)
		(pad "1" smd roundrect
			(at -0.48 0 90)
			(size 0.59 0.64)
			(layers "F.Cu" "F.Mask" "F.Paste")
			(roundrect_rratio 0.25)
			(net 1 "GND")
			(pintype "passive")
		)
		(pad "2" smd roundrect
			(at 0.48 0 90)
			(size 0.59 0.64)
			(layers "F.Cu" "F.Mask" "F.Paste")
			(roundrect_rratio 0.25)
			(net 49 "Net-(U3-PB8-BOOT0)")
			(pintype "passive")
		)
	)
	(footprint "antmicro-footprints:TP_SMD_1mm"
		(layer "F.Cu")
		(at 197.411 127.476 180)
		(property "Reference" "TP8"
			(at 0 -0.731898 180)
			(layer "F.SilkS")
			(hide yes)
			(effects
				(font
					(size 0.7 0.7)
					(thickness 0.15)
				)
				(justify left bottom)
			)
		)
		(property "Value" "TP_1mm_SMD"
			(at 0 1.4 180)
			(layer "F.Fab")
			(effects
				(font
					(size 0.7 0.7)
					(thickness 0.15)
				)
				(justify left bottom)
			)
		)
		(property "Description" "Test point 1mm SMD"
			(at 0 0 180)
			(layer "F.Fab")
			(hide yes)
			(effects
				(font
					(size 1.27 1.27)
					(thickness 0.15)
				)
			)
		)
		(property "Author" "Antmicro"
			(at 394.822 254.952 0)
			(layer "F.Fab")
			(hide yes)
			(effects
				(font
					(size 1 1)
					(thickness 0.15)
				)
			)
		)
		(property "License" "Apache-2.0"
			(at 394.822 254.952 0)
			(layer "F.Fab")
			(hide yes)
			(effects
				(font
					(size 1 1)
					(thickness 0.15)
				)
			)
		)
		(property "MPN" ""
			(at 394.822 254.952 0)
			(layer "F.Fab")
			(hide yes)
			(effects
				(font
					(size 1 1)
					(thickness 0.15)
				)
			)
		)
		(property "Manufacturer" ""
			(at 394.822 254.952 0)
			(layer "F.Fab")
			(hide yes)
			(effects
				(font
					(size 1 1)
					(thickness 0.15)
				)
			)
		)
		(property "Public" "False"
			(at 394.822 254.952 0)
			(layer "F.Fab")
			(hide yes)
			(effects
				(font
					(size 1 1)
					(thickness 0.15)
				)
			)
		)
		(sheetfile "environment-sensor.kicad_sch")
		(attr exclude_from_pos_files)
		(pad "1" smd circle
			(at 0 0 180)
			(size 1 1)
			(layers "F.Cu" "F.Mask")
			(net 49 "Net-(U3-PB8-BOOT0)")
			(pinfunction "1")
			(pintype "passive")
		)
	)
	(footprint "antmicro-footprints:C_0402_1005Metric"
		(layer "F.Cu")
		(at 191.314 138.424 90)
		(descr "Capacitor SMD 0402")
		(tags "capacitor SMD 0402")
		(property "Reference" "C22"
			(at 17.955 -8.3245 90)
			(layer "B.SilkS")
			(effects
				(font
					(size 0.7 0.7)
					(thickness 0.15)
				)
				(justify left bottom mirror)
			)
		)
		(property "Value" "C_100n_0402"
			(at 0 1.4 90)
			(layer "F.Fab")
			(effects
				(font
					(size 0.7 0.7)
					(thickness 0.15)
				)
				(justify left bottom)
			)
		)
		(property "Description" "SMD Multilayer Ceramic Capacitor, 0.1 µF, 50 V, 0402 [1005 Metric], ± 10%, X5R, GRM Series"
			(at 0 0 90)
			(layer "F.Fab")
			(hide yes)
			(effects
				(font
					(size 1.27 1.27)
					(thickness 0.15)
				)
			)
		)
		(property "Author" "Antmicro"
			(at 329.738 -52.89 0)
			(layer "F.Fab")
			(hide yes)
			(effects
				(font
					(size 1 1)
					(thickness 0.15)
				)
			)
		)
		(property "Dielectric" "X5R"
			(at 329.738 -52.89 0)
			(layer "F.Fab")
			(hide yes)
			(effects
				(font
					(size 1 1)
					(thickness 0.15)
				)
			)
		)
		(property "License" "Apache-2.0"
			(at 329.738 -52.89 0)
			(layer "F.Fab")
			(hide yes)
			(effects
				(font
					(size 1 1)
					(thickness 0.15)
				)
			)
		)
		(property "MPN" "GRM155R61H104KE14D"
			(at 329.738 -52.89 0)
			(layer "F.Fab")
			(hide yes)
			(effects
				(font
					(size 1 1)
					(thickness 0.15)
				)
			)
		)
		(property "Manufacturer" "Murata"
			(at 329.738 -52.89 0)
			(layer "F.Fab")
			(hide yes)
			(effects
				(font
					(size 1 1)
					(thickness 0.15)
				)
			)
		)
		(property "Public" "False"
			(at 329.738 -52.89 0)
			(layer "F.Fab")
			(hide yes)
			(effects
				(font
					(size 1 1)
					(thickness 0.15)
				)
			)
		)
		(property "Val" "100n"
			(at 329.738 -52.89 0)
			(layer "F.Fab")
			(hide yes)
			(effects
				(font
					(size 1 1)
					(thickness 0.15)
				)
			)
		)
		(property "Voltage" "50V"
			(at 329.738 -52.89 0)
			(layer "F.Fab")
			(hide yes)
			(effects
				(font
					(size 1 1)
					(thickness 0.15)
				)
			)
		)
		(sheetfile "environment-sensor.kicad_sch")
		(attr smd)
		(fp_rect
			(start -0.925 -0.47)
			(end 0.925 0.47)
			(stroke
				(width 0.05)
				(type default)
			)
			(fill no)
			(layer "F.CrtYd")
		)
		(fp_line
			(start 0.504 -0.25)
			(end 0.504 0.248)
			(stroke
				(width 0.15)
				(type solid)
			)
			(layer "F.Fab")
		)
		(fp_line
			(start -0.494 -0.25)
			(end 0.504 -0.25)
			(stroke
				(width 0.15)
				(type solid)
			)
			(layer "F.Fab")
		)
		(fp_line
			(start 0.504 0.248)
			(end -0.494 0.248)
			(stroke
				(width 0.15)
				(type solid)
			)
			(layer "F.Fab")
		)
		(fp_line
			(start -0.494 0.248)
			(end -0.494 -0.25)
			(stroke
				(width 0.15)
				(type solid)
			)
			(layer "F.Fab")
		)
		(pad "1" smd roundrect
			(at -0.48 0 90)
			(size 0.59 0.64)
			(layers "F.Cu" "F.Mask" "F.Paste")
			(roundrect_rratio 0.25)
			(net 32 "Net-(U3-VREF+)")
			(pintype "passive")
		)
		(pad "2" smd roundrect
			(at 0.48 0 90)
			(size 0.59 0.64)
			(layers "F.Cu" "F.Mask" "F.Paste")
			(roundrect_rratio 0.25)
			(net 1 "GND")
			(pintype "passive")
		)
	)
	(footprint "antmicro-footprints:R_0402_1005Metric"
		(layer "F.Cu")
		(at 192.644 125.087 90)
		(descr "Resistor SMD 0402")
		(tags "resistor SMD 0402")
		(property "Reference" "R29"
			(at 1.887 2.456 0)
			(layer "F.SilkS")
			(effects
				(font
					(size 0.7 0.7)
					(thickness 0.15)
				)
				(justify left bottom)
			)
		)
		(property "Value" "R_100k_0402"
			(at 0 1.4 90)
			(layer "F.Fab")
			(effects
				(font
					(size 0.7 0.7)
					(thickness 0.15)
				)
				(justify left bottom)
			)
		)
		(property "Description" "SMD Chip Resistor, 100 kohm, ± 1%, 62.5 mW, 0402 [1005 Metric], Thick Film, General Purpose"
			(at 0 0 90)
			(layer "F.Fab")
			(hide yes)
			(effects
				(font
					(size 1.27 1.27)
					(thickness 0.15)
				)
			)
		)
		(property "Author" "Antmicro"
			(at 317.731 -67.557 0)
			(layer "F.Fab")
			(hide yes)
			(effects
				(font
					(size 1 1)
					(thickness 0.15)
				)
			)
		)
		(property "License" "Apache-2.0"
			(at 317.731 -67.557 0)
			(layer "F.Fab")
			(hide yes)
			(effects
				(font
					(size 1 1)
					(thickness 0.15)
				)
			)
		)
		(property "MPN" "CR0402-FX-1003GLF"
			(at 317.731 -67.557 0)
			(layer "F.Fab")
			(hide yes)
			(effects
				(font
					(size 1 1)
					(thickness 0.15)
				)
			)
		)
		(property "Manufacturer" "Bourns"
			(at 317.731 -67.557 0)
			(layer "F.Fab")
			(hide yes)
			(effects
				(font
					(size 1 1)
					(thickness 0.15)
				)
			)
		)
		(property "Public" "False"
			(at 317.731 -67.557 0)
			(layer "F.Fab")
			(hide yes)
			(effects
				(font
					(size 1 1)
					(thickness 0.15)
				)
			)
		)
		(property "Tolerance" "1%"
			(at 317.731 -67.557 0)
			(layer "F.Fab")
			(hide yes)
			(effects
				(font
					(size 1 1)
					(thickness 0.15)
				)
			)
		)
		(property "Val" "100k"
			(at 317.731 -67.557 0)
			(layer "F.Fab")
			(hide yes)
			(effects
				(font
					(size 1 1)
					(thickness 0.15)
				)
			)
		)
		(sheetfile "environment-sensor.kicad_sch")
		(attr smd)
		(fp_rect
			(start -0.925 -0.47)
			(end 0.925 0.47)
			(stroke
				(width 0.05)
				(type default)
			)
			(fill no)
			(layer "F.CrtYd")
		)
		(fp_rect
			(start -0.5 -0.25)
			(end 0.5 0.25)
			(stroke
				(width 0.15)
				(type solid)
			)
			(fill no)
			(layer "F.Fab")
		)
		(pad "1" smd roundrect
			(at -0.48 0 90)
			(size 0.59 0.64)
			(layers "F.Cu" "F.Mask" "F.Paste")
			(roundrect_rratio 0.25)
			(net 49 "Net-(U3-PB8-BOOT0)")
			(pintype "passive")
		)
		(pad "2" smd roundrect
			(at 0.48 0 90)
			(size 0.59 0.64)
			(layers "F.Cu" "F.Mask" "F.Paste")
			(roundrect_rratio 0.25)
			(net 2 "+3V3")
			(pintype "passive")
		)
	)
	(footprint "antmicro-footprints:R_0402_1005Metric"
		(layer "F.Cu")
		(at 189.344 125.087 90)
		(descr "Resistor SMD 0402")
		(tags "resistor SMD 0402")
		(property "Reference" "R28"
			(at 4.887 5.756 180)
			(layer "F.SilkS")
			(effects
				(font
					(size 0.7 0.7)
					(thickness 0.15)
				)
				(justify left bottom)
			)
		)
		(property "Value" "R_100R_0402"
			(at 0 1.4 90)
			(layer "F.Fab")
			(effects
				(font
					(size 0.7 0.7)
					(thickness 0.15)
				)
				(justify left bottom)
			)
		)
		(property "Description" "SMD Chip Resistor, 100 ohm, ± 1%, 62.5 mW, 0402 [1005 Metric], Thick Film, General Purpose"
			(at 0 0 90)
			(layer "F.Fab")
			(hide yes)
			(effects
				(font
					(size 1.27 1.27)
					(thickness 0.15)
				)
			)
		)
		(property "Author" "Antmicro"
			(at 314.431 -64.257 0)
			(layer "F.Fab")
			(hide yes)
			(effects
				(font
					(size 1 1)
					(thickness 0.15)
				)
			)
		)
		(property "License" "Apache-2.0"
			(at 314.431 -64.257 0)
			(layer "F.Fab")
			(hide yes)
			(effects
				(font
					(size 1 1)
					(thickness 0.15)
				)
			)
		)
		(property "MPN" "CR0402-FX-1000GLF"
			(at 314.431 -64.257 0)
			(layer "F.Fab")
			(hide yes)
			(effects
				(font
					(size 1 1)
					(thickness 0.15)
				)
			)
		)
		(property "Manufacturer" "Bourns"
			(at 314.431 -64.257 0)
			(layer "F.Fab")
			(hide yes)
			(effects
				(font
					(size 1 1)
					(thickness 0.15)
				)
			)
		)
		(property "Public" "False"
			(at 314.431 -64.257 0)
			(layer "F.Fab")
			(hide yes)
			(effects
				(font
					(size 1 1)
					(thickness 0.15)
				)
			)
		)
		(property "Tolerance" "1%"
			(at 314.431 -64.257 0)
			(layer "F.Fab")
			(hide yes)
			(effects
				(font
					(size 1 1)
					(thickness 0.15)
				)
			)
		)
		(property "Val" "100R"
			(at 314.431 -64.257 0)
			(layer "F.Fab")
			(hide yes)
			(effects
				(font
					(size 1 1)
					(thickness 0.15)
				)
			)
		)
		(sheetfile "environment-sensor.kicad_sch")
		(attr smd)
		(fp_rect
			(start -0.925 -0.47)
			(end 0.925 0.47)
			(stroke
				(width 0.05)
				(type default)
			)
			(fill no)
			(layer "F.CrtYd")
		)
		(fp_rect
			(start -0.5 -0.25)
			(end 0.5 0.25)
			(stroke
				(width 0.15)
				(type solid)
			)
			(fill no)
			(layer "F.Fab")
		)
		(pad "1" smd roundrect
			(at -0.48 0 90)
			(size 0.59 0.64)
			(layers "F.Cu" "F.Mask" "F.Paste")
			(roundrect_rratio 0.25)
			(net 50 "Net-(U3-PB9)")
			(pintype "passive")
		)
		(pad "2" smd roundrect
			(at 0.48 0 90)
			(size 0.59 0.64)
			(layers "F.Cu" "F.Mask" "F.Paste")
			(roundrect_rratio 0.25)
			(net 9 "I2C_1_SDA")
			(pintype "passive")
		)
	)
	(footprint "antmicro-footprints:C_0402_1005Metric"
		(layer "F.Cu")
		(at 169.55 137.3 180)
		(descr "Capacitor SMD 0402")
		(tags "capacitor SMD 0402")
		(property "Reference" "C4"
			(at 0.982 -0.252 180)
			(layer "F.SilkS")
			(effects
				(font
					(size 0.7 0.7)
					(thickness 0.15)
				)
				(justify right bottom)
			)
		)
		(property "Value" "C_2u2_0402"
			(at 0 1.4 0)
			(layer "F.Fab")
			(effects
				(font
					(size 0.7 0.7)
					(thickness 0.15)
				)
				(justify right bottom)
			)
		)
		(property "Description" "SMD Multilayer Ceramic Capacitor, 2.2 µF, 10 V, 0402 [1005 Metric], ± 10%, X5R, C"
			(at 0 0 180)
			(layer "F.Fab")
			(hide yes)
			(effects
				(font
					(size 1.27 1.27)
					(thickness 0.15)
				)
			)
		)
		(property "Author" "Antmicro"
			(at 339.1 274.6 0)
			(layer "F.Fab")
			(hide yes)
			(effects
				(font
					(size 1 1)
					(thickness 0.15)
				)
			)
		)
		(property "Dielectric" ""
			(at 339.1 274.6 0)
			(layer "F.Fab")
			(hide yes)
			(effects
				(font
					(size 1 1)
					(thickness 0.15)
				)
			)
		)
		(property "License" "Apache-2.0"
			(at 339.1 274.6 0)
			(layer "F.Fab")
			(hide yes)
			(effects
				(font
					(size 1 1)
					(thickness 0.15)
				)
			)
		)
		(property "MPN" "C1005X5R1A225K050BC"
			(at 339.1 274.6 0)
			(layer "F.Fab")
			(hide yes)
			(effects
				(font
					(size 1 1)
					(thickness 0.15)
				)
			)
		)
		(property "Manufacturer" "TDK"
			(at 339.1 274.6 0)
			(layer "F.Fab")
			(hide yes)
			(effects
				(font
					(size 1 1)
					(thickness 0.15)
				)
			)
		)
		(property "Public" "False"
			(at 339.1 274.6 0)
			(layer "F.Fab")
			(hide yes)
			(effects
				(font
					(size 1 1)
					(thickness 0.15)
				)
			)
		)
		(property "Val" "2u2"
			(at 339.1 274.6 0)
			(layer "F.Fab")
			(hide yes)
			(effects
				(font
					(size 1 1)
					(thickness 0.15)
				)
			)
		)
		(property "Voltage" ""
			(at 339.1 274.6 0)
			(layer "F.Fab")
			(hide yes)
			(effects
				(font
					(size 1 1)
					(thickness 0.15)
				)
			)
		)
		(sheetfile "environment-sensor.kicad_sch")
		(attr smd)
		(fp_rect
			(start -0.925 -0.47)
			(end 0.925 0.47)
			(stroke
				(width 0.05)
				(type default)
			)
			(fill no)
			(layer "F.CrtYd")
		)
		(fp_line
			(start 0.504 0.248)
			(end -0.494 0.248)
			(stroke
				(width 0.15)
				(type solid)
			)
			(layer "F.Fab")
		)
		(fp_line
			(start 0.504 -0.25)
			(end 0.504 0.248)
			(stroke
				(width 0.15)
				(type solid)
			)
			(layer "F.Fab")
		)
		(fp_line
			(start -0.494 0.248)
			(end -0.494 -0.25)
			(stroke
				(width 0.15)
				(type solid)
			)
			(layer "F.Fab")
		)
		(fp_line
			(start -0.494 -0.25)
			(end 0.504 -0.25)
			(stroke
				(width 0.15)
				(type solid)
			)
			(layer "F.Fab")
		)
		(pad "1" smd roundrect
			(at -0.48 0 180)
			(size 0.59 0.64)
			(layers "F.Cu" "F.Mask" "F.Paste")
			(roundrect_rratio 0.25)
			(net 1 "GND")
			(pintype "passive")
		)
		(pad "2" smd roundrect
			(at 0.48 0 180)
			(size 0.59 0.64)
			(layers "F.Cu" "F.Mask" "F.Paste")
			(roundrect_rratio 0.25)
			(net 27 "/VBUS")
			(pintype "passive")
		)
	)
	(footprint "antmicro-footprints:R_0402_1005Metric"
		(layer "F.Cu")
		(at 177.5 126.25 90)
		(descr "Resistor SMD 0402")
		(tags "resistor SMD 0402")
		(property "Reference" "R8"
			(at 11.75 1.773 270)
			(layer "B.SilkS")
			(effects
				(font
					(size 0.7 0.7)
					(thickness 0.15)
				)
				(justify left bottom mirror)
			)
		)
		(property "Value" "R_0R_0402"
			(at 0 1.4 90)
			(layer "F.Fab")
			(effects
				(font
					(size 0.7 0.7)
					(thickness 0.15)
				)
				(justify left bottom)
			)
		)
		(property "Description" "SMD Chip Resistor, Jumper, 0 ohm, 100 mW, 0402 [1005 Metric], Thick Film, General Purpose"
			(at 0 0 90)
			(layer "F.Fab")
			(hide yes)
			(effects
				(font
					(size 1.27 1.27)
					(thickness 0.15)
				)
			)
		)
		(property "Author" "Antmicro"
			(at 303.75 -51.25 0)
			(layer "F.Fab")
			(hide yes)
			(effects
				(font
					(size 1 1)
					(thickness 0.15)
				)
			)
		)
		(property "Current" "1A"
			(at 303.75 -51.25 0)
			(layer "F.Fab")
			(hide yes)
			(effects
				(font
					(size 1 1)
					(thickness 0.15)
				)
			)
		)
		(property "License" "Apache-2.0"
			(at 303.75 -51.25 0)
			(layer "F.Fab")
			(hide yes)
			(effects
				(font
					(size 1 1)
					(thickness 0.15)
				)
			)
		)
		(property "MPN" "ERJ2GE0R00X"
			(at 303.75 -51.25 0)
			(layer "F.Fab")
			(hide yes)
			(effects
				(font
					(size 1 1)
					(thickness 0.15)
				)
			)
		)
		(property "Manufacturer" "Panasonic"
			(at 303.75 -51.25 0)
			(layer "F.Fab")
			(hide yes)
			(effects
				(font
					(size 1 1)
					(thickness 0.15)
				)
			)
		)
		(property "Public" "False"
			(at 303.75 -51.25 0)
			(layer "F.Fab")
			(hide yes)
			(effects
				(font
					(size 1 1)
					(thickness 0.15)
				)
			)
		)
		(property "Tolerance" ""
			(at 303.75 -51.25 0)
			(layer "F.Fab")
			(hide yes)
			(effects
				(font
					(size 1 1)
					(thickness 0.15)
				)
			)
		)
		(property "Val" "0R"
			(at 303.75 -51.25 0)
			(layer "F.Fab")
			(hide yes)
			(effects
				(font
					(size 1 1)
					(thickness 0.15)
				)
			)
		)
		(sheetfile "environment-sensor.kicad_sch")
		(attr smd)
		(fp_rect
			(start -0.925 -0.47)
			(end 0.925 0.47)
			(stroke
				(width 0.05)
				(type default)
			)
			(fill no)
			(layer "F.CrtYd")
		)
		(fp_rect
			(start -0.5 -0.25)
			(end 0.5 0.25)
			(stroke
				(width 0.15)
				(type solid)
			)
			(fill no)
			(layer "F.Fab")
		)
		(pad "1" smd roundrect
			(at -0.48 0 90)
			(size 0.59 0.64)
			(layers "F.Cu" "F.Mask" "F.Paste")
			(roundrect_rratio 0.25)
			(net 40 "Net-(U1-DCD#)")
			(pintype "passive")
		)
		(pad "2" smd roundrect
			(at 0.48 0 90)
			(size 0.59 0.64)
			(layers "F.Cu" "F.Mask" "F.Paste")
			(roundrect_rratio 0.25)
			(net 14 "NRST")
			(pintype "passive")
		)
	)
	(footprint "antmicro-footprints:C_0402_1005Metric"
		(layer "F.Cu")
		(at 205.15 117.835 90)
		(descr "Capacitor SMD 0402")
		(tags "capacitor SMD 0402")
		(property "Reference" "C28"
			(at -3.465 -5.05 180)
			(layer "F.SilkS")
			(effects
				(font
					(size 0.7 0.7)
					(thickness 0.15)
				)
				(justify left bottom)
			)
		)
		(property "Value" "C_100n_0402"
			(at 0 1.4 90)
			(layer "F.Fab")
			(effects
				(font
					(size 0.7 0.7)
					(thickness 0.15)
				)
				(justify left bottom)
			)
		)
		(property "Description" "SMD Multilayer Ceramic Capacitor, 0.1 µF, 50 V, 0402 [1005 Metric], ± 10%, X5R, GRM Series"
			(at 0 0 90)
			(layer "F.Fab")
			(hide yes)
			(effects
				(font
					(size 1.27 1.27)
					(thickness 0.15)
				)
			)
		)
		(property "Author" "Antmicro"
			(at 322.985 -87.315 0)
			(layer "F.Fab")
			(hide yes)
			(effects
				(font
					(size 1 1)
					(thickness 0.15)
				)
			)
		)
		(property "Dielectric" "X5R"
			(at 322.985 -87.315 0)
			(layer "F.Fab")
			(hide yes)
			(effects
				(font
					(size 1 1)
					(thickness 0.15)
				)
			)
		)
		(property "License" "Apache-2.0"
			(at 322.985 -87.315 0)
			(layer "F.Fab")
			(hide yes)
			(effects
				(font
					(size 1 1)
					(thickness 0.15)
				)
			)
		)
		(property "MPN" "GRM155R61H104KE14D"
			(at 322.985 -87.315 0)
			(layer "F.Fab")
			(hide yes)
			(effects
				(font
					(size 1 1)
					(thickness 0.15)
				)
			)
		)
		(property "Manufacturer" "Murata"
			(at 322.985 -87.315 0)
			(layer "F.Fab")
			(hide yes)
			(effects
				(font
					(size 1 1)
					(thickness 0.15)
				)
			)
		)
		(property "Public" "False"
			(at 322.985 -87.315 0)
			(layer "F.Fab")
			(hide yes)
			(effects
				(font
					(size 1 1)
					(thickness 0.15)
				)
			)
		)
		(property "Val" "100n"
			(at 322.985 -87.315 0)
			(layer "F.Fab")
			(hide yes)
			(effects
				(font
					(size 1 1)
					(thickness 0.15)
				)
			)
		)
		(property "Voltage" "50V"
			(at 322.985 -87.315 0)
			(layer "F.Fab")
			(hide yes)
			(effects
				(font
					(size 1 1)
					(thickness 0.15)
				)
			)
		)
		(sheetfile "environment-sensor.kicad_sch")
		(attr smd)
		(fp_rect
			(start -0.925 -0.47)
			(end 0.925 0.47)
			(stroke
				(width 0.05)
				(type default)
			)
			(fill no)
			(layer "F.CrtYd")
		)
		(fp_line
			(start 0.504 -0.25)
			(end 0.504 0.248)
			(stroke
				(width 0.15)
				(type solid)
			)
			(layer "F.Fab")
		)
		(fp_line
			(start -0.494 -0.25)
			(end 0.504 -0.25)
			(stroke
				(width 0.15)
				(type solid)
			)
			(layer "F.Fab")
		)
		(fp_line
			(start 0.504 0.248)
			(end -0.494 0.248)
			(stroke
				(width 0.15)
				(type solid)
			)
			(layer "F.Fab")
		)
		(fp_line
			(start -0.494 0.248)
			(end -0.494 -0.25)
			(stroke
				(width 0.15)
				(type solid)
			)
			(layer "F.Fab")
		)
		(pad "1" smd roundrect
			(at -0.48 0 90)
			(size 0.59 0.64)
			(layers "F.Cu" "F.Mask" "F.Paste")
			(roundrect_rratio 0.25)
			(net 2 "+3V3")
			(pintype "passive")
		)
		(pad "2" smd roundrect
			(at 0.48 0 90)
			(size 0.59 0.64)
			(layers "F.Cu" "F.Mask" "F.Paste")
			(roundrect_rratio 0.25)
			(net 1 "GND")
			(pintype "passive")
		)
	)
	(footprint "antmicro-footprints:R_0402_1005Metric"
		(layer "F.Cu")
		(at 193.744 125.087 90)
		(descr "Resistor SMD 0402")
		(tags "resistor SMD 0402")
		(property "Reference" "R23"
			(at 0.937 1.356 180)
			(layer "F.SilkS")
			(effects
				(font
					(size 0.7 0.7)
					(thickness 0.15)
				)
				(justify left bottom)
			)
		)
		(property "Value" "R_100R_0402"
			(at -1.011843 1.772047 90)
			(layer "F.Fab")
			(effects
				(font
					(size 0.7 0.7)
					(thickness 0.15)
				)
				(justify left bottom)
			)
		)
		(property "Description" "SMD Chip Resistor, 100 ohm, ± 1%, 62.5 mW, 0402 [1005 Metric], Thick Film, General Purpose"
			(at 0 0 90)
			(layer "F.Fab")
			(hide yes)
			(effects
				(font
					(size 1.27 1.27)
					(thickness 0.15)
				)
			)
		)
		(property "Author" "Antmicro"
			(at 318.831 -68.657 0)
			(layer "F.Fab")
			(hide yes)
			(effects
				(font
					(size 1 1)
					(thickness 0.15)
				)
			)
		)
		(property "License" "Apache-2.0"
			(at 318.831 -68.657 0)
			(layer "F.Fab")
			(hide yes)
			(effects
				(font
					(size 1 1)
					(thickness 0.15)
				)
			)
		)
		(property "MPN" "CR0402-FX-1000GLF"
			(at 318.831 -68.657 0)
			(layer "F.Fab")
			(hide yes)
			(effects
				(font
					(size 1 1)
					(thickness 0.15)
				)
			)
		)
		(property "Manufacturer" "Bourns"
			(at 318.831 -68.657 0)
			(layer "F.Fab")
			(hide yes)
			(effects
				(font
					(size 1 1)
					(thickness 0.15)
				)
			)
		)
		(property "Public" "False"
			(at 318.831 -68.657 0)
			(layer "F.Fab")
			(hide yes)
			(effects
				(font
					(size 1 1)
					(thickness 0.15)
				)
			)
		)
		(property "Tolerance" "1%"
			(at 318.831 -68.657 0)
			(layer "F.Fab")
			(hide yes)
			(effects
				(font
					(size 1 1)
					(thickness 0.15)
				)
			)
		)
		(property "Val" "100R"
			(at 318.831 -68.657 0)
			(layer "F.Fab")
			(hide yes)
			(effects
				(font
					(size 1 1)
					(thickness 0.15)
				)
			)
		)
		(sheetfile "environment-sensor.kicad_sch")
		(attr smd exclude_from_pos_files exclude_from_bom dnp)
		(fp_rect
			(start -0.925 -0.47)
			(end 0.925 0.47)
			(stroke
				(width 0.05)
				(type default)
			)
			(fill no)
			(layer "F.CrtYd")
		)
		(fp_rect
			(start -0.5 -0.25)
			(end 0.5 0.25)
			(stroke
				(width 0.15)
				(type solid)
			)
			(fill no)
			(layer "F.Fab")
		)
		(pad "1" smd roundrect
			(at -0.48 0 90)
			(size 0.59 0.64)
			(layers "F.Cu" "F.Mask" "F.Paste")
			(roundrect_rratio 0.25)
			(net 46 "Net-(U3-PA15)")
			(pintype "passive")
		)
		(pad "2" smd roundrect
			(at 0.48 0 90)
			(size 0.59 0.64)
			(layers "F.Cu" "F.Mask" "F.Paste")
			(roundrect_rratio 0.25)
			(net 8 "I2C_1_SCL")
			(pintype "passive")
		)
	)
	(footprint "antmicro-footprints:R_0402_1005Metric"
		(layer "F.Cu")
		(at 182.736 119.5855)
		(descr "Resistor SMD 0402")
		(tags "resistor SMD 0402")
		(property "Reference" "R32"
			(at -3.136 0.4145 0)
			(layer "F.SilkS")
			(effects
				(font
					(size 0.7 0.7)
					(thickness 0.15)
				)
				(justify left bottom)
			)
		)
		(property "Value" "R_100k_0402"
			(at 0 1.4 0)
			(layer "F.Fab")
			(effects
				(font
					(size 0.7 0.7)
					(thickness 0.15)
				)
				(justify left bottom)
			)
		)
		(property "Description" "SMD Chip Resistor, 100 kohm, ± 1%, 62.5 mW, 0402 [1005 Metric], Thick Film, General Purpose"
			(at 0 0 0)
			(layer "F.Fab")
			(hide yes)
			(effects
				(font
					(size 1.27 1.27)
					(thickness 0.15)
				)
			)
		)
		(property "Author" "Antmicro"
			(at 0 0 0)
			(layer "F.Fab")
			(hide yes)
			(effects
				(font
					(size 1 1)
					(thickness 0.15)
				)
			)
		)
		(property "License" "Apache-2.0"
			(at 0 0 0)
			(layer "F.Fab")
			(hide yes)
			(effects
				(font
					(size 1 1)
					(thickness 0.15)
				)
			)
		)
		(property "MPN" "CR0402-FX-1003GLF"
			(at 0 0 0)
			(layer "F.Fab")
			(hide yes)
			(effects
				(font
					(size 1 1)
					(thickness 0.15)
				)
			)
		)
		(property "Manufacturer" "Bourns"
			(at 0 0 0)
			(layer "F.Fab")
			(hide yes)
			(effects
				(font
					(size 1 1)
					(thickness 0.15)
				)
			)
		)
		(property "Public" "False"
			(at 0 0 0)
			(layer "F.Fab")
			(hide yes)
			(effects
				(font
					(size 1 1)
					(thickness 0.15)
				)
			)
		)
		(property "Tolerance" "1%"
			(at 0 0 0)
			(layer "F.Fab")
			(hide yes)
			(effects
				(font
					(size 1 1)
					(thickness 0.15)
				)
			)
		)
		(property "Val" "100k"
			(at 0 0 0)
			(layer "F.Fab")
			(hide yes)
			(effects
				(font
					(size 1 1)
					(thickness 0.15)
				)
			)
		)
		(sheetfile "environment-sensor.kicad_sch")
		(attr smd)
		(fp_rect
			(start -0.925 -0.47)
			(end 0.925 0.47)
			(stroke
				(width 0.05)
				(type default)
			)
			(fill no)
			(layer "F.CrtYd")
		)
		(fp_rect
			(start -0.5 -0.25)
			(end 0.5 0.25)
			(stroke
				(width 0.15)
				(type solid)
			)
			(fill no)
			(layer "F.Fab")
		)
		(pad "1" smd roundrect
			(at -0.48 0)
			(size 0.59 0.64)
			(layers "F.Cu" "F.Mask" "F.Paste")
			(roundrect_rratio 0.25)
			(net 1 "GND")
			(pintype "passive")
		)
		(pad "2" smd roundrect
			(at 0.48 0)
			(size 0.59 0.64)
			(layers "F.Cu" "F.Mask" "F.Paste")
			(roundrect_rratio 0.25)
			(net 51 "Net-(U4-A1)")
			(pintype "passive")
		)
	)
	(footprint "antmicro-footprints:SOD-923"
		(layer "F.Cu")
		(at 203.085 130.25 90)
		(property "Reference" "D7"
			(at -1.5 0.065 90)
			(unlocked yes)
			(layer "F.SilkS")
			(effects
				(font
					(size 0.65 0.65)
					(thickness 0.15)
				)
			)
		)
		(property "Value" "ESD9X5.0ST5G"
			(at 0 2.4 90)
			(unlocked yes)
			(layer "F.Fab")
			(effects
				(font
					(size 1 1)
					(thickness 0.15)
				)
			)
		)
		(property "Description" "Unidirectional TVS, 30 kV,  SOD-923, 5 V, 65 pF"
			(at 0 0 90)
			(layer "F.Fab")
			(hide yes)
			(effects
				(font
					(size 1.27 1.27)
					(thickness 0.15)
				)
			)
		)
		(property "Author" "Antmicro"
			(at 333.335 -72.835 0)
			(layer "F.Fab")
			(hide yes)
			(effects
				(font
					(size 1 1)
					(thickness 0.15)
				)
			)
		)
		(property "License" "Apache-2.0"
			(at 333.335 -72.835 0)
			(layer "F.Fab")
			(hide yes)
			(effects
				(font
					(size 1 1)
					(thickness 0.15)
				)
			)
		)
		(property "MPN" "ESD9X5.0ST5G"
			(at 333.335 -72.835 0)
			(layer "F.Fab")
			(hide yes)
			(effects
				(font
					(size 1 1)
					(thickness 0.15)
				)
			)
		)
		(property "Manufacturer" "ON Semiconductor"
			(at 333.335 -72.835 0)
			(layer "F.Fab")
			(hide yes)
			(effects
				(font
					(size 1 1)
					(thickness 0.15)
				)
			)
		)
		(property "Public" "False"
			(at 333.335 -72.835 0)
			(layer "F.Fab")
			(hide yes)
			(effects
				(font
					(size 1 1)
					(thickness 0.15)
				)
			)
		)
		(sheetfile "environment-sensor.kicad_sch")
		(attr smd)
		(fp_line
			(start 0.5 -0.4)
			(end 0.5 -0.3)
			(stroke
				(width 0.15)
				(type solid)
			)
			(layer "F.SilkS")
		)
		(fp_line
			(start -0.16 -0.4)
			(end -0.16 0.4)
			(stroke
				(width 0.15)
				(type solid)
			)
			(layer "F.SilkS")
		)
		(fp_line
			(start -0.5 -0.4)
			(end 0.5 -0.4)
			(stroke
				(width 0.15)
				(type solid)
			)
			(layer "F.SilkS")
		)
		(fp_line
			(start -0.5 -0.3)
			(end -0.5 -0.4)
			(stroke
				(width 0.15)
				(type solid)
			)
			(layer "F.SilkS")
		)
		(fp_line
			(start 0.5 0.4)
			(end 0.5 0.3)
			(stroke
				(width 0.15)
				(type solid)
			)
			(layer "F.SilkS")
		)
		(fp_line
			(start -0.5 0.4)
			(end -0.5 0.3)
			(stroke
				(width 0.15)
				(type solid)
			)
			(layer "F.SilkS")
		)
		(fp_line
			(start -0.5 0.4)
			(end 0.5 0.4)
			(stroke
				(width 0.15)
				(type solid)
			)
			(layer "F.SilkS")
		)
		(fp_rect
			(start -0.68 -0.41)
			(end 0.68 0.41)
			(stroke
				(width 0.05)
				(type solid)
			)
			(fill no)
			(layer "F.CrtYd")
		)
		(fp_line
			(start -0.202 -0.3)
			(end -0.202 0.298)
			(stroke
				(width 0.15)
				(type solid)
			)
			(layer "F.Fab")
		)
		(fp_rect
			(start -0.402 -0.3)
			(end 0.4 0.298)
			(stroke
				(width 0.15)
				(type solid)
			)
			(fill no)
			(layer "F.Fab")
		)
		(fp_text user "${REFERENCE}"
			(at 0 1.1 90)
			(unlocked yes)
			(layer "F.Fab")
			(effects
				(font
					(size 1 1)
					(thickness 0.15)
				)
			)
		)
		(pad "1" smd roundrect
			(at -0.438 0 90)
			(size 0.4 0.325)
			(layers "F.Cu" "F.Mask" "F.Paste")
			(roundrect_rratio 0.25)
			(net 1 "GND")
			(pinfunction "C")
			(pintype "passive")
		)
		(pad "2" smd roundrect
			(at 0.436 0 90)
			(size 0.4 0.325)
			(layers "F.Cu" "F.Mask" "F.Paste")
			(roundrect_rratio 0.25)
			(net 2 "+3V3")
			(pinfunction "A")
			(pintype "passive")
		)
	)
	(footprint "antmicro-footprints:R_0402_1005Metric"
		(layer "F.Cu")
		(at 182.91 131.5 180)
		(descr "Resistor SMD 0402")
		(tags "resistor SMD 0402")
		(property "Reference" "R18"
			(at -3.04 -0.4 0)
			(layer "F.SilkS")
			(effects
				(font
					(size 0.7 0.7)
					(thickness 0.15)
				)
				(justify right bottom)
			)
		)
		(property "Value" "R_1M_0402"
			(at -1.011843 1.772047 0)
			(layer "F.Fab")
			(effects
				(font
					(size 0.7 0.7)
					(thickness 0.15)
				)
				(justify right bottom)
			)
		)
		(property "Description" "SMD Chip Resistor, 1 Mohm, ± 1%, 62.5 mW, 0402 [1005 Metric], Thick Film, General Purpose"
			(at 0 0 180)
			(layer "F.Fab")
			(hide yes)
			(effects
				(font
					(size 1.27 1.27)
					(thickness 0.15)
				)
			)
		)
		(property "Author" "Antmicro"
			(at 365.82 263 0)
			(layer "F.Fab")
			(hide yes)
			(effects
				(font
					(size 1 1)
					(thickness 0.15)
				)
			)
		)
		(property "License" "Apache-2.0"
			(at 365.82 263 0)
			(layer "F.Fab")
			(hide yes)
			(effects
				(font
					(size 1 1)
					(thickness 0.15)
				)
			)
		)
		(property "MPN" "CR0402-FX-1004GLF"
			(at 365.82 263 0)
			(layer "F.Fab")
			(hide yes)
			(effects
				(font
					(size 1 1)
					(thickness 0.15)
				)
			)
		)
		(property "Manufacturer" "Bourns"
			(at 365.82 263 0)
			(layer "F.Fab")
			(hide yes)
			(effects
				(font
					(size 1 1)
					(thickness 0.15)
				)
			)
		)
		(property "Public" "False"
			(at 365.82 263 0)
			(layer "F.Fab")
			(hide yes)
			(effects
				(font
					(size 1 1)
					(thickness 0.15)
				)
			)
		)
		(property "Tolerance" "1%"
			(at 365.82 263 0)
			(layer "F.Fab")
			(hide yes)
			(effects
				(font
					(size 1 1)
					(thickness 0.15)
				)
			)
		)
		(property "Val" "1M"
			(at 365.82 263 0)
			(layer "F.Fab")
			(hide yes)
			(effects
				(font
					(size 1 1)
					(thickness 0.15)
				)
			)
		)
		(sheetfile "environment-sensor.kicad_sch")
		(attr smd exclude_from_pos_files exclude_from_bom dnp)
		(fp_rect
			(start -0.925 -0.47)
			(end 0.925 0.47)
			(stroke
				(width 0.05)
				(type default)
			)
			(fill no)
			(layer "F.CrtYd")
		)
		(fp_rect
			(start -0.5 -0.25)
			(end 0.5 0.25)
			(stroke
				(width 0.15)
				(type solid)
			)
			(fill no)
			(layer "F.Fab")
		)
		(pad "1" smd roundrect
			(at -0.48 0 180)
			(size 0.59 0.64)
			(layers "F.Cu" "F.Mask" "F.Paste")
			(roundrect_rratio 0.25)
			(net 86 "/OSC32_IN")
			(pintype "passive")
		)
		(pad "2" smd roundrect
			(at 0.48 0 180)
			(size 0.59 0.64)
			(layers "F.Cu" "F.Mask" "F.Paste")
			(roundrect_rratio 0.25)
			(net 87 "/OSC32_OUT")
			(pintype "passive")
		)
	)
	(footprint "antmicro-footprints:R_0402_1005Metric"
		(layer "F.Cu")
		(at 177.303 123.697 -90)
		(descr "Resistor SMD 0402")
		(tags "resistor SMD 0402")
		(property "Reference" "R11"
			(at 0.053 -2.647 180)
			(layer "F.SilkS")
			(effects
				(font
					(size 0.7 0.7)
					(thickness 0.15)
				)
				(justify right bottom)
			)
		)
		(property "Value" "R_0R_0402"
			(at -1.011843 1.772047 90)
			(layer "F.Fab")
			(effects
				(font
					(size 0.7 0.7)
					(thickness 0.15)
				)
				(justify right bottom)
			)
		)
		(property "Description" "SMD Chip Resistor, Jumper, 0 ohm, 100 mW, 0402 [1005 Metric], Thick Film, General Purpose"
			(at 0 0 270)
			(layer "F.Fab")
			(hide yes)
			(effects
				(font
					(size 1.27 1.27)
					(thickness 0.15)
				)
			)
		)
		(property "Author" "Antmicro"
			(at 53.606 301 0)
			(layer "F.Fab")
			(hide yes)
			(effects
				(font
					(size 1 1)
					(thickness 0.15)
				)
			)
		)
		(property "Current" "1A"
			(at 53.606 301 0)
			(layer "F.Fab")
			(hide yes)
			(effects
				(font
					(size 1 1)
					(thickness 0.15)
				)
			)
		)
		(property "License" "Apache-2.0"
			(at 53.606 301 0)
			(layer "F.Fab")
			(hide yes)
			(effects
				(font
					(size 1 1)
					(thickness 0.15)
				)
			)
		)
		(property "MPN" "ERJ2GE0R00X"
			(at 53.606 301 0)
			(layer "F.Fab")
			(hide yes)
			(effects
				(font
					(size 1 1)
					(thickness 0.15)
				)
			)
		)
		(property "Manufacturer" "Panasonic"
			(at 53.606 301 0)
			(layer "F.Fab")
			(hide yes)
			(effects
				(font
					(size 1 1)
					(thickness 0.15)
				)
			)
		)
		(property "Public" "False"
			(at 53.606 301 0)
			(layer "F.Fab")
			(hide yes)
			(effects
				(font
					(size 1 1)
					(thickness 0.15)
				)
			)
		)
		(property "Tolerance" ""
			(at 53.606 301 0)
			(layer "F.Fab")
			(hide yes)
			(effects
				(font
					(size 1 1)
					(thickness 0.15)
				)
			)
		)
		(property "Val" "0R"
			(at 53.606 301 0)
			(layer "F.Fab")
			(hide yes)
			(effects
				(font
					(size 1 1)
					(thickness 0.15)
				)
			)
		)
		(sheetfile "environment-sensor.kicad_sch")
		(attr smd exclude_from_pos_files exclude_from_bom dnp)
		(fp_rect
			(start -0.925 -0.47)
			(end 0.925 0.47)
			(stroke
				(width 0.05)
				(type default)
			)
			(fill no)
			(layer "F.CrtYd")
		)
		(fp_rect
			(start -0.5 -0.25)
			(end 0.5 0.25)
			(stroke
				(width 0.15)
				(type solid)
			)
			(fill no)
			(layer "F.Fab")
		)
		(pad "1" smd roundrect
			(at -0.48 0 270)
			(size 0.59 0.64)
			(layers "F.Cu" "F.Mask" "F.Paste")
			(roundrect_rratio 0.25)
			(net 43 "Net-(U1-CBUS0)")
			(pintype "passive")
		)
		(pad "2" smd roundrect
			(at 0.48 0 270)
			(size 0.59 0.64)
			(layers "F.Cu" "F.Mask" "F.Paste")
			(roundrect_rratio 0.25)
			(net 21 "/FTDI_USER_PB")
			(pintype "passive")
		)
	)
	(footprint "antmicro-footprints:TP_SMD_1.5mm"
		(locked yes)
		(layer "F.Cu")
		(at 181 116)
		(property "Reference" "TP6"
			(at -1.471 -1.044 0)
			(layer "F.SilkS")
			(hide yes)
			(effects
				(font
					(size 0.7 0.7)
					(thickness 0.15)
				)
				(justify left bottom)
			)
		)
		(property "Value" "TP_1.5mm_SMD"
			(at 0 1.7 0)
			(layer "F.Fab")
			(effects
				(font
					(size 0.7 0.7)
					(thickness 0.15)
				)
				(justify left bottom)
			)
		)
		(property "Description" "test point, SMT"
			(at 0 0 0)
			(layer "F.Fab")
			(hide yes)
			(effects
				(font
					(size 1.27 1.27)
					(thickness 0.15)
				)
			)
		)
		(property "Author" "Antmicro"
			(at 0 0 0)
			(layer "F.Fab")
			(hide yes)
			(effects
				(font
					(size 1 1)
					(thickness 0.15)
				)
			)
		)
		(property "License" "Apache-2.0"
			(at 0 0 0)
			(layer "F.Fab")
			(hide yes)
			(effects
				(font
					(size 1 1)
					(thickness 0.15)
				)
			)
		)
		(property "MPN" ""
			(at 0 0 0)
			(layer "F.Fab")
			(hide yes)
			(effects
				(font
					(size 1 1)
					(thickness 0.15)
				)
			)
		)
		(property "Manufacturer" ""
			(at 0 0 0)
			(layer "F.Fab")
			(hide yes)
			(effects
				(font
					(size 1 1)
					(thickness 0.15)
				)
			)
		)
		(property "Public" "False"
			(at 0 0 0)
			(layer "F.Fab")
			(hide yes)
			(effects
				(font
					(size 1 1)
					(thickness 0.15)
				)
			)
		)
		(sheetfile "environment-sensor.kicad_sch")
		(attr exclude_from_pos_files)
		(pad "1" smd circle
			(at 0 0 270)
			(size 1.5 1.5)
			(layers "F.Cu" "F.Mask")
			(net 25 "JTDI")
			(pinfunction "1")
			(pintype "passive")
		)
	)
	(footprint "antmicro-footprints:R_0402_1005Metric"
		(layer "F.Cu")
		(at 203.75 115.835 -90)
		(descr "Resistor SMD 0402")
		(tags "resistor SMD 0402")
		(property "Reference" "R36"
			(at 4.465 1.55 0)
			(layer "F.SilkS")
			(effects
				(font
					(size 0.7 0.7)
					(thickness 0.15)
				)
				(justify left bottom)
			)
		)
		(property "Value" "R_100k_0402"
			(at 0 1.4 90)
			(layer "F.Fab")
			(effects
				(font
					(size 0.7 0.7)
					(thickness 0.15)
				)
				(justify right bottom)
			)
		)
		(property "Description" "SMD Chip Resistor, 100 kohm, ± 1%, 62.5 mW, 0402 [1005 Metric], Thick Film, General Purpose"
			(at 0 0 270)
			(layer "F.Fab")
			(hide yes)
			(effects
				(font
					(size 1.27 1.27)
					(thickness 0.15)
				)
			)
		)
		(property "Author" "Antmicro"
			(at 87.915 319.585 0)
			(layer "F.Fab")
			(hide yes)
			(effects
				(font
					(size 1 1)
					(thickness 0.15)
				)
			)
		)
		(property "License" "Apache-2.0"
			(at 87.915 319.585 0)
			(layer "F.Fab")
			(hide yes)
			(effects
				(font
					(size 1 1)
					(thickness 0.15)
				)
			)
		)
		(property "MPN" "CR0402-FX-1003GLF"
			(at 87.915 319.585 0)
			(layer "F.Fab")
			(hide yes)
			(effects
				(font
					(size 1 1)
					(thickness 0.15)
				)
			)
		)
		(property "Manufacturer" "Bourns"
			(at 87.915 319.585 0)
			(layer "F.Fab")
			(hide yes)
			(effects
				(font
					(size 1 1)
					(thickness 0.15)
				)
			)
		)
		(property "Public" "False"
			(at 87.915 319.585 0)
			(layer "F.Fab")
			(hide yes)
			(effects
				(font
					(size 1 1)
					(thickness 0.15)
				)
			)
		)
		(property "Tolerance" "1%"
			(at 87.915 319.585 0)
			(layer "F.Fab")
			(hide yes)
			(effects
				(font
					(size 1 1)
					(thickness 0.15)
				)
			)
		)
		(property "Val" "100k"
			(at 87.915 319.585 0)
			(layer "F.Fab")
			(hide yes)
			(effects
				(font
					(size 1 1)
					(thickness 0.15)
				)
			)
		)
		(sheetfile "environment-sensor.kicad_sch")
		(attr smd)
		(fp_rect
			(start -0.925 -0.47)
			(end 0.925 0.47)
			(stroke
				(width 0.05)
				(type default)
			)
			(fill no)
			(layer "F.CrtYd")
		)
		(fp_rect
			(start -0.5 -0.25)
			(end 0.5 0.25)
			(stroke
				(width 0.15)
				(type solid)
			)
			(fill no)
			(layer "F.Fab")
		)
		(pad "1" smd roundrect
			(at -0.48 0 270)
			(size 0.59 0.64)
			(layers "F.Cu" "F.Mask" "F.Paste")
			(roundrect_rratio 0.25)
			(net 1 "GND")
			(pintype "passive")
		)
		(pad "2" smd roundrect
			(at 0.48 0 270)
			(size 0.59 0.64)
			(layers "F.Cu" "F.Mask" "F.Paste")
			(roundrect_rratio 0.25)
			(net 53 "Net-(U6-SDO)")
			(pintype "passive")
		)
	)
	(footprint "antmicro-footprints:TP_SMD_1.5mm"
		(locked yes)
		(layer "F.Cu")
		(at 193.5 116)
		(property "Reference" "TP2"
			(at -1.612 -1.214 0)
			(layer "F.SilkS")
			(hide yes)
			(effects
				(font
					(size 0.7 0.7)
					(thickness 0.15)
				)
				(justify left bottom)
			)
		)
		(property "Value" "TP_1.5mm_SMD"
			(at 0 1.7 0)
			(layer "F.Fab")
			(effects
				(font
					(size 0.7 0.7)
					(thickness 0.15)
				)
				(justify left bottom)
			)
		)
		(property "Description" "test point, SMT"
			(at 0 0 0)
			(layer "F.Fab")
			(hide yes)
			(effects
				(font
					(size 1.27 1.27)
					(thickness 0.15)
				)
			)
		)
		(property "Author" "Antmicro"
			(at 0 0 0)
			(layer "F.Fab")
			(hide yes)
			(effects
				(font
					(size 1 1)
					(thickness 0.15)
				)
			)
		)
		(property "License" "Apache-2.0"
			(at 0 0 0)
			(layer "F.Fab")
			(hide yes)
			(effects
				(font
					(size 1 1)
					(thickness 0.15)
				)
			)
		)
		(property "MPN" ""
			(at 0 0 0)
			(layer "F.Fab")
			(hide yes)
			(effects
				(font
					(size 1 1)
					(thickness 0.15)
				)
			)
		)
		(property "Manufacturer" ""
			(at 0 0 0)
			(layer "F.Fab")
			(hide yes)
			(effects
				(font
					(size 1 1)
					(thickness 0.15)
				)
			)
		)
		(property "Public" "False"
			(at 0 0 0)
			(layer "F.Fab")
			(hide yes)
			(effects
				(font
					(size 1 1)
					(thickness 0.15)
				)
			)
		)
		(sheetfile "environment-sensor.kicad_sch")
		(attr exclude_from_pos_files)
		(pad "1" smd circle
			(at 0 0 270)
			(size 1.5 1.5)
			(layers "F.Cu" "F.Mask")
			(net 13 "JTRST")
			(pinfunction "1")
			(pintype "passive")
		)
	)
	(footprint "antmicro-footprints:LGA-8_2.5x2.5mm_BME280"
		(layer "F.Cu")
		(at 207.5 116 -90)
		(property "Reference" "U6"
			(at 0 -2.301 90)
			(layer "F.SilkS")
			(effects
				(font
					(size 0.7 0.7)
					(thickness 0.15)
				)
				(justify right bottom)
			)
		)
		(property "Value" "BME280"
			(at 0 2.47 90)
			(layer "F.Fab")
			(effects
				(font
					(size 0.7 0.7)
					(thickness 0.15)
				)
				(justify right bottom)
			)
		)
		(property "Description" "Sensor"
			(at 0 0 270)
			(layer "F.Fab")
			(hide yes)
			(effects
				(font
					(size 1.27 1.27)
					(thickness 0.15)
				)
			)
		)
		(property "Author" "Antmicro"
			(at 91.5 323.5 0)
			(layer "F.Fab")
			(hide yes)
			(effects
				(font
					(size 1 1)
					(thickness 0.15)
				)
			)
		)
		(property "License" "Apache-2.0"
			(at 91.5 323.5 0)
			(layer "F.Fab")
			(hide yes)
			(effects
				(font
					(size 1 1)
					(thickness 0.15)
				)
			)
		)
		(property "MPN" "BME280"
			(at 91.5 323.5 0)
			(layer "F.Fab")
			(hide yes)
			(effects
				(font
					(size 1 1)
					(thickness 0.15)
				)
			)
		)
		(property "Manufacturer" "Bosch"
			(at 91.5 323.5 0)
			(layer "F.Fab")
			(hide yes)
			(effects
				(font
					(size 1 1)
					(thickness 0.15)
				)
			)
		)
		(sheetfile "environment-sensor.kicad_sch")
		(attr smd)
		(fp_line
			(start -1.351 1.35)
			(end -0.85 1.35)
			(stroke
				(width 0.15)
				(type solid)
			)
			(layer "F.SilkS")
		)
		(fp_line
			(start -1.351 1.35)
			(end -1.351 0.848)
			(stroke
				(width 0.15)
				(type solid)
			)
			(layer "F.SilkS")
		)
		(fp_line
			(start 1.35 1.35)
			(end 0.848 1.35)
			(stroke
				(width 0.15)
				(type solid)
			)
			(layer "F.SilkS")
		)
		(fp_line
			(start 1.35 1.35)
			(end 1.35 0.848)
			(stroke
				(width 0.15)
				(type solid)
			)
			(layer "F.SilkS")
		)
		(fp_line
			(start -1.351 -1.351)
			(end -1.351 -0.85)
			(stroke
				(width 0.15)
				(type solid)
			)
			(layer "F.SilkS")
		)
		(fp_line
			(start -1.351 -1.351)
			(end -0.85 -1.351)
			(stroke
				(width 0.15)
				(type solid)
			)
			(layer "F.SilkS")
		)
		(fp_line
			(start 1.35 -1.351)
			(end 1.35 -0.975)
			(stroke
				(width 0.15)
				(type solid)
			)
			(layer "F.SilkS")
		)
		(fp_line
			(start 1.35 -1.351)
			(end 0.973 -1.351)
			(stroke
				(width 0.15)
				(type solid)
			)
			(layer "F.SilkS")
		)
		(fp_circle
			(center -1 -1.6)
			(end -0.95 -1.6)
			(stroke
				(width 0.15)
				(type solid)
			)
			(fill yes)
			(layer "F.SilkS")
		)
		(fp_rect
			(start -1.6 -1.6)
			(end 1.6 1.6)
			(stroke
				(width 0.05)
				(type solid)
			)
			(fill no)
			(layer "F.CrtYd")
		)
		(fp_line
			(start -1.25 1.249)
			(end -1.25 -0.635)
			(stroke
				(width 0.15)
				(type solid)
			)
			(layer "F.Fab")
		)
		(fp_line
			(start 1.249 1.249)
			(end -1.25 1.249)
			(stroke
				(width 0.15)
				(type solid)
			)
			(layer "F.Fab")
		)
		(fp_line
			(start -0.635 -1.25)
			(end -1.25 -0.635)
			(stroke
				(width 0.15)
				(type solid)
			)
			(layer "F.Fab")
		)
		(fp_line
			(start -0.635 -1.25)
			(end 1.249 -1.25)
			(stroke
				(width 0.15)
				(type solid)
			)
			(layer "F.Fab")
		)
		(fp_line
			(start 1.249 -1.25)
			(end 1.249 1.249)
			(stroke
				(width 0.15)
				(type solid)
			)
			(layer "F.Fab")
		)
		(pad "1" smd rect
			(at -0.975 -1.025 270)
			(size 0.35 0.5)
			(layers "F.Cu" "F.Mask" "F.Paste")
			(net 1 "GND")
			(pinfunction "GND")
			(pintype "power_in")
		)
		(pad "2" smd rect
			(at -0.327 -1.025 270)
			(size 0.35 0.5)
			(layers "F.Cu" "F.Mask" "F.Paste")
			(net 2 "+3V3")
			(pinfunction "CSB")
			(pintype "input")
		)
		(pad "3" smd rect
			(at 0.325 -1.025 270)
			(size 0.35 0.5)
			(layers "F.Cu" "F.Mask" "F.Paste")
			(net 9 "I2C_1_SDA")
			(pinfunction "SDI")
			(pintype "bidirectional")
		)
		(pad "4" smd rect
			(at 0.973 -1.025 270)
			(size 0.35 0.5)
			(layers "F.Cu" "F.Mask" "F.Paste")
			(net 8 "I2C_1_SCL")
			(pinfunction "SCK")
			(pintype "input")
		)
		(pad "5" smd rect
			(at 0.973 1.024 270)
			(size 0.35 0.5)
			(layers "F.Cu" "F.Mask" "F.Paste")
			(net 53 "Net-(U6-SDO)")
			(pinfunction "SDO")
			(pintype "bidirectional")
		)
		(pad "6" smd rect
			(at 0.325 1.024 270)
			(size 0.35 0.5)
			(layers "F.Cu" "F.Mask" "F.Paste")
			(net 2 "+3V3")
			(pinfunction "VDDIO")
			(pintype "power_in")
		)
		(pad "7" smd rect
			(at -0.327 1.024 270)
			(size 0.35 0.5)
			(layers "F.Cu" "F.Mask" "F.Paste")
			(net 1 "GND")
			(pinfunction "GND")
			(pintype "passive")
		)
		(pad "8" smd rect
			(at -0.975 1.024 270)
			(size 0.35 0.5)
			(layers "F.Cu" "F.Mask" "F.Paste")
			(net 2 "+3V3")
			(pinfunction "VDD")
			(pintype "power_in")
		)
	)
	(footprint "antmicro-footprints:R_0402_1005Metric"
		(layer "F.Cu")
		(at 190.444 125.087 90)
		(descr "Resistor SMD 0402")
		(tags "resistor SMD 0402")
		(property "Reference" "R27"
			(at 3.887 4.656 0)
			(layer "F.SilkS")
			(effects
				(font
					(size 0.7 0.7)
					(thickness 0.15)
				)
				(justify left bottom)
			)
		)
		(property "Value" "R_100R_0402"
			(at 0 1.4 90)
			(layer "F.Fab")
			(effects
				(font
					(size 0.7 0.7)
					(thickness 0.15)
				)
				(justify left bottom)
			)
		)
		(property "Description" "SMD Chip Resistor, 100 ohm, ± 1%, 62.5 mW, 0402 [1005 Metric], Thick Film, General Purpose"
			(at 0 0 90)
			(layer "F.Fab")
			(hide yes)
			(effects
				(font
					(size 1.27 1.27)
					(thickness 0.15)
				)
			)
		)
		(property "Author" "Antmicro"
			(at 315.531 -65.357 0)
			(layer "F.Fab")
			(hide yes)
			(effects
				(font
					(size 1 1)
					(thickness 0.15)
				)
			)
		)
		(property "License" "Apache-2.0"
			(at 315.531 -65.357 0)
			(layer "F.Fab")
			(hide yes)
			(effects
				(font
					(size 1 1)
					(thickness 0.15)
				)
			)
		)
		(property "MPN" "CR0402-FX-1000GLF"
			(at 315.531 -65.357 0)
			(layer "F.Fab")
			(hide yes)
			(effects
				(font
					(size 1 1)
					(thickness 0.15)
				)
			)
		)
		(property "Manufacturer" "Bourns"
			(at 315.531 -65.357 0)
			(layer "F.Fab")
			(hide yes)
			(effects
				(font
					(size 1 1)
					(thickness 0.15)
				)
			)
		)
		(property "Public" "False"
			(at 315.531 -65.357 0)
			(layer "F.Fab")
			(hide yes)
			(effects
				(font
					(size 1 1)
					(thickness 0.15)
				)
			)
		)
		(property "Tolerance" "1%"
			(at 315.531 -65.357 0)
			(layer "F.Fab")
			(hide yes)
			(effects
				(font
					(size 1 1)
					(thickness 0.15)
				)
			)
		)
		(property "Val" "100R"
			(at 315.531 -65.357 0)
			(layer "F.Fab")
			(hide yes)
			(effects
				(font
					(size 1 1)
					(thickness 0.15)
				)
			)
		)
		(sheetfile "environment-sensor.kicad_sch")
		(attr smd)
		(fp_rect
			(start -0.925 -0.47)
			(end 0.925 0.47)
			(stroke
				(width 0.05)
				(type default)
			)
			(fill no)
			(layer "F.CrtYd")
		)
		(fp_rect
			(start -0.5 -0.25)
			(end 0.5 0.25)
			(stroke
				(width 0.15)
				(type solid)
			)
			(fill no)
			(layer "F.Fab")
		)
		(pad "1" smd roundrect
			(at -0.48 0 90)
			(size 0.59 0.64)
			(layers "F.Cu" "F.Mask" "F.Paste")
			(roundrect_rratio 0.25)
			(net 49 "Net-(U3-PB8-BOOT0)")
			(pintype "passive")
		)
		(pad "2" smd roundrect
			(at 0.48 0 90)
			(size 0.59 0.64)
			(layers "F.Cu" "F.Mask" "F.Paste")
			(roundrect_rratio 0.25)
			(net 8 "I2C_1_SCL")
			(pintype "passive")
		)
	)
	(footprint "antmicro-footprints:R_0402_1005Metric"
		(layer "F.Cu")
		(at 198.5 132.5)
		(descr "Resistor SMD 0402")
		(tags "resistor SMD 0402")
		(property "Reference" "R21"
			(at 0.85 0.4 0)
			(layer "F.SilkS")
			(effects
				(font
					(size 0.7 0.7)
					(thickness 0.15)
				)
				(justify left bottom)
			)
		)
		(property "Value" "R_100R_0402"
			(at -1.011843 1.772047 0)
			(layer "F.Fab")
			(effects
				(font
					(size 0.7 0.7)
					(thickness 0.15)
				)
				(justify left bottom)
			)
		)
		(property "Description" "SMD Chip Resistor, 100 ohm, ± 1%, 62.5 mW, 0402 [1005 Metric], Thick Film, General Purpose"
			(at 0 0 0)
			(layer "F.Fab")
			(hide yes)
			(effects
				(font
					(size 1.27 1.27)
					(thickness 0.15)
				)
			)
		)
		(property "Author" "Antmicro"
			(at 0 0 0)
			(layer "F.Fab")
			(hide yes)
			(effects
				(font
					(size 1 1)
					(thickness 0.15)
				)
			)
		)
		(property "License" "Apache-2.0"
			(at 0 0 0)
			(layer "F.Fab")
			(hide yes)
			(effects
				(font
					(size 1 1)
					(thickness 0.15)
				)
			)
		)
		(property "MPN" "CR0402-FX-1000GLF"
			(at 0 0 0)
			(layer "F.Fab")
			(hide yes)
			(effects
				(font
					(size 1 1)
					(thickness 0.15)
				)
			)
		)
		(property "Manufacturer" "Bourns"
			(at 0 0 0)
			(layer "F.Fab")
			(hide yes)
			(effects
				(font
					(size 1 1)
					(thickness 0.15)
				)
			)
		)
		(property "Public" "False"
			(at 0 0 0)
			(layer "F.Fab")
			(hide yes)
			(effects
				(font
					(size 1 1)
					(thickness 0.15)
				)
			)
		)
		(property "Tolerance" "1%"
			(at 0 0 0)
			(layer "F.Fab")
			(hide yes)
			(effects
				(font
					(size 1 1)
					(thickness 0.15)
				)
			)
		)
		(property "Val" "100R"
			(at 0 0 0)
			(layer "F.Fab")
			(hide yes)
			(effects
				(font
					(size 1 1)
					(thickness 0.15)
				)
			)
		)
		(sheetfile "environment-sensor.kicad_sch")
		(attr smd exclude_from_pos_files exclude_from_bom dnp)
		(fp_rect
			(start -0.925 -0.47)
			(end 0.925 0.47)
			(stroke
				(width 0.05)
				(type default)
			)
			(fill no)
			(layer "F.CrtYd")
		)
		(fp_rect
			(start -0.5 -0.25)
			(end 0.5 0.25)
			(stroke
				(width 0.15)
				(type solid)
			)
			(fill no)
			(layer "F.Fab")
		)
		(pad "1" smd roundrect
			(at -0.48 0)
			(size 0.59 0.64)
			(layers "F.Cu" "F.Mask" "F.Paste")
			(roundrect_rratio 0.25)
			(net 47 "Net-(U3-PA8)")
			(pintype "passive")
		)
		(pad "2" smd roundrect
			(at 0.48 0)
			(size 0.59 0.64)
			(layers "F.Cu" "F.Mask" "F.Paste")
			(roundrect_rratio 0.25)
			(net 9 "I2C_1_SDA")
			(pintype "passive")
		)
	)
	(footprint "antmicro-footprints:R_0402_1005Metric"
		(layer "F.Cu")
		(at 184.75 126.25 -90)
		(descr "Resistor SMD 0402")
		(tags "resistor SMD 0402")
		(property "Reference" "R9"
			(at -10.25 -0.95 90)
			(layer "B.SilkS")
			(effects
				(font
					(size 0.7 0.7)
					(thickness 0.15)
				)
				(justify right bottom mirror)
			)
		)
		(property "Value" "R_0R_0402"
			(at 0 1.4 90)
			(layer "F.Fab")
			(effects
				(font
					(size 0.7 0.7)
					(thickness 0.15)
				)
				(justify right bottom)
			)
		)
		(property "Description" "SMD Chip Resistor, Jumper, 0 ohm, 100 mW, 0402 [1005 Metric], Thick Film, General Purpose"
			(at 0 0 270)
			(layer "F.Fab")
			(hide yes)
			(effects
				(font
					(size 1.27 1.27)
					(thickness 0.15)
				)
			)
		)
		(property "Author" "Antmicro"
			(at 58.5 311 0)
			(layer "F.Fab")
			(hide yes)
			(effects
				(font
					(size 1 1)
					(thickness 0.15)
				)
			)
		)
		(property "Current" "1A"
			(at 58.5 311 0)
			(layer "F.Fab")
			(hide yes)
			(effects
				(font
					(size 1 1)
					(thickness 0.15)
				)
			)
		)
		(property "License" "Apache-2.0"
			(at 58.5 311 0)
			(layer "F.Fab")
			(hide yes)
			(effects
				(font
					(size 1 1)
					(thickness 0.15)
				)
			)
		)
		(property "MPN" "ERJ2GE0R00X"
			(at 58.5 311 0)
			(layer "F.Fab")
			(hide yes)
			(effects
				(font
					(size 1 1)
					(thickness 0.15)
				)
			)
		)
		(property "Manufacturer" "Panasonic"
			(at 58.5 311 0)
			(layer "F.Fab")
			(hide yes)
			(effects
				(font
					(size 1 1)
					(thickness 0.15)
				)
			)
		)
		(property "Public" "False"
			(at 58.5 311 0)
			(layer "F.Fab")
			(hide yes)
			(effects
				(font
					(size 1 1)
					(thickness 0.15)
				)
			)
		)
		(property "Tolerance" ""
			(at 58.5 311 0)
			(layer "F.Fab")
			(hide yes)
			(effects
				(font
					(size 1 1)
					(thickness 0.15)
				)
			)
		)
		(property "Val" "0R"
			(at 58.5 311 0)
			(layer "F.Fab")
			(hide yes)
			(effects
				(font
					(size 1 1)
					(thickness 0.15)
				)
			)
		)
		(sheetfile "environment-sensor.kicad_sch")
		(attr smd)
		(fp_rect
			(start -0.925 -0.47)
			(end 0.925 0.47)
			(stroke
				(width 0.05)
				(type default)
			)
			(fill no)
			(layer "F.CrtYd")
		)
		(fp_rect
			(start -0.5 -0.25)
			(end 0.5 0.25)
			(stroke
				(width 0.15)
				(type solid)
			)
			(fill no)
			(layer "F.Fab")
		)
		(pad "1" smd roundrect
			(at -0.48 0 270)
			(size 0.59 0.64)
			(layers "F.Cu" "F.Mask" "F.Paste")
			(roundrect_rratio 0.25)
			(net 41 "Net-(U1-CTS#)")
			(pintype "passive")
		)
		(pad "2" smd roundrect
			(at 0.48 0 270)
			(size 0.59 0.64)
			(layers "F.Cu" "F.Mask" "F.Paste")
			(roundrect_rratio 0.25)
			(net 19 "JTDO")
			(pintype "passive")
		)
	)
	(footprint "antmicro-footprints:LED_0603_1608Metric_G"
		(layer "F.Cu")
		(at 175.1 138.7)
		(descr "LED SMD 0603 Green")
		(tags "LED SMD 0603 Green")
		(property "Reference" "LD2"
			(at 25.7 0.9 0)
			(layer "F.SilkS")
			(effects
				(font
					(size 0.7 0.7)
					(thickness 0.15)
				)
				(justify left bottom)
			)
		)
		(property "Value" "LED_G_0603_KP-1608ZGC"
			(at 0 1.6 0)
			(layer "F.Fab")
			(effects
				(font
					(size 0.7 0.7)
					(thickness 0.15)
				)
				(justify left bottom)
			)
		)
		(property "Description" "LED, Green, SMD, 0603, 20 mA, 3.3 V, 525 nm"
			(at 0 0 0)
			(layer "F.Fab")
			(hide yes)
			(effects
				(font
					(size 1.27 1.27)
					(thickness 0.15)
				)
			)
		)
		(property "Author" "Antmicro"
			(at 0 0 0)
			(layer "F.Fab")
			(hide yes)
			(effects
				(font
					(size 1 1)
					(thickness 0.15)
				)
			)
		)
		(property "Color" "Green"
			(at 0 0 0)
			(layer "F.Fab")
			(hide yes)
			(effects
				(font
					(size 1 1)
					(thickness 0.15)
				)
			)
		)
		(property "License" "Apache-2.0"
			(at 0 0 0)
			(layer "F.Fab")
			(hide yes)
			(effects
				(font
					(size 1 1)
					(thickness 0.15)
				)
			)
		)
		(property "MPN" "KP-1608ZGC"
			(at 0 0 0)
			(layer "F.Fab")
			(hide yes)
			(effects
				(font
					(size 1 1)
					(thickness 0.15)
				)
			)
		)
		(property "Manufacturer" "Kingbright"
			(at 0 0 0)
			(layer "F.Fab")
			(hide yes)
			(effects
				(font
					(size 1 1)
					(thickness 0.15)
				)
			)
		)
		(property "Public" "False"
			(at 0 0 0)
			(layer "F.Fab")
			(hide yes)
			(effects
				(font
					(size 1 1)
					(thickness 0.15)
				)
			)
		)
		(sheetfile "environment-sensor.kicad_sch")
		(attr smd)
		(fp_line
			(start -1.18 -0.319)
			(end -1.18 0.321)
			(stroke
				(width 0.15)
				(type solid)
			)
			(layer "F.SilkS")
		)
		(fp_line
			(start -0.094672 0.001008)
			(end -0.24 0.001008)
			(stroke
				(width 0.1)
				(type solid)
			)
			(layer "F.SilkS")
		)
		(fp_line
			(start -0.094672 0.001008)
			(end 0.105328 -0.198992)
			(stroke
				(width 0.1)
				(type solid)
			)
			(layer "F.SilkS")
		)
		(fp_line
			(start -0.094672 0.201008)
			(end -0.094672 -0.198992)
			(stroke
				(width 0.1)
				(type solid)
			)
			(layer "F.SilkS")
		)
		(fp_line
			(start 0.105328 0.001008)
			(end 0.24 0.001)
			(stroke
				(width 0.1)
				(type solid)
			)
			(layer "F.SilkS")
		)
		(fp_line
			(start 0.105328 0.201008)
			(end -0.094672 0.001008)
			(stroke
				(width 0.1)
				(type solid)
			)
			(layer "F.SilkS")
		)
		(fp_line
			(start 0.105328 0.201008)
			(end 0.105328 -0.198992)
			(stroke
				(width 0.1)
				(type solid)
			)
			(layer "F.SilkS")
		)
		(fp_line
			(start 0.22 -0.35)
			(end -0.22 -0.35)
			(stroke
				(width 0.15)
				(type solid)
			)
			(layer "F.SilkS")
		)
		(fp_line
			(start 0.22 0.35)
			(end -0.22 0.35)
			(stroke
				(width 0.15)
				(type solid)
			)
			(layer "F.SilkS")
		)
		(fp_rect
			(start 1.25 0.65)
			(end -1.25 -0.65)
			(stroke
				(width 0.05)
				(type solid)
			)
			(fill no)
			(layer "F.CrtYd")
		)
		(fp_line
			(start -0.199 -0.202)
			(end -0.199 0.1)
			(stroke
				(width 0.15)
				(type solid)
			)
			(layer "F.Fab")
		)
		(fp_line
			(start -0.199 0)
			(end -0.597 0)
			(stroke
				(width 0.15)
				(type solid)
			)
			(layer "F.Fab")
		)
		(fp_line
			(start -0.199 0.2)
			(end -0.199 0.1)
			(stroke
				(width 0.15)
				(type solid)
			)
			(layer "F.Fab")
		)
		(fp_line
			(start -0.101 0)
			(end 0.201 0.2)
			(stroke
				(width 0.15)
				(type solid)
			)
			(layer "F.Fab")
		)
		(fp_line
			(start 0.201 -0.202)
			(end -0.101 0)
			(stroke
				(width 0.15)
				(type solid)
			)
			(layer "F.Fab")
		)
		(fp_line
			(start 0.201 0)
			(end 0.201 -0.202)
			(stroke
				(width 0.15)
				(type solid)
			)
			(layer "F.Fab")
		)
		(fp_line
			(start 0.201 0.2)
			(end 0.201 0)
			(stroke
				(width 0.15)
				(type solid)
			)
			(layer "F.Fab")
		)
		(fp_line
			(start 0.599 0)
			(end 0.201 0)
			(stroke
				(width 0.15)
				(type solid)
			)
			(layer "F.Fab")
		)
		(fp_rect
			(start 0.848 0.4)
			(end -0.85 -0.402)
			(stroke
				(width 0.15)
				(type solid)
			)
			(fill no)
			(layer "F.Fab")
		)
		(pad "1" smd roundrect
			(at -0.7 0 180)
			(size 0.8 1)
			(layers "F.Cu" "F.Mask" "F.Paste")
			(roundrect_rratio 0.2)
			(net 12 "/LD2")
			(pinfunction "C")
			(pintype "passive")
		)
		(pad "2" smd roundrect
			(at 0.7 0 180)
			(size 0.8 1)
			(layers "F.Cu" "F.Mask" "F.Paste")
			(roundrect_rratio 0.2)
			(net 11 "Net-(LD2-A)")
			(pinfunction "A")
			(pintype "passive")
		)
	)
	(footprint "antmicro-footprints:C_0402_1005Metric"
		(layer "F.Cu")
		(at 205.15 115.835 90)
		(descr "Capacitor SMD 0402")
		(tags "capacitor SMD 0402")
		(property "Reference" "C27"
			(at -5.461 -2.977 180)
			(layer "F.SilkS")
			(effects
				(font
					(size 0.7 0.7)
					(thickness 0.15)
				)
				(justify left bottom)
			)
		)
		(property "Value" "C_100n_0402"
			(at 0 1.4 90)
			(layer "F.Fab")
			(effects
				(font
					(size 0.7 0.7)
					(thickness 0.15)
				)
				(justify left bottom)
			)
		)
		(property "Description" "SMD Multilayer Ceramic Capacitor, 0.1 µF, 50 V, 0402 [1005 Metric], ± 10%, X5R, GRM Series"
			(at 0 0 90)
			(layer "F.Fab")
			(hide yes)
			(effects
				(font
					(size 1.27 1.27)
					(thickness 0.15)
				)
			)
		)
		(property "Author" "Antmicro"
			(at 320.985 -89.315 0)
			(layer "F.Fab")
			(hide yes)
			(effects
				(font
					(size 1 1)
					(thickness 0.15)
				)
			)
		)
		(property "Dielectric" "X5R"
			(at 320.985 -89.315 0)
			(layer "F.Fab")
			(hide yes)
			(effects
				(font
					(size 1 1)
					(thickness 0.15)
				)
			)
		)
		(property "License" "Apache-2.0"
			(at 320.985 -89.315 0)
			(layer "F.Fab")
			(hide yes)
			(effects
				(font
					(size 1 1)
					(thickness 0.15)
				)
			)
		)
		(property "MPN" "GRM155R61H104KE14D"
			(at 320.985 -89.315 0)
			(layer "F.Fab")
			(hide yes)
			(effects
				(font
					(size 1 1)
					(thickness 0.15)
				)
			)
		)
		(property "Manufacturer" "Murata"
			(at 320.985 -89.315 0)
			(layer "F.Fab")
			(hide yes)
			(effects
				(font
					(size 1 1)
					(thickness 0.15)
				)
			)
		)
		(property "Public" "False"
			(at 320.985 -89.315 0)
			(layer "F.Fab")
			(hide yes)
			(effects
				(font
					(size 1 1)
					(thickness 0.15)
				)
			)
		)
		(property "Val" "100n"
			(at 320.985 -89.315 0)
			(layer "F.Fab")
			(hide yes)
			(effects
				(font
					(size 1 1)
					(thickness 0.15)
				)
			)
		)
		(property "Voltage" "50V"
			(at 320.985 -89.315 0)
			(layer "F.Fab")
			(hide yes)
			(effects
				(font
					(size 1 1)
					(thickness 0.15)
				)
			)
		)
		(sheetfile "environment-sensor.kicad_sch")
		(attr smd)
		(fp_rect
			(start -0.925 -0.47)
			(end 0.925 0.47)
			(stroke
				(width 0.05)
				(type default)
			)
			(fill no)
			(layer "F.CrtYd")
		)
		(fp_line
			(start 0.504 -0.25)
			(end 0.504 0.248)
			(stroke
				(width 0.15)
				(type solid)
			)
			(layer "F.Fab")
		)
		(fp_line
			(start -0.494 -0.25)
			(end 0.504 -0.25)
			(stroke
				(width 0.15)
				(type solid)
			)
			(layer "F.Fab")
		)
		(fp_line
			(start 0.504 0.248)
			(end -0.494 0.248)
			(stroke
				(width 0.15)
				(type solid)
			)
			(layer "F.Fab")
		)
		(fp_line
			(start -0.494 0.248)
			(end -0.494 -0.25)
			(stroke
				(width 0.15)
				(type solid)
			)
			(layer "F.Fab")
		)
		(pad "1" smd roundrect
			(at -0.48 0 90)
			(size 0.59 0.64)
			(layers "F.Cu" "F.Mask" "F.Paste")
			(roundrect_rratio 0.25)
			(net 1 "GND")
			(pintype "passive")
		)
		(pad "2" smd roundrect
			(at 0.48 0 90)
			(size 0.59 0.64)
			(layers "F.Cu" "F.Mask" "F.Paste")
			(roundrect_rratio 0.25)
			(net 2 "+3V3")
			(pintype "passive")
		)
	)
	(footprint "antmicro-footprints:SOD-923"
		(layer "F.Cu")
		(at 168.035 129.55 90)
		(property "Reference" "D2"
			(at 1.15 -0.385 0)
			(unlocked yes)
			(layer "F.SilkS")
			(effects
				(font
					(size 0.65 0.65)
					(thickness 0.15)
				)
			)
		)
		(property "Value" "ESD9X5.0ST5G"
			(at 0 2.4 90)
			(unlocked yes)
			(layer "F.Fab")
			(effects
				(font
					(size 1 1)
					(thickness 0.15)
				)
			)
		)
		(property "Description" "Unidirectional TVS, 30 kV,  SOD-923, 5 V, 65 pF"
			(at 0 0 90)
			(layer "F.Fab")
			(hide yes)
			(effects
				(font
					(size 1.27 1.27)
					(thickness 0.15)
				)
			)
		)
		(property "Author" "Antmicro"
			(at 297.585 -38.485 0)
			(layer "F.Fab")
			(hide yes)
			(effects
				(font
					(size 1 1)
					(thickness 0.15)
				)
			)
		)
		(property "License" "Apache-2.0"
			(at 297.585 -38.485 0)
			(layer "F.Fab")
			(hide yes)
			(effects
				(font
					(size 1 1)
					(thickness 0.15)
				)
			)
		)
		(property "MPN" "ESD9X5.0ST5G"
			(at 297.585 -38.485 0)
			(layer "F.Fab")
			(hide yes)
			(effects
				(font
					(size 1 1)
					(thickness 0.15)
				)
			)
		)
		(property "Manufacturer" "ON Semiconductor"
			(at 297.585 -38.485 0)
			(layer "F.Fab")
			(hide yes)
			(effects
				(font
					(size 1 1)
					(thickness 0.15)
				)
			)
		)
		(property "Public" "False"
			(at 297.585 -38.485 0)
			(layer "F.Fab")
			(hide yes)
			(effects
				(font
					(size 1 1)
					(thickness 0.15)
				)
			)
		)
		(sheetfile "environment-sensor.kicad_sch")
		(attr smd)
		(fp_line
			(start 0.5 -0.4)
			(end 0.5 -0.3)
			(stroke
				(width 0.15)
				(type solid)
			)
			(layer "F.SilkS")
		)
		(fp_line
			(start -0.16 -0.4)
			(end -0.16 0.4)
			(stroke
				(width 0.15)
				(type solid)
			)
			(layer "F.SilkS")
		)
		(fp_line
			(start -0.5 -0.4)
			(end 0.5 -0.4)
			(stroke
				(width 0.15)
				(type solid)
			)
			(layer "F.SilkS")
		)
		(fp_line
			(start -0.5 -0.3)
			(end -0.5 -0.4)
			(stroke
				(width 0.15)
				(type solid)
			)
			(layer "F.SilkS")
		)
		(fp_line
			(start 0.5 0.4)
			(end 0.5 0.3)
			(stroke
				(width 0.15)
				(type solid)
			)
			(layer "F.SilkS")
		)
		(fp_line
			(start -0.5 0.4)
			(end -0.5 0.3)
			(stroke
				(width 0.15)
				(type solid)
			)
			(layer "F.SilkS")
		)
		(fp_line
			(start -0.5 0.4)
			(end 0.5 0.4)
			(stroke
				(width 0.15)
				(type solid)
			)
			(layer "F.SilkS")
		)
		(fp_rect
			(start -0.68 -0.41)
			(end 0.68 0.41)
			(stroke
				(width 0.05)
				(type solid)
			)
			(fill no)
			(layer "F.CrtYd")
		)
		(fp_line
			(start -0.202 -0.3)
			(end -0.202 0.298)
			(stroke
				(width 0.15)
				(type solid)
			)
			(layer "F.Fab")
		)
		(fp_rect
			(start -0.402 -0.3)
			(end 0.4 0.298)
			(stroke
				(width 0.15)
				(type solid)
			)
			(fill no)
			(layer "F.Fab")
		)
		(fp_text user "${REFERENCE}"
			(at 0 1.1 90)
			(unlocked yes)
			(layer "F.Fab")
			(effects
				(font
					(size 1 1)
					(thickness 0.15)
				)
			)
		)
		(pad "1" smd roundrect
			(at -0.438 0 90)
			(size 0.4 0.325)
			(layers "F.Cu" "F.Mask" "F.Paste")
			(roundrect_rratio 0.25)
			(net 1 "GND")
			(pinfunction "C")
			(pintype "passive")
		)
		(pad "2" smd roundrect
			(at 0.436 0 90)
			(size 0.4 0.325)
			(layers "F.Cu" "F.Mask" "F.Paste")
			(roundrect_rratio 0.25)
			(net 27 "/VBUS")
			(pinfunction "A")
			(pintype "passive")
		)
	)
	(footprint "antmicro-footprints:oshw-logo"
		(layer "B.Cu")
		(at 206.621 129.967 180)
		(descr "OSHW Logo")
		(tags "OSHW Logo")
		(property "Reference" "N2"
			(at 0 4.4 0)
			(layer "B.SilkS")
			(hide yes)
			(effects
				(font
					(size 0.7 0.7)
					(thickness 0.15)
				)
				(justify left bottom mirror)
			)
		)
		(property "Value" "oshw_logo"
			(at 0 3.4 0)
			(layer "B.Fab")
			(hide yes)
			(effects
				(font
					(size 0.7 0.7)
					(thickness 0.15)
				)
				(justify left bottom mirror)
			)
		)
		(property "Description" "Mechanical part"
			(at 0 0 180)
			(layer "F.Fab")
			(hide yes)
			(effects
				(font
					(size 1.27 1.27)
					(thickness 0.15)
				)
			)
		)
		(property "Author" "Antmicro"
			(at 413.242 259.934 0)
			(layer "B.Fab")
			(hide yes)
			(effects
				(font
					(size 1 1)
					(thickness 0.15)
				)
				(justify mirror)
			)
		)
		(property "License" "Apache-2.0"
			(at 413.242 259.934 0)
			(layer "B.Fab")
			(hide yes)
			(effects
				(font
					(size 1 1)
					(thickness 0.15)
				)
				(justify mirror)
			)
		)
		(property "MPN" ""
			(at 413.242 259.934 0)
			(layer "B.Fab")
			(hide yes)
			(effects
				(font
					(size 1 1)
					(thickness 0.15)
				)
				(justify mirror)
			)
		)
		(property "Manufacturer" ""
			(at 413.242 259.934 0)
			(layer "B.Fab")
			(hide yes)
			(effects
				(font
					(size 1 1)
					(thickness 0.15)
				)
				(justify mirror)
			)
		)
		(property "Public" "False"
			(at 413.242 259.934 0)
			(layer "B.Fab")
			(hide yes)
			(effects
				(font
					(size 1 1)
					(thickness 0.15)
				)
				(justify mirror)
			)
		)
		(sheetfile "environment-sensor.kicad_sch")
		(attr exclude_from_pos_files exclude_from_bom allow_soldermask_bridges)
		(fp_poly
			(pts
				(xy -0.843 -2.558) (xy -0.815 -2.564) (xy -0.794 -2.572) (xy -0.773 -2.581) (xy -0.759 -2.589) (xy -0.738 -2.603)
				(xy -0.783 -2.658) (xy -0.8 -2.677) (xy -0.814 -2.694) (xy -0.825 -2.706) (xy -0.831 -2.712) (xy -0.832 -2.712)
				(xy -0.837 -2.71) (xy -0.847 -2.703) (xy -0.849 -2.702) (xy -0.874 -2.69) (xy -0.904 -2.684) (xy -0.935 -2.685)
				(xy -0.942 -2.686) (xy -0.975 -2.698) (xy -1.001 -2.717) (xy -1.02 -2.741) (xy -1.034 -2.766) (xy -1.039 -3.197)
				(xy -1.164 -3.2) (xy -1.164 -2.565) (xy -1.037 -2.565) (xy -1.037 -2.626) (xy -1.009 -2.604) (xy -0.972 -2.579)
				(xy -0.931 -2.563) (xy -0.887 -2.556) (xy -0.843 -2.558)
			)
			(stroke
				(width 0.01)
				(type solid)
			)
			(fill yes)
			(layer "B.Cu")
		)
		(fp_poly
			(pts
				(xy 1.889 -1.554) (xy 1.907 -1.559) (xy 1.927 -1.566) (xy 1.948 -1.574) (xy 1.966 -1.583) (xy 1.979 -1.592)
				(xy 1.984 -1.597) (xy 1.982 -1.604) (xy 1.974 -1.616) (xy 1.962 -1.633) (xy 1.946 -1.652) (xy 1.945 -1.654)
				(xy 1.929 -1.673) (xy 1.915 -1.689) (xy 1.906 -1.7) (xy 1.901 -1.706) (xy 1.896 -1.705) (xy 1.885 -1.7)
				(xy 1.873 -1.695) (xy 1.84 -1.683) (xy 1.808 -1.68) (xy 1.776 -1.685) (xy 1.747 -1.698) (xy 1.723 -1.717)
				(xy 1.704 -1.742) (xy 1.696 -1.763) (xy 1.695 -1.772) (xy 1.694 -1.79) (xy 1.693 -1.817) (xy 1.692 -1.85)
				(xy 1.692 -1.89) (xy 1.691 -1.934) (xy 1.691 -1.983) (xy 1.691 -2.194) (xy 1.559 -2.194) (xy 1.559 -1.559)
				(xy 1.691 -1.559) (xy 1.691 -1.626) (xy 1.71 -1.607) (xy 1.739 -1.585) (xy 1.775 -1.568) (xy 1.814 -1.556)
				(xy 1.855 -1.552) (xy 1.889 -1.554)
			)
			(stroke
				(width 0.01)
				(type solid)
			)
			(fill yes)
			(layer "B.Cu")
		)
		(fp_poly
			(pts
				(xy -0.837 -1.56) (xy -0.797 -1.576) (xy -0.761 -1.6) (xy -0.73 -1.63) (xy -0.706 -1.667) (xy -0.69 -1.709)
				(xy -0.687 -1.721) (xy -0.685 -1.734) (xy -0.684 -1.757) (xy -0.683 -1.79) (xy -0.682 -1.833) (xy -0.681 -1.884)
				(xy -0.681 -1.945) (xy -0.681 -1.971) (xy -0.681 -2.194) (xy -0.808 -2.194) (xy -0.809 -1.984) (xy -0.811 -1.774)
				(xy -0.826 -1.744) (xy -0.845 -1.716) (xy -0.868 -1.697) (xy -0.897 -1.686) (xy -0.925 -1.682) (xy -0.947 -1.682)
				(xy -0.967 -1.684) (xy -0.979 -1.686) (xy -1.001 -1.698) (xy -1.023 -1.716) (xy -1.041 -1.738) (xy -1.049 -1.752)
				(xy -1.052 -1.758) (xy -1.054 -1.765) (xy -1.056 -1.773) (xy -1.057 -1.783) (xy -1.058 -1.797) (xy -1.059 -1.815)
				(xy -1.06 -1.839) (xy -1.06 -1.869) (xy -1.061 -1.907) (xy -1.061 -1.953) (xy -1.061 -1.985) (xy -1.063 -2.194)
				(xy -1.189 -2.194) (xy -1.189 -1.559) (xy -1.062 -1.559) (xy -1.062 -1.625) (xy -1.033 -1.602) (xy -1.001 -1.579)
				(xy -0.969 -1.564) (xy -0.934 -1.555) (xy -0.927 -1.554) (xy -0.881 -1.553) (xy -0.837 -1.56)
			)
			(stroke
				(width 0.01)
				(type solid)
			)
			(fill yes)
			(layer "B.Cu")
		)
		(fp_poly
			(pts
				(xy 1.042 -1.769) (xy 1.043 -1.979) (xy 1.059 -2.009) (xy 1.077 -2.036) (xy 1.1 -2.056) (xy 1.129 -2.067)
				(xy 1.159 -2.071) (xy 1.193 -2.07) (xy 1.221 -2.063) (xy 1.245 -2.047) (xy 1.258 -2.034) (xy 1.266 -2.025)
				(xy 1.273 -2.016) (xy 1.278 -2.008) (xy 1.282 -1.997) (xy 1.286 -1.985) (xy 1.288 -1.969) (xy 1.29 -1.948)
				(xy 1.291 -1.922) (xy 1.292 -1.89) (xy 1.293 -1.85) (xy 1.293 -1.801) (xy 1.294 -1.766) (xy 1.295 -1.559)
				(xy 1.422 -1.559) (xy 1.422 -2.194) (xy 1.295 -2.194) (xy 1.295 -2.161) (xy 1.295 -2.144) (xy 1.293 -2.132)
				(xy 1.292 -2.128) (xy 1.287 -2.131) (xy 1.278 -2.14) (xy 1.271 -2.147) (xy 1.256 -2.159) (xy 1.236 -2.171)
				(xy 1.219 -2.181) (xy 1.202 -2.188) (xy 1.186 -2.193) (xy 1.17 -2.196) (xy 1.148 -2.197) (xy 1.135 -2.198)
				(xy 1.107 -2.198) (xy 1.087 -2.197) (xy 1.07 -2.194) (xy 1.059 -2.19) (xy 1.036 -2.181) (xy 1.019 -2.172)
				(xy 1.003 -2.161) (xy 0.985 -2.146) (xy 0.981 -2.141) (xy 0.952 -2.107) (xy 0.931 -2.068) (xy 0.92 -2.033)
				(xy 0.918 -2.019) (xy 0.917 -1.996) (xy 0.916 -1.963) (xy 0.915 -1.92) (xy 0.914 -1.869) (xy 0.914 -1.808)
				(xy 0.914 -1.782) (xy 0.914 -1.559) (xy 1.04 -1.559) (xy 1.042 -1.769)
			)
			(stroke
				(width 0.01)
				(type solid)
			)
			(fill yes)
			(layer "B.Cu")
		)
		(fp_poly
			(pts
				(xy 1.753 -2.563) (xy 1.768 -2.568) (xy 1.787 -2.577) (xy 1.804 -2.586) (xy 1.818 -2.595) (xy 1.826 -2.602)
				(xy 1.827 -2.606) (xy 1.824 -2.611) (xy 1.815 -2.621) (xy 1.803 -2.636) (xy 1.789 -2.654) (xy 1.775 -2.671)
				(xy 1.761 -2.688) (xy 1.749 -2.701) (xy 1.742 -2.71) (xy 1.739 -2.712) (xy 1.735 -2.71) (xy 1.724 -2.704)
				(xy 1.713 -2.698) (xy 1.697 -2.69) (xy 1.682 -2.686) (xy 1.664 -2.685) (xy 1.653 -2.685) (xy 1.618 -2.688)
				(xy 1.59 -2.699) (xy 1.566 -2.718) (xy 1.561 -2.723) (xy 1.554 -2.732) (xy 1.548 -2.74) (xy 1.544 -2.748)
				(xy 1.54 -2.758) (xy 1.537 -2.769) (xy 1.534 -2.785) (xy 1.533 -2.804) (xy 1.532 -2.829) (xy 1.531 -2.861)
				(xy 1.53 -2.899) (xy 1.53 -2.947) (xy 1.53 -2.988) (xy 1.528 -3.2) (xy 1.468 -3.2) (xy 1.444 -3.2)
				(xy 1.425 -3.199) (xy 1.411 -3.198) (xy 1.405 -3.197) (xy 1.404 -3.191) (xy 1.404 -3.176) (xy 1.403 -3.153)
				(xy 1.403 -3.122) (xy 1.402 -3.085) (xy 1.402 -3.042) (xy 1.402 -2.993) (xy 1.402 -2.941) (xy 1.402 -2.886)
				(xy 1.402 -2.565) (xy 1.529 -2.565) (xy 1.529 -2.595) (xy 1.529 -2.611) (xy 1.53 -2.623) (xy 1.532 -2.626)
				(xy 1.537 -2.623) (xy 1.547 -2.615) (xy 1.554 -2.608) (xy 1.588 -2.584) (xy 1.627 -2.567) (xy 1.669 -2.558)
				(xy 1.712 -2.556) (xy 1.753 -2.563)
			)
			(stroke
				(width 0.01)
				(type solid)
			)
			(fill yes)
			(layer "B.Cu")
		)
		(fp_poly
			(pts
				(xy 2.316 -1.557) (xy 2.365 -1.57) (xy 2.41 -1.593) (xy 2.453 -1.625) (xy 2.46 -1.631) (xy 2.491 -1.661)
				(xy 2.466 -1.684) (xy 2.448 -1.699) (xy 2.43 -1.715) (xy 2.419 -1.725) (xy 2.397 -1.743) (xy 2.376 -1.724)
				(xy 2.345 -1.701) (xy 2.312 -1.687) (xy 2.274 -1.681) (xy 2.265 -1.681) (xy 2.226 -1.684) (xy 2.195 -1.693)
				(xy 2.167 -1.708) (xy 2.159 -1.715) (xy 2.136 -1.741) (xy 2.118 -1.776) (xy 2.107 -1.817) (xy 2.103 -1.866)
				(xy 2.103 -1.876) (xy 2.106 -1.926) (xy 2.116 -1.97) (xy 2.132 -2.006) (xy 2.155 -2.034) (xy 2.184 -2.055)
				(xy 2.219 -2.067) (xy 2.259 -2.072) (xy 2.274 -2.071) (xy 2.309 -2.066) (xy 2.339 -2.056) (xy 2.366 -2.038)
				(xy 2.377 -2.028) (xy 2.386 -2.02) (xy 2.393 -2.016) (xy 2.4 -2.015) (xy 2.409 -2.018) (xy 2.42 -2.027)
				(xy 2.436 -2.041) (xy 2.456 -2.059) (xy 2.491 -2.092) (xy 2.476 -2.108) (xy 2.449 -2.132) (xy 2.416 -2.155)
				(xy 2.38 -2.174) (xy 2.35 -2.186) (xy 2.327 -2.193) (xy 2.306 -2.197) (xy 2.283 -2.199) (xy 2.259 -2.199)
				(xy 2.233 -2.198) (xy 2.209 -2.196) (xy 2.189 -2.193) (xy 2.182 -2.191) (xy 2.133 -2.173) (xy 2.089 -2.146)
				(xy 2.053 -2.112) (xy 2.023 -2.071) (xy 2.012 -2.051) (xy 2 -2.023) (xy 1.991 -1.999) (xy 1.984 -1.975)
				(xy 1.981 -1.948) (xy 1.979 -1.917) (xy 1.978 -1.879) (xy 1.978 -1.877) (xy 1.979 -1.838) (xy 1.98 -1.806)
				(xy 1.984 -1.78) (xy 1.99 -1.756) (xy 1.999 -1.731) (xy 2.011 -1.704) (xy 2.012 -1.701) (xy 2.039 -1.657)
				(xy 2.072 -1.62) (xy 2.111 -1.591) (xy 2.156 -1.57) (xy 2.207 -1.557) (xy 2.263 -1.552) (xy 2.316 -1.557)
			)
			(stroke
				(width 0.01)
				(type solid)
			)
			(fill yes)
			(layer "B.Cu")
		)
		(fp_poly
			(pts
				(xy -1.494 -1.56) (xy -1.447 -1.576) (xy -1.405 -1.6) (xy -1.368 -1.633) (xy -1.341 -1.668) (xy -1.326 -1.692)
				(xy -1.316 -1.716) (xy -1.308 -1.743) (xy -1.302 -1.774) (xy -1.299 -1.811) (xy -1.297 -1.845) (xy -1.294 -1.925)
				(xy -1.692 -1.925) (xy -1.692 -1.942) (xy -1.687 -1.977) (xy -1.673 -2.011) (xy -1.65 -2.039) (xy -1.626 -2.059)
				(xy -1.601 -2.071) (xy -1.572 -2.078) (xy -1.537 -2.079) (xy -1.497 -2.074) (xy -1.458 -2.06) (xy -1.422 -2.036)
				(xy -1.421 -2.036) (xy -1.402 -2.021) (xy -1.359 -2.057) (xy -1.342 -2.072) (xy -1.327 -2.085) (xy -1.317 -2.094)
				(xy -1.314 -2.098) (xy -1.316 -2.103) (xy -1.324 -2.113) (xy -1.338 -2.126) (xy -1.354 -2.139) (xy -1.372 -2.152)
				(xy -1.389 -2.163) (xy -1.399 -2.168) (xy -1.421 -2.178) (xy -1.445 -2.187) (xy -1.461 -2.191) (xy -1.488 -2.196)
				(xy -1.522 -2.199) (xy -1.557 -2.199) (xy -1.591 -2.196) (xy -1.62 -2.192) (xy -1.629 -2.19) (xy -1.677 -2.171)
				(xy -1.718 -2.146) (xy -1.752 -2.114) (xy -1.779 -2.074) (xy -1.8 -2.026) (xy -1.802 -2.02) (xy -1.81 -1.989)
				(xy -1.815 -1.951) (xy -1.818 -1.908) (xy -1.819 -1.865) (xy -1.818 -1.823) (xy -1.816 -1.804) (xy -1.692 -1.804)
				(xy -1.692 -1.818) (xy -1.428 -1.818) (xy -1.428 -1.801) (xy -1.432 -1.775) (xy -1.442 -1.748) (xy -1.457 -1.722)
				(xy -1.469 -1.707) (xy -1.495 -1.688) (xy -1.526 -1.676) (xy -1.56 -1.672) (xy -1.593 -1.676) (xy -1.619 -1.685)
				(xy -1.646 -1.704) (xy -1.668 -1.73) (xy -1.683 -1.76) (xy -1.691 -1.792) (xy -1.692 -1.804) (xy -1.816 -1.804)
				(xy -1.814 -1.786) (xy -1.812 -1.777) (xy -1.797 -1.724) (xy -1.775 -1.676) (xy -1.747 -1.636) (xy -1.713 -1.603)
				(xy -1.673 -1.578) (xy -1.629 -1.561) (xy -1.597 -1.554) (xy -1.544 -1.552) (xy -1.494 -1.56)
			)
			(stroke
				(width 0.01)
				(type solid)
			)
			(fill yes)
			(layer "B.Cu")
		)
		(fp_poly
			(pts
				(xy 2.835 -1.557) (xy 2.883 -1.57) (xy 2.926 -1.592) (xy 2.964 -1.621) (xy 2.996 -1.657) (xy 3.021 -1.699)
				(xy 3.038 -1.747) (xy 3.04 -1.757) (xy 3.043 -1.776) (xy 3.045 -1.802) (xy 3.047 -1.832) (xy 3.047 -1.858)
				(xy 3.047 -1.925) (xy 2.65 -1.925) (xy 2.653 -1.951) (xy 2.663 -1.991) (xy 2.68 -2.024) (xy 2.703 -2.049)
				(xy 2.733 -2.067) (xy 2.77 -2.077) (xy 2.801 -2.079) (xy 2.845 -2.075) (xy 2.883 -2.063) (xy 2.916 -2.042)
				(xy 2.92 -2.039) (xy 2.929 -2.031) (xy 2.935 -2.026) (xy 2.941 -2.025) (xy 2.949 -2.027) (xy 2.959 -2.034)
				(xy 2.974 -2.047) (xy 2.994 -2.064) (xy 3.01 -2.078) (xy 3.023 -2.088) (xy 3.03 -2.095) (xy 3.032 -2.096)
				(xy 3.03 -2.1) (xy 3.022 -2.11) (xy 3.01 -2.122) (xy 3.009 -2.123) (xy 2.98 -2.147) (xy 2.945 -2.169)
				(xy 2.906 -2.185) (xy 2.887 -2.191) (xy 2.861 -2.196) (xy 2.828 -2.198) (xy 2.793 -2.198) (xy 2.759 -2.197)
				(xy 2.729 -2.193) (xy 2.721 -2.191) (xy 2.675 -2.175) (xy 2.634 -2.15) (xy 2.599 -2.118) (xy 2.569 -2.077)
				(xy 2.547 -2.029) (xy 2.536 -1.996) (xy 2.532 -1.973) (xy 2.529 -1.942) (xy 2.527 -1.906) (xy 2.527 -1.869)
				(xy 2.528 -1.832) (xy 2.529 -1.818) (xy 2.65 -1.818) (xy 2.922 -1.818) (xy 2.918 -1.799) (xy 2.908 -1.758)
				(xy 2.891 -1.725) (xy 2.869 -1.7) (xy 2.84 -1.683) (xy 2.826 -1.678) (xy 2.788 -1.672) (xy 2.753 -1.675)
				(xy 2.722 -1.687) (xy 2.695 -1.706) (xy 2.674 -1.734) (xy 2.659 -1.768) (xy 2.654 -1.794) (xy 2.65 -1.818)
				(xy 2.529 -1.818) (xy 2.53 -1.798) (xy 2.534 -1.769) (xy 2.536 -1.76) (xy 2.554 -1.707) (xy 2.578 -1.662)
				(xy 2.609 -1.624) (xy 2.645 -1.593) (xy 2.687 -1.571) (xy 2.734 -1.557) (xy 2.783 -1.553) (xy 2.835 -1.557)
			)
			(stroke
				(width 0.01)
				(type solid)
			)
			(fill yes)
			(layer "B.Cu")
		)
		(fp_poly
			(pts
				(xy 2.148 -2.561) (xy 2.193 -2.574) (xy 2.235 -2.595) (xy 2.273 -2.623) (xy 2.304 -2.657) (xy 2.326 -2.691)
				(xy 2.338 -2.718) (xy 2.346 -2.745) (xy 2.352 -2.774) (xy 2.355 -2.808) (xy 2.357 -2.85) (xy 2.357 -2.858)
				(xy 2.357 -2.931) (xy 1.96 -2.931) (xy 1.963 -2.955) (xy 1.973 -2.993) (xy 1.991 -3.026) (xy 2.015 -3.053)
				(xy 2.039 -3.069) (xy 2.057 -3.076) (xy 2.08 -3.08) (xy 2.103 -3.082) (xy 2.144 -3.081) (xy 2.18 -3.071)
				(xy 2.214 -3.054) (xy 2.227 -3.045) (xy 2.24 -3.035) (xy 2.25 -3.029) (xy 2.253 -3.027) (xy 2.258 -3.03)
				(xy 2.269 -3.039) (xy 2.284 -3.05) (xy 2.3 -3.064) (xy 2.315 -3.078) (xy 2.329 -3.09) (xy 2.338 -3.099)
				(xy 2.341 -3.103) (xy 2.337 -3.11) (xy 2.327 -3.121) (xy 2.312 -3.134) (xy 2.294 -3.148) (xy 2.276 -3.161)
				(xy 2.259 -3.171) (xy 2.252 -3.175) (xy 2.204 -3.192) (xy 2.152 -3.202) (xy 2.098 -3.204) (xy 2.046 -3.198)
				(xy 2.032 -3.195) (xy 1.984 -3.178) (xy 1.943 -3.154) (xy 1.909 -3.123) (xy 1.881 -3.084) (xy 1.859 -3.037)
				(xy 1.847 -3.003) (xy 1.841 -2.972) (xy 1.838 -2.934) (xy 1.836 -2.893) (xy 1.837 -2.851) (xy 1.839 -2.824)
				(xy 1.96 -2.824) (xy 2.23 -2.824) (xy 2.23 -2.813) (xy 2.225 -2.783) (xy 2.214 -2.753) (xy 2.196 -2.725)
				(xy 2.175 -2.702) (xy 2.151 -2.686) (xy 2.128 -2.68) (xy 2.101 -2.677) (xy 2.072 -2.678) (xy 2.051 -2.683)
				(xy 2.023 -2.696) (xy 2 -2.717) (xy 1.981 -2.746) (xy 1.968 -2.779) (xy 1.963 -2.8) (xy 1.96 -2.824)
				(xy 1.839 -2.824) (xy 1.839 -2.811) (xy 1.844 -2.776) (xy 1.848 -2.76) (xy 1.866 -2.708) (xy 1.889 -2.663)
				(xy 1.919 -2.627) (xy 1.954 -2.598) (xy 1.996 -2.575) (xy 2.007 -2.571) (xy 2.054 -2.559) (xy 2.101 -2.556)
				(xy 2.148 -2.561)
			)
			(stroke
				(width 0.01)
				(type solid)
			)
			(fill yes)
			(layer "B.Cu")
		)
		(fp_poly
			(pts
				(xy -2.733 -1.557) (xy -2.685 -1.57) (xy -2.642 -1.592) (xy -2.604 -1.622) (xy -2.581 -1.649) (xy -2.562 -1.676)
				(xy -2.548 -1.706) (xy -2.537 -1.739) (xy -2.53 -1.777) (xy -2.527 -1.821) (xy -2.526 -1.873) (xy -2.527 -1.907)
				(xy -2.529 -1.956) (xy -2.534 -1.997) (xy -2.542 -2.031) (xy -2.553 -2.06) (xy -2.567 -2.086) (xy -2.587 -2.111)
				(xy -2.603 -2.129) (xy -2.637 -2.158) (xy -2.673 -2.178) (xy -2.714 -2.192) (xy -2.76 -2.198) (xy -2.789 -2.199)
				(xy -2.813 -2.198) (xy -2.835 -2.196) (xy -2.852 -2.194) (xy -2.857 -2.194) (xy -2.898 -2.179) (xy -2.937 -2.155)
				(xy -2.97 -2.126) (xy -2.993 -2.101) (xy -3.011 -2.077) (xy -3.024 -2.051) (xy -3.034 -2.022) (xy -3.041 -1.988)
				(xy -3.045 -1.947) (xy -3.047 -1.91) (xy -3.047 -1.882) (xy -2.919 -1.882) (xy -2.919 -1.968) (xy -2.903 -2.001)
				(xy -2.885 -2.031) (xy -2.863 -2.051) (xy -2.837 -2.064) (xy -2.804 -2.07) (xy -2.779 -2.07) (xy -2.755 -2.069)
				(xy -2.737 -2.065) (xy -2.722 -2.058) (xy -2.717 -2.055) (xy -2.697 -2.041) (xy -2.681 -2.025) (xy -2.67 -2.004)
				(xy -2.662 -1.978) (xy -2.657 -1.945) (xy -2.654 -1.903) (xy -2.654 -1.899) (xy -2.653 -1.848) (xy -2.656 -1.806)
				(xy -2.662 -1.772) (xy -2.673 -1.744) (xy -2.687 -1.722) (xy -2.707 -1.705) (xy -2.723 -1.695) (xy -2.755 -1.684)
				(xy -2.788 -1.68) (xy -2.821 -1.684) (xy -2.851 -1.695) (xy -2.877 -1.713) (xy -2.892 -1.729) (xy -2.901 -1.745)
				(xy -2.908 -1.76) (xy -2.913 -1.778) (xy -2.916 -1.8) (xy -2.918 -1.828) (xy -2.919 -1.864) (xy -2.919 -1.882)
				(xy -3.047 -1.882) (xy -3.048 -1.844) (xy -3.043 -1.786) (xy -3.034 -1.736) (xy -3.021 -1.695) (xy -3.004 -1.664)
				(xy -2.972 -1.624) (xy -2.935 -1.594) (xy -2.893 -1.571) (xy -2.846 -1.558) (xy -2.794 -1.553) (xy -2.787 -1.553)
				(xy -2.733 -1.557)
			)
			(stroke
				(width 0.01)
				(type solid)
			)
			(fill yes)
			(layer "B.Cu")
		)
		(fp_poly
			(pts
				(xy -0.229 -3.2) (xy -0.354 -3.197) (xy -0.355 -3.165) (xy -0.357 -3.133) (xy -0.374 -3.148) (xy -0.411 -3.175)
				(xy -0.453 -3.193) (xy -0.497 -3.203) (xy -0.542 -3.204) (xy -0.585 -3.195) (xy -0.586 -3.195) (xy -0.621 -3.181)
				(xy -0.651 -3.16) (xy -0.673 -3.141) (xy -0.689 -3.123) (xy -0.702 -3.106) (xy -0.712 -3.086) (xy -0.72 -3.064)
				(xy -0.726 -3.038) (xy -0.73 -3.007) (xy -0.732 -2.968) (xy -0.733 -2.922) (xy -0.733 -2.88) (xy -0.602 -2.88)
				(xy -0.602 -2.915) (xy -0.602 -2.942) (xy -0.601 -2.962) (xy -0.6 -2.977) (xy -0.598 -2.988) (xy -0.596 -2.998)
				(xy -0.592 -3.007) (xy -0.591 -3.01) (xy -0.574 -3.039) (xy -0.552 -3.059) (xy -0.525 -3.071) (xy -0.492 -3.076)
				(xy -0.472 -3.076) (xy -0.442 -3.072) (xy -0.418 -3.063) (xy -0.398 -3.048) (xy -0.382 -3.029) (xy -0.371 -3.004)
				(xy -0.363 -2.972) (xy -0.358 -2.933) (xy -0.356 -2.885) (xy -0.356 -2.88) (xy -0.358 -2.828) (xy -0.363 -2.785)
				(xy -0.373 -2.75) (xy -0.387 -2.724) (xy -0.406 -2.704) (xy -0.43 -2.692) (xy -0.46 -2.686) (xy -0.483 -2.685)
				(xy -0.517 -2.687) (xy -0.544 -2.696) (xy -0.565 -2.711) (xy -0.583 -2.734) (xy -0.591 -2.751) (xy -0.595 -2.76)
				(xy -0.598 -2.769) (xy -0.6 -2.779) (xy -0.601 -2.793) (xy -0.602 -2.811) (xy -0.602 -2.836) (xy -0.602 -2.869)
				(xy -0.602 -2.88) (xy -0.733 -2.88) (xy -0.733 -2.827) (xy -0.732 -2.783) (xy -0.729 -2.746) (xy -0.725 -2.716)
				(xy -0.719 -2.691) (xy -0.71 -2.67) (xy -0.699 -2.651) (xy -0.685 -2.633) (xy -0.668 -2.616) (xy -0.668 -2.615)
				(xy -0.632 -2.587) (xy -0.592 -2.567) (xy -0.55 -2.557) (xy -0.506 -2.556) (xy -0.463 -2.564) (xy -0.421 -2.582)
				(xy -0.411 -2.587) (xy -0.394 -2.598) (xy -0.377 -2.61) (xy -0.373 -2.614) (xy -0.356 -2.627) (xy -0.356 -2.306)
				(xy -0.229 -2.306) (xy -0.229 -3.2)
			)
			(stroke
				(width 0.01)
				(type solid)
			)
			(fill yes)
			(layer "B.Cu")
		)
		(fp_poly
			(pts
				(xy 0.605 -1.558) (xy 0.651 -1.574) (xy 0.694 -1.598) (xy 0.728 -1.627) (xy 0.75 -1.652) (xy 0.768 -1.678)
				(xy 0.781 -1.707) (xy 0.791 -1.739) (xy 0.797 -1.777) (xy 0.801 -1.822) (xy 0.802 -1.876) (xy 0.802 -1.877)
				(xy 0.801 -1.929) (xy 0.798 -1.973) (xy 0.792 -2.009) (xy 0.784 -2.04) (xy 0.774 -2.062) (xy 0.748 -2.103)
				(xy 0.715 -2.139) (xy 0.675 -2.167) (xy 0.632 -2.187) (xy 0.626 -2.189) (xy 0.599 -2.195) (xy 0.567 -2.198)
				(xy 0.532 -2.199) (xy 0.499 -2.197) (xy 0.471 -2.193) (xy 0.466 -2.192) (xy 0.428 -2.177) (xy 0.391 -2.155)
				(xy 0.359 -2.129) (xy 0.354 -2.123) (xy 0.332 -2.098) (xy 0.316 -2.073) (xy 0.303 -2.047) (xy 0.294 -2.017)
				(xy 0.287 -1.983) (xy 0.284 -1.943) (xy 0.282 -1.894) (xy 0.282 -1.877) (xy 0.409 -1.877) (xy 0.41 -1.918)
				(xy 0.412 -1.95) (xy 0.416 -1.976) (xy 0.423 -1.997) (xy 0.432 -2.015) (xy 0.445 -2.03) (xy 0.451 -2.037)
				(xy 0.471 -2.054) (xy 0.491 -2.064) (xy 0.514 -2.07) (xy 0.543 -2.072) (xy 0.569 -2.07) (xy 0.59 -2.065)
				(xy 0.601 -2.06) (xy 0.625 -2.047) (xy 0.642 -2.031) (xy 0.656 -2.009) (xy 0.661 -1.998) (xy 0.665 -1.989)
				(xy 0.668 -1.98) (xy 0.67 -1.969) (xy 0.671 -1.954) (xy 0.672 -1.935) (xy 0.673 -1.909) (xy 0.673 -1.877)
				(xy 0.673 -1.842) (xy 0.672 -1.817) (xy 0.671 -1.798) (xy 0.67 -1.784) (xy 0.668 -1.773) (xy 0.665 -1.764)
				(xy 0.661 -1.755) (xy 0.647 -1.73) (xy 0.632 -1.712) (xy 0.612 -1.698) (xy 0.601 -1.693) (xy 0.569 -1.683)
				(xy 0.535 -1.681) (xy 0.501 -1.686) (xy 0.471 -1.7) (xy 0.447 -1.719) (xy 0.434 -1.736) (xy 0.424 -1.753)
				(xy 0.417 -1.774) (xy 0.412 -1.8) (xy 0.41 -1.833) (xy 0.409 -1.873) (xy 0.409 -1.877) (xy 0.282 -1.877)
				(xy 0.283 -1.824) (xy 0.286 -1.78) (xy 0.292 -1.742) (xy 0.301 -1.711) (xy 0.313 -1.683) (xy 0.33 -1.657)
				(xy 0.35 -1.633) (xy 0.351 -1.632) (xy 0.385 -1.601) (xy 0.42 -1.578) (xy 0.46 -1.563) (xy 0.505 -1.554)
				(xy 0.555 -1.551) (xy 0.605 -1.558)
			)
			(stroke
				(width 0.01)
				(type solid)
			)
			(fill yes)
			(layer "B.Cu")
		)
		(fp_poly
			(pts
				(xy 0.004 -1.556) (xy 0.054 -1.566) (xy 0.102 -1.582) (xy 0.146 -1.605) (xy 0.154 -1.61) (xy 0.193 -1.636)
				(xy 0.178 -1.655) (xy 0.166 -1.668) (xy 0.152 -1.686) (xy 0.138 -1.7) (xy 0.114 -1.727) (xy 0.07 -1.705)
				(xy 0.032 -1.688) (xy -0.007 -1.677) (xy -0.044 -1.672) (xy -0.079 -1.672) (xy -0.11 -1.678) (xy -0.136 -1.69)
				(xy -0.154 -1.707) (xy -0.162 -1.724) (xy -0.164 -1.745) (xy -0.164 -1.761) (xy -0.159 -1.772) (xy -0.15 -1.782)
				(xy -0.149 -1.783) (xy -0.139 -1.791) (xy -0.128 -1.797) (xy -0.114 -1.802) (xy -0.095 -1.805) (xy -0.07 -1.808)
				(xy -0.037 -1.811) (xy -0.02 -1.813) (xy 0.027 -1.817) (xy 0.065 -1.823) (xy 0.096 -1.832) (xy 0.122 -1.842)
				(xy 0.14 -1.854) (xy 0.166 -1.879) (xy 0.186 -1.91) (xy 0.2 -1.947) (xy 0.206 -1.987) (xy 0.206 -2.018)
				(xy 0.198 -2.06) (xy 0.181 -2.097) (xy 0.155 -2.129) (xy 0.122 -2.156) (xy 0.08 -2.177) (xy 0.042 -2.189)
				(xy 0.005 -2.196) (xy -0.038 -2.199) (xy -0.083 -2.198) (xy -0.125 -2.194) (xy -0.153 -2.189) (xy -0.177 -2.181)
				(xy -0.204 -2.171) (xy -0.229 -2.16) (xy -0.232 -2.159) (xy -0.251 -2.148) (xy -0.272 -2.136) (xy -0.292 -2.122)
				(xy -0.309 -2.109) (xy -0.323 -2.098) (xy -0.33 -2.09) (xy -0.331 -2.088) (xy -0.327 -2.084) (xy -0.318 -2.073)
				(xy -0.304 -2.059) (xy -0.288 -2.043) (xy -0.246 -2) (xy -0.221 -2.021) (xy -0.184 -2.047) (xy -0.145 -2.065)
				(xy -0.102 -2.075) (xy -0.053 -2.079) (xy -0.049 -2.079) (xy -0.023 -2.079) (xy -0.004 -2.078) (xy 0.011 -2.074)
				(xy 0.025 -2.069) (xy 0.029 -2.068) (xy 0.054 -2.052) (xy 0.071 -2.033) (xy 0.079 -2.01) (xy 0.078 -1.986)
				(xy 0.074 -1.975) (xy 0.068 -1.964) (xy 0.06 -1.956) (xy 0.048 -1.949) (xy 0.031 -1.944) (xy 0.007 -1.939)
				(xy -0.024 -1.935) (xy -0.052 -1.932) (xy -0.089 -1.929) (xy -0.119 -1.925) (xy -0.142 -1.921) (xy -0.16 -1.917)
				(xy -0.176 -1.912) (xy -0.192 -1.906) (xy -0.201 -1.901) (xy -0.235 -1.879) (xy -0.262 -1.85) (xy -0.28 -1.816)
				(xy -0.29 -1.776) (xy -0.292 -1.75) (xy -0.291 -1.727) (xy -0.289 -1.705) (xy -0.286 -1.689) (xy -0.286 -1.688)
				(xy -0.273 -1.659) (xy -0.253 -1.63) (xy -0.229 -1.604) (xy -0.221 -1.599) (xy -0.185 -1.577) (xy -0.143 -1.562)
				(xy -0.096 -1.554) (xy -0.047 -1.552) (xy 0.004 -1.556)
			)
			(stroke
				(width 0.01)
				(type solid)
			)
			(fill yes)
			(layer "B.Cu")
		)
		(fp_poly
			(pts
				(xy 1.038 -2.556) (xy 1.091 -2.563) (xy 1.137 -2.576) (xy 1.177 -2.595) (xy 1.209 -2.62) (xy 1.234 -2.65)
				(xy 1.242 -2.665) (xy 1.247 -2.677) (xy 1.251 -2.691) (xy 1.255 -2.708) (xy 1.258 -2.727) (xy 1.26 -2.751)
				(xy 1.262 -2.78) (xy 1.263 -2.815) (xy 1.263 -2.858) (xy 1.264 -2.908) (xy 1.263 -2.967) (xy 1.263 -2.989)
				(xy 1.262 -3.197) (xy 1.135 -3.197) (xy 1.133 -3.171) (xy 1.132 -3.144) (xy 1.119 -3.159) (xy 1.096 -3.179)
				(xy 1.065 -3.193) (xy 1.026 -3.202) (xy 0.98 -3.204) (xy 0.976 -3.204) (xy 0.955 -3.204) (xy 0.937 -3.203)
				(xy 0.925 -3.202) (xy 0.924 -3.201) (xy 0.879 -3.189) (xy 0.839 -3.17) (xy 0.806 -3.144) (xy 0.781 -3.113)
				(xy 0.763 -3.077) (xy 0.753 -3.037) (xy 0.753 -3.005) (xy 0.873 -3.005) (xy 0.874 -3.023) (xy 0.878 -3.035)
				(xy 0.887 -3.047) (xy 0.89 -3.05) (xy 0.903 -3.063) (xy 0.917 -3.072) (xy 0.935 -3.078) (xy 0.957 -3.081)
				(xy 0.986 -3.082) (xy 1.013 -3.082) (xy 1.043 -3.081) (xy 1.065 -3.079) (xy 1.08 -3.077) (xy 1.091 -3.073)
				(xy 1.096 -3.071) (xy 1.112 -3.058) (xy 1.123 -3.039) (xy 1.13 -3.012) (xy 1.132 -2.977) (xy 1.132 -2.975)
				(xy 1.132 -2.931) (xy 1.035 -2.931) (xy 0.999 -2.931) (xy 0.973 -2.931) (xy 0.953 -2.932) (xy 0.939 -2.934)
				(xy 0.928 -2.936) (xy 0.919 -2.939) (xy 0.916 -2.94) (xy 0.893 -2.954) (xy 0.88 -2.971) (xy 0.874 -2.994)
				(xy 0.873 -3.005) (xy 0.753 -3.005) (xy 0.753 -2.994) (xy 0.761 -2.951) (xy 0.768 -2.931) (xy 0.776 -2.915)
				(xy 0.786 -2.901) (xy 0.802 -2.884) (xy 0.804 -2.882) (xy 0.82 -2.867) (xy 0.835 -2.854) (xy 0.85 -2.845)
				(xy 0.867 -2.838) (xy 0.887 -2.833) (xy 0.912 -2.829) (xy 0.943 -2.827) (xy 0.982 -2.826) (xy 1.015 -2.825)
				(xy 1.133 -2.823) (xy 1.132 -2.771) (xy 1.131 -2.746) (xy 1.129 -2.73) (xy 1.127 -2.719) (xy 1.123 -2.711)
				(xy 1.117 -2.705) (xy 1.098 -2.691) (xy 1.07 -2.682) (xy 1.032 -2.677) (xy 1.006 -2.677) (xy 0.972 -2.678)
				(xy 0.945 -2.682) (xy 0.924 -2.688) (xy 0.907 -2.699) (xy 0.9 -2.706) (xy 0.882 -2.723) (xy 0.834 -2.686)
				(xy 0.816 -2.672) (xy 0.801 -2.66) (xy 0.79 -2.652) (xy 0.787 -2.648) (xy 0.791 -2.639) (xy 0.801 -2.626)
				(xy 0.816 -2.612) (xy 0.832 -2.6) (xy 0.864 -2.581) (xy 0.902 -2.568) (xy 0.946 -2.559) (xy 0.98 -2.556)
				(xy 1.038 -2.556)
			)
			(stroke
				(width 0.01)
				(type solid)
			)
			(fill yes)
			(layer "B.Cu")
		)
		(fp_poly
			(pts
				(xy -1.521 -2.559) (xy -1.485 -2.562) (xy -1.454 -2.568) (xy -1.427 -2.577) (xy -1.401 -2.589) (xy -1.371 -2.61)
				(xy -1.345 -2.639) (xy -1.325 -2.67) (xy -1.321 -2.679) (xy -1.309 -2.71) (xy -1.309 -3.197) (xy -1.433 -3.2)
				(xy -1.433 -3.172) (xy -1.434 -3.157) (xy -1.435 -3.147) (xy -1.436 -3.144) (xy -1.44 -3.147) (xy -1.449 -3.156)
				(xy -1.453 -3.161) (xy -1.472 -3.178) (xy -1.496 -3.19) (xy -1.526 -3.198) (xy -1.563 -3.202) (xy -1.578 -3.203)
				(xy -1.603 -3.203) (xy -1.627 -3.203) (xy -1.647 -3.201) (xy -1.656 -3.2) (xy -1.686 -3.191) (xy -1.717 -3.176)
				(xy -1.746 -3.159) (xy -1.765 -3.143) (xy -1.79 -3.111) (xy -1.807 -3.075) (xy -1.816 -3.037) (xy -1.817 -2.998)
				(xy -1.817 -2.997) (xy -1.697 -2.997) (xy -1.696 -3.02) (xy -1.687 -3.042) (xy -1.67 -3.06) (xy -1.668 -3.062)
				(xy -1.654 -3.07) (xy -1.64 -3.076) (xy -1.624 -3.08) (xy -1.602 -3.081) (xy -1.574 -3.082) (xy -1.558 -3.082)
				(xy -1.529 -3.081) (xy -1.508 -3.08) (xy -1.494 -3.078) (xy -1.483 -3.075) (xy -1.474 -3.07) (xy -1.458 -3.058)
				(xy -1.447 -3.041) (xy -1.44 -3.017) (xy -1.435 -2.985) (xy -1.435 -2.977) (xy -1.432 -2.931) (xy -1.533 -2.931)
				(xy -1.568 -2.931) (xy -1.595 -2.931) (xy -1.615 -2.932) (xy -1.63 -2.934) (xy -1.641 -2.936) (xy -1.65 -2.938)
				(xy -1.655 -2.941) (xy -1.676 -2.955) (xy -1.69 -2.974) (xy -1.697 -2.997) (xy -1.817 -2.997) (xy -1.811 -2.96)
				(xy -1.797 -2.924) (xy -1.775 -2.892) (xy -1.747 -2.864) (xy -1.715 -2.845) (xy -1.7 -2.838) (xy -1.685 -2.833)
				(xy -1.668 -2.83) (xy -1.648 -2.827) (xy -1.623 -2.825) (xy -1.591 -2.824) (xy -1.551 -2.824) (xy -1.54 -2.824)
				(xy -1.432 -2.824) (xy -1.434 -2.776) (xy -1.436 -2.747) (xy -1.441 -2.726) (xy -1.448 -2.711) (xy -1.46 -2.699)
				(xy -1.474 -2.689) (xy -1.483 -2.685) (xy -1.492 -2.682) (xy -1.505 -2.68) (xy -1.524 -2.68) (xy -1.55 -2.679)
				(xy -1.56 -2.679) (xy -1.594 -2.68) (xy -1.62 -2.682) (xy -1.639 -2.686) (xy -1.654 -2.692) (xy -1.666 -2.701)
				(xy -1.675 -2.711) (xy -1.686 -2.724) (xy -1.735 -2.686) (xy -1.754 -2.672) (xy -1.769 -2.659) (xy -1.78 -2.65)
				(xy -1.784 -2.646) (xy -1.78 -2.64) (xy -1.77 -2.629) (xy -1.756 -2.616) (xy -1.74 -2.604) (xy -1.724 -2.592)
				(xy -1.711 -2.584) (xy -1.71 -2.583) (xy -1.688 -2.574) (xy -1.668 -2.566) (xy -1.647 -2.562) (xy -1.623 -2.559)
				(xy -1.593 -2.558) (xy -1.565 -2.558) (xy -1.521 -2.559)
			)
			(stroke
				(width 0.01)
				(type solid)
			)
			(fill yes)
			(layer "B.Cu")
		)
		(fp_poly
			(pts
				(xy 0.035 -2.777) (xy 0.047 -2.822) (xy 0.059 -2.864) (xy 0.069 -2.903) (xy 0.078 -2.936) (xy 0.086 -2.963)
				(xy 0.092 -2.984) (xy 0.095 -2.996) (xy 0.096 -2.999) (xy 0.098 -2.999) (xy 0.103 -2.991) (xy 0.109 -2.975)
				(xy 0.118 -2.95) (xy 0.129 -2.917) (xy 0.143 -2.874) (xy 0.152 -2.849) (xy 0.165 -2.807) (xy 0.179 -2.766)
				(xy 0.192 -2.726) (xy 0.204 -2.689) (xy 0.214 -2.658) (xy 0.221 -2.634) (xy 0.224 -2.627) (xy 0.244 -2.565)
				(xy 0.338 -2.565) (xy 0.406 -2.774) (xy 0.42 -2.819) (xy 0.434 -2.861) (xy 0.446 -2.899) (xy 0.457 -2.932)
				(xy 0.466 -2.96) (xy 0.473 -2.981) (xy 0.477 -2.993) (xy 0.478 -2.997) (xy 0.48 -2.998) (xy 0.482 -2.996)
				(xy 0.485 -2.99) (xy 0.49 -2.978) (xy 0.495 -2.96) (xy 0.502 -2.936) (xy 0.511 -2.905) (xy 0.523 -2.865)
				(xy 0.536 -2.817) (xy 0.543 -2.789) (xy 0.556 -2.744) (xy 0.568 -2.701) (xy 0.578 -2.663) (xy 0.587 -2.629)
				(xy 0.595 -2.602) (xy 0.601 -2.582) (xy 0.605 -2.57) (xy 0.606 -2.567) (xy 0.611 -2.566) (xy 0.625 -2.566)
				(xy 0.645 -2.566) (xy 0.669 -2.566) (xy 0.673 -2.566) (xy 0.739 -2.567) (xy 0.656 -2.827) (xy 0.64 -2.878)
				(xy 0.624 -2.928) (xy 0.609 -2.976) (xy 0.595 -3.02) (xy 0.582 -3.06) (xy 0.571 -3.094) (xy 0.563 -3.121)
				(xy 0.557 -3.139) (xy 0.556 -3.143) (xy 0.538 -3.2) (xy 0.425 -3.197) (xy 0.358 -2.975) (xy 0.341 -2.917)
				(xy 0.327 -2.87) (xy 0.315 -2.831) (xy 0.305 -2.801) (xy 0.297 -2.78) (xy 0.292 -2.766) (xy 0.289 -2.761)
				(xy 0.288 -2.761) (xy 0.286 -2.768) (xy 0.281 -2.783) (xy 0.274 -2.806) (xy 0.265 -2.836) (xy 0.254 -2.871)
				(xy 0.242 -2.911) (xy 0.23 -2.953) (xy 0.223 -2.976) (xy 0.21 -3.02) (xy 0.197 -3.062) (xy 0.186 -3.099)
				(xy 0.177 -3.132) (xy 0.169 -3.158) (xy 0.163 -3.177) (xy 0.16 -3.189) (xy 0.159 -3.191) (xy 0.157 -3.195)
				(xy 0.151 -3.198) (xy 0.141 -3.199) (xy 0.124 -3.2) (xy 0.101 -3.2) (xy 0.073 -3.199) (xy 0.055 -3.198)
				(xy 0.045 -3.196) (xy 0.043 -3.194) (xy 0.041 -3.188) (xy 0.036 -3.173) (xy 0.029 -3.15) (xy 0.019 -3.121)
				(xy 0.008 -3.084) (xy -0.006 -3.043) (xy -0.02 -2.996) (xy -0.036 -2.946) (xy -0.053 -2.893) (xy -0.057 -2.883)
				(xy -0.074 -2.83) (xy -0.09 -2.779) (xy -0.105 -2.732) (xy -0.119 -2.689) (xy -0.131 -2.652) (xy -0.141 -2.621)
				(xy -0.148 -2.596) (xy -0.154 -2.58) (xy -0.156 -2.572) (xy -0.156 -2.569) (xy -0.151 -2.567) (xy -0.14 -2.566)
				(xy -0.123 -2.565) (xy -0.096 -2.565) (xy -0.091 -2.565) (xy -0.023 -2.565) (xy 0.035 -2.777)
			)
			(stroke
				(width 0.01)
				(type solid)
			)
			(fill yes)
			(layer "B.Cu")
		)
		(fp_poly
			(pts
				(xy -2.065 -1.559) (xy -2.024 -1.576) (xy -1.986 -1.601) (xy -1.973 -1.612) (xy -1.957 -1.63) (xy -1.943 -1.649)
				(xy -1.932 -1.668) (xy -1.924 -1.69) (xy -1.918 -1.716) (xy -1.914 -1.747) (xy -1.911 -1.785) (xy -1.91 -1.831)
				(xy -1.91 -1.877) (xy -1.91 -1.93) (xy -1.912 -1.974) (xy -1.914 -2.011) (xy -1.919 -2.041) (xy -1.925 -2.067)
				(xy -1.934 -2.088) (xy -1.945 -2.107) (xy -1.959 -2.125) (xy -1.972 -2.139) (xy -1.993 -2.157) (xy -2.018 -2.173)
				(xy -2.031 -2.18) (xy -2.047 -2.188) (xy -2.06 -2.192) (xy -2.074 -2.195) (xy -2.091 -2.196) (xy -2.114 -2.197)
				(xy -2.122 -2.197) (xy -2.147 -2.196) (xy -2.165 -2.195) (xy -2.179 -2.193) (xy -2.191 -2.189) (xy -2.205 -2.183)
				(xy -2.21 -2.18) (xy -2.231 -2.169) (xy -2.251 -2.156) (xy -2.265 -2.146) (xy -2.286 -2.127) (xy -2.286 -2.627)
				(xy -2.266 -2.608) (xy -2.248 -2.595) (xy -2.227 -2.582) (xy -2.217 -2.577) (xy -2.173 -2.562) (xy -2.129 -2.556)
				(xy -2.086 -2.559) (xy -2.045 -2.57) (xy -2.007 -2.589) (xy -1.974 -2.616) (xy -1.946 -2.648) (xy -1.926 -2.687)
				(xy -1.919 -2.707) (xy -1.917 -2.715) (xy -1.915 -2.724) (xy -1.914 -2.737) (xy -1.913 -2.753) (xy -1.912 -2.774)
				(xy -1.911 -2.8) (xy -1.911 -2.833) (xy -1.911 -2.874) (xy -1.911 -2.923) (xy -1.911 -2.967) (xy -1.911 -3.2)
				(xy -2.035 -3.197) (xy -2.038 -2.984) (xy -2.038 -2.932) (xy -2.039 -2.889) (xy -2.039 -2.854) (xy -2.04 -2.826)
				(xy -2.041 -2.805) (xy -2.042 -2.788) (xy -2.043 -2.776) (xy -2.045 -2.767) (xy -2.046 -2.76) (xy -2.049 -2.755)
				(xy -2.051 -2.75) (xy -2.072 -2.721) (xy -2.098 -2.701) (xy -2.128 -2.688) (xy -2.161 -2.683) (xy -2.195 -2.687)
				(xy -2.22 -2.697) (xy -2.24 -2.71) (xy -2.259 -2.729) (xy -2.274 -2.75) (xy -2.278 -2.757) (xy -2.28 -2.765)
				(xy -2.281 -2.781) (xy -2.283 -2.806) (xy -2.284 -2.839) (xy -2.285 -2.881) (xy -2.286 -2.933) (xy -2.286 -2.984)
				(xy -2.289 -3.197) (xy -2.413 -3.2) (xy -2.413 -1.877) (xy -2.286 -1.877) (xy -2.285 -1.926) (xy -2.281 -1.966)
				(xy -2.274 -1.998) (xy -2.262 -2.024) (xy -2.247 -2.043) (xy -2.228 -2.058) (xy -2.215 -2.064) (xy -2.194 -2.07)
				(xy -2.168 -2.072) (xy -2.141 -2.071) (xy -2.117 -2.066) (xy -2.106 -2.063) (xy -2.079 -2.044) (xy -2.058 -2.019)
				(xy -2.05 -2.001) (xy -2.045 -1.984) (xy -2.042 -1.959) (xy -2.04 -1.929) (xy -2.038 -1.895) (xy -2.038 -1.861)
				(xy -2.039 -1.829) (xy -2.041 -1.8) (xy -2.044 -1.777) (xy -2.045 -1.772) (xy -2.057 -1.738) (xy -2.073 -1.712)
				(xy -2.094 -1.695) (xy -2.122 -1.684) (xy -2.156 -1.681) (xy -2.159 -1.681) (xy -2.192 -1.683) (xy -2.22 -1.691)
				(xy -2.243 -1.705) (xy -2.26 -1.725) (xy -2.273 -1.753) (xy -2.281 -1.788) (xy -2.285 -1.832) (xy -2.286 -1.877)
				(xy -2.413 -1.877) (xy -2.413 -1.559) (xy -2.286 -1.559) (xy -2.286 -1.62) (xy -2.26 -1.6) (xy -2.225 -1.577)
				(xy -2.19 -1.563) (xy -2.154 -1.554) (xy -2.109 -1.552) (xy -2.065 -1.559)
			)
			(stroke
				(width 0.01)
				(type solid)
			)
			(fill yes)
			(layer "B.Cu")
		)
		(fp_poly
			(pts
				(xy 0.063 3.201) (xy 0.118 3.201) (xy 0.164 3.201) (xy 0.202 3.2) (xy 0.233 3.2) (xy 0.258 3.2)
				(xy 0.277 3.199) (xy 0.292 3.198) (xy 0.302 3.197) (xy 0.309 3.196) (xy 0.314 3.195) (xy 0.317 3.193)
				(xy 0.319 3.192) (xy 0.321 3.189) (xy 0.324 3.183) (xy 0.327 3.174) (xy 0.33 3.161) (xy 0.334 3.144)
				(xy 0.339 3.12) (xy 0.345 3.091) (xy 0.352 3.054) (xy 0.361 3.01) (xy 0.371 2.958) (xy 0.382 2.897)
				(xy 0.385 2.878) (xy 0.395 2.824) (xy 0.405 2.772) (xy 0.414 2.724) (xy 0.423 2.68) (xy 0.43 2.642)
				(xy 0.437 2.61) (xy 0.442 2.586) (xy 0.446 2.569) (xy 0.448 2.562) (xy 0.456 2.55) (xy 0.464 2.544)
				(xy 0.476 2.539) (xy 0.495 2.53) (xy 0.521 2.519) (xy 0.552 2.506) (xy 0.587 2.492) (xy 0.624 2.477)
				(xy 0.664 2.461) (xy 0.704 2.445) (xy 0.743 2.43) (xy 0.78 2.415) (xy 0.814 2.402) (xy 0.843 2.391)
				(xy 0.868 2.382) (xy 0.885 2.376) (xy 0.895 2.373) (xy 0.896 2.373) (xy 0.911 2.376) (xy 0.931 2.386)
				(xy 0.948 2.397) (xy 0.962 2.406) (xy 0.983 2.421) (xy 1.011 2.44) (xy 1.043 2.462) (xy 1.079 2.487)
				(xy 1.118 2.513) (xy 1.158 2.541) (xy 1.198 2.568) (xy 1.238 2.595) (xy 1.275 2.621) (xy 1.309 2.644)
				(xy 1.338 2.665) (xy 1.362 2.681) (xy 1.377 2.691) (xy 1.398 2.705) (xy 1.418 2.717) (xy 1.433 2.725)
				(xy 1.442 2.728) (xy 1.443 2.728) (xy 1.448 2.726) (xy 1.456 2.72) (xy 1.468 2.71) (xy 1.486 2.694)
				(xy 1.508 2.673) (xy 1.535 2.647) (xy 1.568 2.614) (xy 1.608 2.575) (xy 1.654 2.53) (xy 1.675 2.509)
				(xy 1.721 2.462) (xy 1.761 2.422) (xy 1.794 2.388) (xy 1.822 2.36) (xy 1.844 2.337) (xy 1.862 2.318)
				(xy 1.875 2.304) (xy 1.884 2.293) (xy 1.89 2.284) (xy 1.893 2.279) (xy 1.894 2.275) (xy 1.892 2.269)
				(xy 1.886 2.257) (xy 1.875 2.239) (xy 1.86 2.215) (xy 1.839 2.183) (xy 1.814 2.145) (xy 1.783 2.1)
				(xy 1.747 2.046) (xy 1.721 2.009) (xy 1.69 1.964) (xy 1.661 1.921) (xy 1.634 1.88) (xy 1.609 1.844)
				(xy 1.588 1.811) (xy 1.57 1.785) (xy 1.557 1.764) (xy 1.549 1.75) (xy 1.546 1.743) (xy 1.547 1.735)
				(xy 1.552 1.719) (xy 1.56 1.696) (xy 1.571 1.667) (xy 1.585 1.634) (xy 1.6 1.597) (xy 1.616 1.557)
				(xy 1.633 1.516) (xy 1.651 1.476) (xy 1.668 1.436) (xy 1.685 1.398) (xy 1.701 1.363) (xy 1.715 1.333)
				(xy 1.727 1.309) (xy 1.736 1.291) (xy 1.742 1.281) (xy 1.744 1.279) (xy 1.751 1.277) (xy 1.767 1.273)
				(xy 1.791 1.268) (xy 1.822 1.261) (xy 1.86 1.254) (xy 1.903 1.245) (xy 1.951 1.236) (xy 2.002 1.226)
				(xy 2.049 1.217) (xy 2.103 1.207) (xy 2.154 1.198) (xy 2.201 1.188) (xy 2.244 1.18) (xy 2.281 1.173)
				(xy 2.311 1.166) (xy 2.335 1.161) (xy 2.35 1.157) (xy 2.355 1.156) (xy 2.367 1.148) (xy 2.367 0.834)
				(xy 2.367 0.768) (xy 2.367 0.712) (xy 2.367 0.664) (xy 2.366 0.625) (xy 2.366 0.592) (xy 2.365 0.566)
				(xy 2.364 0.546) (xy 2.363 0.531) (xy 2.361 0.52) (xy 2.358 0.512) (xy 2.355 0.507) (xy 2.352 0.504)
				(xy 2.348 0.503) (xy 2.343 0.501) (xy 2.34 0.501) (xy 2.333 0.499) (xy 2.317 0.496) (xy 2.293 0.492)
				(xy 2.261 0.486) (xy 2.224 0.479) (xy 2.181 0.471) (xy 2.134 0.462) (xy 2.084 0.453) (xy 2.054 0.448)
				(xy 2.002 0.438) (xy 1.953 0.429) (xy 1.907 0.42) (xy 1.866 0.412) (xy 1.831 0.404) (xy 1.802 0.398)
				(xy 1.78 0.394) (xy 1.767 0.391) (xy 1.764 0.39) (xy 1.76 0.387) (xy 1.757 0.384) (xy 1.753 0.379)
				(xy 1.748 0.371) (xy 1.742 0.36) (xy 1.735 0.344) (xy 1.726 0.324) (xy 1.715 0.297) (xy 1.701 0.264)
				(xy 1.685 0.223) (xy 1.665 0.174) (xy 1.653 0.145) (xy 1.63 0.086) (xy 1.61 0.037) (xy 1.594 -0.005)
				(xy 1.582 -0.038) (xy 1.572 -0.064) (xy 1.566 -0.084) (xy 1.562 -0.097) (xy 1.561 -0.104) (xy 1.562 -0.105)
				(xy 1.565 -0.111) (xy 1.574 -0.125) (xy 1.587 -0.146) (xy 1.604 -0.173) (xy 1.626 -0.205) (xy 1.65 -0.241)
				(xy 1.677 -0.281) (xy 1.706 -0.324) (xy 1.729 -0.358) (xy 1.768 -0.413) (xy 1.8 -0.461) (xy 1.827 -0.502)
				(xy 1.85 -0.535) (xy 1.867 -0.562) (xy 1.88 -0.583) (xy 1.889 -0.598) (xy 1.893 -0.608) (xy 1.894 -0.612)
				(xy 1.893 -0.616) (xy 1.89 -0.622) (xy 1.885 -0.63) (xy 1.876 -0.64) (xy 1.863 -0.655) (xy 1.846 -0.673)
				(xy 1.825 -0.695) (xy 1.798 -0.723) (xy 1.765 -0.756) (xy 1.727 -0.795) (xy 1.682 -0.839) (xy 1.635 -0.886)
				(xy 1.595 -0.926) (xy 1.561 -0.96) (xy 1.532 -0.989) (xy 1.508 -1.012) (xy 1.488 -1.03) (xy 1.473 -1.044)
				(xy 1.461 -1.054) (xy 1.452 -1.061) (xy 1.445 -1.065) (xy 1.44 -1.066) (xy 1.438 -1.066) (xy 1.433 -1.064)
				(xy 1.421 -1.055) (xy 1.401 -1.043) (xy 1.376 -1.026) (xy 1.345 -1.005) (xy 1.31 -0.981) (xy 1.27 -0.954)
				(xy 1.228 -0.925) (xy 1.193 -0.901) (xy 1.138 -0.864) (xy 1.089 -0.83) (xy 1.046 -0.802) (xy 1.01 -0.778)
				(xy 0.981 -0.759) (xy 0.96 -0.746) (xy 0.946 -0.738) (xy 0.94 -0.736) (xy 0.932 -0.738) (xy 0.917 -0.745)
				(xy 0.895 -0.755) (xy 0.869 -0.768) (xy 0.84 -0.783) (xy 0.816 -0.795) (xy 0.781 -0.814) (xy 0.753 -0.828)
				(xy 0.732 -0.838) (xy 0.717 -0.845) (xy 0.707 -0.849) (xy 0.699 -0.85) (xy 0.694 -0.849) (xy 0.691 -0.847)
				(xy 0.687 -0.84) (xy 0.682 -0.829) (xy 0.674 -0.814) (xy 0.665 -0.793) (xy 0.653 -0.767) (xy 0.639 -0.735)
				(xy 0.623 -0.696) (xy 0.604 -0.651) (xy 0.582 -0.598) (xy 0.556 -0.538) (xy 0.528 -0.469) (xy 0.496 -0.391)
				(xy 0.47 -0.329) (xy 0.436 -0.247) (xy 0.406 -0.173) (xy 0.379 -0.108) (xy 0.355 -0.05) (xy 0.335 0)
				(xy 0.317 0.043) (xy 0.303 0.079) (xy 0.291 0.11) (xy 0.281 0.135) (xy 0.273 0.155) (xy 0.268 0.171)
				(xy 0.264 0.183) (xy 0.262 0.191) (xy 0.262 0.196) (xy 0.262 0.198) (xy 0.269 0.207) (xy 0.283 0.219)
				(xy 0.302 0.233) (xy 0.303 0.234) (xy 0.354 0.268) (xy 0.398 0.3) (xy 0.435 0.331) (xy 0.469 0.363)
				(xy 0.5 0.397) (xy 0.507 0.405) (xy 0.556 0.472) (xy 0.596 0.543) (xy 0.627 0.619) (xy 0.643 0.672)
				(xy 0.651 0.718) (xy 0.657 0.77) (xy 0.66 0.824) (xy 0.659 0.878) (xy 0.654 0.927) (xy 0.652 0.936)
				(xy 0.634 1.015) (xy 0.607 1.09) (xy 0.571 1.161) (xy 0.528 1.227) (xy 0.477 1.287) (xy 0.419 1.341)
				(xy 0.355 1.387) (xy 0.285 1.426) (xy 0.21 1.456) (xy 0.205 1.458) (xy 0.131 1.477) (xy 0.054 1.487)
				(xy -0.025 1.489) (xy -0.103 1.482) (xy -0.178 1.466) (xy -0.206 1.458) (xy -0.281 1.428) (xy -0.351 1.39)
				(xy -0.416 1.344) (xy -0.474 1.29) (xy -0.526 1.23) (xy -0.571 1.164) (xy -0.607 1.093) (xy -0.63 1.034)
				(xy -0.649 0.96) (xy -0.659 0.883) (xy -0.661 0.804) (xy -0.654 0.726) (xy -0.638 0.651) (xy -0.63 0.623)
				(xy -0.618 0.591) (xy -0.602 0.554) (xy -0.584 0.518) (xy -0.566 0.485) (xy -0.553 0.463) (xy -0.509 0.407)
				(xy -0.457 0.352) (xy -0.397 0.299) (xy -0.33 0.25) (xy -0.289 0.224) (xy -0.273 0.212) (xy -0.263 0.2)
				(xy -0.262 0.197) (xy -0.263 0.19) (xy -0.268 0.175) (xy -0.277 0.151) (xy -0.288 0.121) (xy -0.302 0.084)
				(xy -0.319 0.042) (xy -0.338 -0.005) (xy -0.358 -0.056) (xy -0.381 -0.111) (xy -0.404 -0.168) (xy -0.428 -0.228)
				(xy -0.453 -0.288) (xy -0.478 -0.349) (xy -0.504 -0.41) (xy -0.529 -0.47) (xy -0.553 -0.527) (xy -0.576 -0.583)
				(xy -0.598 -0.635) (xy -0.619 -0.683) (xy -0.638 -0.727) (xy -0.655 -0.765) (xy -0.669 -0.797) (xy -0.68 -0.822)
				(xy -0.689 -0.839) (xy -0.694 -0.848) (xy -0.695 -0.849) (xy -0.699 -0.85) (xy -0.706 -0.849) (xy -0.717 -0.845)
				(xy -0.732 -0.839) (xy -0.752 -0.829) (xy -0.779 -0.815) (xy -0.814 -0.797) (xy -0.817 -0.795) (xy -0.848 -0.779)
				(xy -0.877 -0.764) (xy -0.902 -0.752) (xy -0.922 -0.743) (xy -0.936 -0.737) (xy -0.941 -0.736) (xy -0.949 -0.739)
				(xy -0.964 -0.748) (xy -0.987 -0.761) (xy -1.015 -0.78) (xy -1.05 -0.803) (xy -1.072 -0.818) (xy -1.138 -0.863)
				(xy -1.195 -0.903) (xy -1.245 -0.937) (xy -1.289 -0.966) (xy -1.325 -0.991) (xy -1.356 -1.012) (xy -1.381 -1.029)
				(xy -1.401 -1.042) (xy -1.416 -1.052) (xy -1.427 -1.059) (xy -1.435 -1.064) (xy -1.439 -1.066) (xy -1.44 -1.066)
				(xy -1.449 -1.064) (xy -1.453 -1.061) (xy -1.458 -1.057) (xy -1.47 -1.046) (xy -1.487 -1.029) (xy -1.509 -1.007)
				(xy -1.537 -0.98) (xy -1.568 -0.95) (xy -1.602 -0.915) (xy -1.639 -0.879) (xy -1.678 -0.84) (xy -1.678 -0.839)
				(xy -1.726 -0.792) (xy -1.767 -0.751) (xy -1.801 -0.716) (xy -1.829 -0.687) (xy -1.852 -0.663) (xy -1.869 -0.644)
				(xy -1.882 -0.63) (xy -1.89 -0.62) (xy -1.894 -0.613) (xy -1.895 -0.61) (xy -1.892 -0.603) (xy -1.884 -0.588)
				(xy -1.87 -0.565) (xy -1.85 -0.536) (xy -1.826 -0.499) (xy -1.797 -0.455) (xy -1.763 -0.405) (xy -1.73 -0.358)
				(xy -1.7 -0.313) (xy -1.671 -0.271) (xy -1.645 -0.232) (xy -1.621 -0.197) (xy -1.601 -0.166) (xy -1.584 -0.141)
				(xy -1.572 -0.121) (xy -1.565 -0.109) (xy -1.563 -0.105) (xy -1.563 -0.099) (xy -1.566 -0.087) (xy -1.572 -0.07)
				(xy -1.58 -0.045) (xy -1.592 -0.013) (xy -1.607 0.026) (xy -1.626 0.074) (xy -1.648 0.13) (xy -1.654 0.145)
				(xy -1.676 0.199) (xy -1.695 0.245) (xy -1.71 0.282) (xy -1.723 0.313) (xy -1.733 0.337) (xy -1.741 0.356)
				(xy -1.748 0.369) (xy -1.753 0.379) (xy -1.758 0.385) (xy -1.761 0.388) (xy -1.763 0.389) (xy -1.767 0.39)
				(xy -1.774 0.392) (xy -1.784 0.395) (xy -1.799 0.398) (xy -1.818 0.402) (xy -1.843 0.407) (xy -1.873 0.413)
				(xy -1.91 0.42) (xy -1.954 0.429) (xy -2.005 0.438) (xy -2.065 0.449) (xy -2.133 0.462) (xy -2.211 0.477)
				(xy -2.22 0.478) (xy -2.26 0.486) (xy -2.29 0.491) (xy -2.313 0.496) (xy -2.33 0.499) (xy -2.341 0.502)
				(xy -2.349 0.504) (xy -2.353 0.506) (xy -2.356 0.508) (xy -2.359 0.51) (xy -2.36 0.511) (xy -2.361 0.514)
				(xy -2.363 0.518) (xy -2.364 0.526) (xy -2.365 0.536) (xy -2.366 0.551) (xy -2.366 0.571) (xy -2.367 0.597)
				(xy -2.367 0.629) (xy -2.368 0.668) (xy -2.368 0.715) (xy -2.368 0.771) (xy -2.368 0.834) (xy -2.368 1.148)
				(xy -2.356 1.155) (xy -2.349 1.158) (xy -2.333 1.162) (xy -2.309 1.167) (xy -2.278 1.173) (xy -2.24 1.181)
				(xy -2.197 1.189) (xy -2.149 1.198) (xy -2.098 1.208) (xy -2.051 1.217) (xy -1.996 1.227) (xy -1.945 1.237)
				(xy -1.897 1.246) (xy -1.854 1.254) (xy -1.817 1.262) (xy -1.787 1.268) (xy -1.764 1.273) (xy -1.75 1.277)
				(xy -1.745 1.279) (xy -1.741 1.285) (xy -1.733 1.3) (xy -1.722 1.322) (xy -1.709 1.35) (xy -1.694 1.382)
				(xy -1.677 1.419) (xy -1.66 1.458) (xy -1.642 1.498) (xy -1.625 1.539) (xy -1.608 1.58) (xy -1.592 1.618)
				(xy -1.578 1.653) (xy -1.565 1.684) (xy -1.556 1.709) (xy -1.549 1.729) (xy -1.546 1.74) (xy -1.546 1.742)
				(xy -1.549 1.749) (xy -1.558 1.763) (xy -1.571 1.784) (xy -1.588 1.811) (xy -1.61 1.843) (xy -1.634 1.88)
				(xy -1.661 1.92) (xy -1.691 1.963) (xy -1.722 2.008) (xy -1.762 2.067) (xy -1.796 2.117) (xy -1.825 2.16)
				(xy -1.848 2.196) (xy -1.867 2.225) (xy -1.881 2.247) (xy -1.89 2.262) (xy -1.895 2.272) (xy -1.895 2.275)
				(xy -1.894 2.279) (xy -1.891 2.285) (xy -1.884 2.293) (xy -1.875 2.305) (xy -1.861 2.32) (xy -1.843 2.339)
				(xy -1.82 2.363) (xy -1.792 2.392) (xy -1.758 2.426) (xy -1.718 2.466) (xy -1.676 2.509) (xy -1.627 2.557)
				(xy -1.585 2.599) (xy -1.549 2.634) (xy -1.52 2.663) (xy -1.495 2.686) (xy -1.476 2.704) (xy -1.462 2.716)
				(xy -1.452 2.724) (xy -1.446 2.728) (xy -1.444 2.728) (xy -1.437 2.726) (xy -1.423 2.717) (xy -1.401 2.703)
				(xy -1.372 2.685) (xy -1.337 2.661) (xy -1.295 2.634) (xy -1.248 2.602) (xy -1.196 2.566) (xy -1.173 2.551)
				(xy -1.118 2.513) (xy -1.071 2.481) (xy -1.031 2.454) (xy -0.998 2.432) (xy -0.97 2.413) (xy -0.948 2.399)
				(xy -0.931 2.389) (xy -0.917 2.381) (xy -0.907 2.376) (xy -0.901 2.373) (xy -0.897 2.373) (xy -0.888 2.375)
				(xy -0.87 2.38) (xy -0.845 2.39) (xy -0.813 2.402) (xy -0.774 2.417) (xy -0.73 2.434) (xy -0.681 2.454)
				(xy -0.629 2.475) (xy -0.586 2.493) (xy -0.55 2.508) (xy -0.522 2.52) (xy -0.499 2.529) (xy -0.482 2.537)
				(xy -0.47 2.543) (xy -0.461 2.548) (xy -0.455 2.551) (xy -0.452 2.554) (xy -0.449 2.557) (xy -0.448 2.56)
				(xy -0.447 2.566) (xy -0.443 2.582) (xy -0.438 2.605) (xy -0.432 2.637) (xy -0.425 2.674) (xy -0.417 2.717)
				(xy -0.407 2.765) (xy -0.398 2.817) (xy -0.388 2.871) (xy -0.387 2.876) (xy -0.375 2.94) (xy -0.364 2.995)
				(xy -0.356 3.042) (xy -0.348 3.081) (xy -0.342 3.112) (xy -0.337 3.137) (xy -0.332 3.157) (xy -0.328 3.171)
				(xy -0.325 3.181) (xy -0.323 3.188) (xy -0.32 3.191) (xy -0.32 3.192) (xy -0.317 3.194) (xy -0.313 3.195)
				(xy -0.307 3.197) (xy -0.298 3.198) (xy -0.286 3.199) (xy -0.269 3.199) (xy -0.247 3.2) (xy -0.219 3.2)
				(xy -0.184 3.201) (xy -0.142 3.201) (xy -0.092 3.201) (xy -0.033 3.201) (xy -0.001 3.201) (xy 0.063 3.201)
			)
			(stroke
				(width 0.01)
				(type solid)
			)
			(fill yes)
			(layer "B.Cu")
		)
		(fp_poly
			(pts
				(xy -0.843 -2.558) (xy -0.815 -2.564) (xy -0.794 -2.572) (xy -0.773 -2.581) (xy -0.759 -2.589) (xy -0.738 -2.603)
				(xy -0.783 -2.658) (xy -0.8 -2.677) (xy -0.814 -2.694) (xy -0.825 -2.706) (xy -0.831 -2.712) (xy -0.832 -2.712)
				(xy -0.837 -2.71) (xy -0.847 -2.703) (xy -0.849 -2.702) (xy -0.874 -2.69) (xy -0.904 -2.684) (xy -0.935 -2.685)
				(xy -0.942 -2.686) (xy -0.975 -2.698) (xy -1.001 -2.717) (xy -1.02 -2.741) (xy -1.034 -2.766) (xy -1.039 -3.197)
				(xy -1.164 -3.2) (xy -1.164 -2.565) (xy -1.037 -2.565) (xy -1.037 -2.626) (xy -1.009 -2.604) (xy -0.972 -2.579)
				(xy -0.931 -2.563) (xy -0.887 -2.556) (xy -0.843 -2.558)
			)
			(stroke
				(width 0.01)
				(type solid)
			)
			(fill yes)
			(layer "B.Mask")
		)
		(fp_poly
			(pts
				(xy 1.889 -1.554) (xy 1.907 -1.559) (xy 1.927 -1.566) (xy 1.948 -1.574) (xy 1.966 -1.583) (xy 1.979 -1.592)
				(xy 1.984 -1.597) (xy 1.982 -1.604) (xy 1.974 -1.616) (xy 1.962 -1.633) (xy 1.946 -1.652) (xy 1.945 -1.654)
				(xy 1.929 -1.673) (xy 1.915 -1.689) (xy 1.906 -1.7) (xy 1.901 -1.706) (xy 1.896 -1.705) (xy 1.885 -1.7)
				(xy 1.873 -1.695) (xy 1.84 -1.683) (xy 1.808 -1.68) (xy 1.776 -1.685) (xy 1.747 -1.698) (xy 1.723 -1.717)
				(xy 1.704 -1.742) (xy 1.696 -1.763) (xy 1.695 -1.772) (xy 1.694 -1.79) (xy 1.693 -1.817) (xy 1.692 -1.85)
				(xy 1.692 -1.89) (xy 1.691 -1.934) (xy 1.691 -1.983) (xy 1.691 -2.194) (xy 1.559 -2.194) (xy 1.559 -1.559)
				(xy 1.691 -1.559) (xy 1.691 -1.626) (xy 1.71 -1.607) (xy 1.739 -1.585) (xy 1.775 -1.568) (xy 1.814 -1.556)
				(xy 1.855 -1.552) (xy 1.889 -1.554)
			)
			(stroke
				(width 0.01)
				(type solid)
			)
			(fill yes)
			(layer "B.Mask")
		)
		(fp_poly
			(pts
				(xy -0.837 -1.56) (xy -0.797 -1.576) (xy -0.761 -1.6) (xy -0.73 -1.63) (xy -0.706 -1.667) (xy -0.69 -1.709)
				(xy -0.687 -1.721) (xy -0.685 -1.734) (xy -0.684 -1.757) (xy -0.683 -1.79) (xy -0.682 -1.833) (xy -0.681 -1.884)
				(xy -0.681 -1.945) (xy -0.681 -1.971) (xy -0.681 -2.194) (xy -0.808 -2.194) (xy -0.809 -1.984) (xy -0.811 -1.774)
				(xy -0.826 -1.744) (xy -0.845 -1.716) (xy -0.868 -1.697) (xy -0.897 -1.686) (xy -0.925 -1.682) (xy -0.947 -1.682)
				(xy -0.967 -1.684) (xy -0.979 -1.686) (xy -1.001 -1.698) (xy -1.023 -1.716) (xy -1.041 -1.738) (xy -1.049 -1.752)
				(xy -1.052 -1.758) (xy -1.054 -1.765) (xy -1.056 -1.773) (xy -1.057 -1.783) (xy -1.058 -1.797) (xy -1.059 -1.815)
				(xy -1.06 -1.839) (xy -1.06 -1.869) (xy -1.061 -1.907) (xy -1.061 -1.953) (xy -1.061 -1.985) (xy -1.063 -2.194)
				(xy -1.189 -2.194) (xy -1.189 -1.559) (xy -1.062 -1.559) (xy -1.062 -1.625) (xy -1.033 -1.602) (xy -1.001 -1.579)
				(xy -0.969 -1.564) (xy -0.934 -1.555) (xy -0.927 -1.554) (xy -0.881 -1.553) (xy -0.837 -1.56)
			)
			(stroke
				(width 0.01)
				(type solid)
			)
			(fill yes)
			(layer "B.Mask")
		)
		(fp_poly
			(pts
				(xy 1.042 -1.769) (xy 1.043 -1.979) (xy 1.059 -2.009) (xy 1.077 -2.036) (xy 1.1 -2.056) (xy 1.129 -2.067)
				(xy 1.159 -2.071) (xy 1.193 -2.07) (xy 1.221 -2.063) (xy 1.245 -2.047) (xy 1.258 -2.034) (xy 1.266 -2.025)
				(xy 1.273 -2.016) (xy 1.278 -2.008) (xy 1.282 -1.997) (xy 1.286 -1.985) (xy 1.288 -1.969) (xy 1.29 -1.948)
				(xy 1.291 -1.922) (xy 1.292 -1.89) (xy 1.293 -1.85) (xy 1.293 -1.801) (xy 1.294 -1.766) (xy 1.295 -1.559)
				(xy 1.422 -1.559) (xy 1.422 -2.194) (xy 1.295 -2.194) (xy 1.295 -2.161) (xy 1.295 -2.144) (xy 1.293 -2.132)
				(xy 1.292 -2.128) (xy 1.287 -2.131) (xy 1.278 -2.14) (xy 1.271 -2.147) (xy 1.256 -2.159) (xy 1.236 -2.171)
				(xy 1.219 -2.181) (xy 1.202 -2.188) (xy 1.186 -2.193) (xy 1.17 -2.196) (xy 1.148 -2.197) (xy 1.135 -2.198)
				(xy 1.107 -2.198) (xy 1.087 -2.197) (xy 1.07 -2.194) (xy 1.059 -2.19) (xy 1.036 -2.181) (xy 1.019 -2.172)
				(xy 1.003 -2.161) (xy 0.985 -2.146) (xy 0.981 -2.141) (xy 0.952 -2.107) (xy 0.931 -2.068) (xy 0.92 -2.033)
				(xy 0.918 -2.019) (xy 0.917 -1.996) (xy 0.916 -1.963) (xy 0.915 -1.92) (xy 0.914 -1.869) (xy 0.914 -1.808)
				(xy 0.914 -1.782) (xy 0.914 -1.559) (xy 1.04 -1.559) (xy 1.042 -1.769)
			)
			(stroke
				(width 0.01)
				(type solid)
			)
			(fill yes)
			(layer "B.Mask")
		)
		(fp_poly
			(pts
				(xy 1.753 -2.563) (xy 1.768 -2.568) (xy 1.787 -2.577) (xy 1.804 -2.586) (xy 1.818 -2.595) (xy 1.826 -2.602)
				(xy 1.827 -2.606) (xy 1.824 -2.611) (xy 1.815 -2.621) (xy 1.803 -2.636) (xy 1.789 -2.654) (xy 1.775 -2.671)
				(xy 1.761 -2.688) (xy 1.749 -2.701) (xy 1.742 -2.71) (xy 1.739 -2.712) (xy 1.735 -2.71) (xy 1.724 -2.704)
				(xy 1.713 -2.698) (xy 1.697 -2.69) (xy 1.682 -2.686) (xy 1.664 -2.685) (xy 1.653 -2.685) (xy 1.618 -2.688)
				(xy 1.59 -2.699) (xy 1.566 -2.718) (xy 1.561 -2.723) (xy 1.554 -2.732) (xy 1.548 -2.74) (xy 1.544 -2.748)
				(xy 1.54 -2.758) (xy 1.537 -2.769) (xy 1.534 -2.785) (xy 1.533 -2.804) (xy 1.532 -2.829) (xy 1.531 -2.861)
				(xy 1.53 -2.899) (xy 1.53 -2.947) (xy 1.53 -2.988) (xy 1.528 -3.2) (xy 1.468 -3.2) (xy 1.444 -3.2)
				(xy 1.425 -3.199) (xy 1.411 -3.198) (xy 1.405 -3.197) (xy 1.404 -3.191) (xy 1.404 -3.176) (xy 1.403 -3.153)
				(xy 1.403 -3.122) (xy 1.402 -3.085) (xy 1.402 -3.042) (xy 1.402 -2.993) (xy 1.402 -2.941) (xy 1.402 -2.886)
				(xy 1.402 -2.565) (xy 1.529 -2.565) (xy 1.529 -2.595) (xy 1.529 -2.611) (xy 1.53 -2.623) (xy 1.532 -2.626)
				(xy 1.537 -2.623) (xy 1.547 -2.615) (xy 1.554 -2.608) (xy 1.588 -2.584) (xy 1.627 -2.567) (xy 1.669 -2.558)
				(xy 1.712 -2.556) (xy 1.753 -2.563)
			)
			(stroke
				(width 0.01)
				(type solid)
			)
			(fill yes)
			(layer "B.Mask")
		)
		(fp_poly
			(pts
				(xy 2.316 -1.557) (xy 2.365 -1.57) (xy 2.41 -1.593) (xy 2.453 -1.625) (xy 2.46 -1.631) (xy 2.491 -1.661)
				(xy 2.466 -1.684) (xy 2.448 -1.699) (xy 2.43 -1.715) (xy 2.419 -1.725) (xy 2.397 -1.743) (xy 2.376 -1.724)
				(xy 2.345 -1.701) (xy 2.312 -1.687) (xy 2.274 -1.681) (xy 2.265 -1.681) (xy 2.226 -1.684) (xy 2.195 -1.693)
				(xy 2.167 -1.708) (xy 2.159 -1.715) (xy 2.136 -1.741) (xy 2.118 -1.776) (xy 2.107 -1.817) (xy 2.103 -1.866)
				(xy 2.103 -1.876) (xy 2.106 -1.926) (xy 2.116 -1.97) (xy 2.132 -2.006) (xy 2.155 -2.034) (xy 2.184 -2.055)
				(xy 2.219 -2.067) (xy 2.259 -2.072) (xy 2.274 -2.071) (xy 2.309 -2.066) (xy 2.339 -2.056) (xy 2.366 -2.038)
				(xy 2.377 -2.028) (xy 2.386 -2.02) (xy 2.393 -2.016) (xy 2.4 -2.015) (xy 2.409 -2.018) (xy 2.42 -2.027)
				(xy 2.436 -2.041) (xy 2.456 -2.059) (xy 2.491 -2.092) (xy 2.476 -2.108) (xy 2.449 -2.132) (xy 2.416 -2.155)
				(xy 2.38 -2.174) (xy 2.35 -2.186) (xy 2.327 -2.193) (xy 2.306 -2.197) (xy 2.283 -2.199) (xy 2.259 -2.199)
				(xy 2.233 -2.198) (xy 2.209 -2.196) (xy 2.189 -2.193) (xy 2.182 -2.191) (xy 2.133 -2.173) (xy 2.089 -2.146)
				(xy 2.053 -2.112) (xy 2.023 -2.071) (xy 2.012 -2.051) (xy 2 -2.023) (xy 1.991 -1.999) (xy 1.984 -1.975)
				(xy 1.981 -1.948) (xy 1.979 -1.917) (xy 1.978 -1.879) (xy 1.978 -1.877) (xy 1.979 -1.838) (xy 1.98 -1.806)
				(xy 1.984 -1.78) (xy 1.99 -1.756) (xy 1.999 -1.731) (xy 2.011 -1.704) (xy 2.012 -1.701) (xy 2.039 -1.657)
				(xy 2.072 -1.62) (xy 2.111 -1.591) (xy 2.156 -1.57) (xy 2.207 -1.557) (xy 2.263 -1.552) (xy 2.316 -1.557)
			)
			(stroke
				(width 0.01)
				(type solid)
			)
			(fill yes)
			(layer "B.Mask")
		)
		(fp_poly
			(pts
				(xy -1.494 -1.56) (xy -1.447 -1.576) (xy -1.405 -1.6) (xy -1.368 -1.633) (xy -1.341 -1.668) (xy -1.326 -1.692)
				(xy -1.316 -1.716) (xy -1.308 -1.743) (xy -1.302 -1.774) (xy -1.299 -1.811) (xy -1.297 -1.845) (xy -1.294 -1.925)
				(xy -1.692 -1.925) (xy -1.692 -1.942) (xy -1.687 -1.977) (xy -1.673 -2.011) (xy -1.65 -2.039) (xy -1.626 -2.059)
				(xy -1.601 -2.071) (xy -1.572 -2.078) (xy -1.537 -2.079) (xy -1.497 -2.074) (xy -1.458 -2.06) (xy -1.422 -2.036)
				(xy -1.421 -2.036) (xy -1.402 -2.021) (xy -1.359 -2.057) (xy -1.342 -2.072) (xy -1.327 -2.085) (xy -1.317 -2.094)
				(xy -1.314 -2.098) (xy -1.316 -2.103) (xy -1.324 -2.113) (xy -1.338 -2.126) (xy -1.354 -2.139) (xy -1.372 -2.152)
				(xy -1.389 -2.163) (xy -1.399 -2.168) (xy -1.421 -2.178) (xy -1.445 -2.187) (xy -1.461 -2.191) (xy -1.488 -2.196)
				(xy -1.522 -2.199) (xy -1.557 -2.199) (xy -1.591 -2.196) (xy -1.62 -2.192) (xy -1.629 -2.19) (xy -1.677 -2.171)
				(xy -1.718 -2.146) (xy -1.752 -2.114) (xy -1.779 -2.074) (xy -1.8 -2.026) (xy -1.802 -2.02) (xy -1.81 -1.989)
				(xy -1.815 -1.951) (xy -1.818 -1.908) (xy -1.819 -1.865) (xy -1.818 -1.823) (xy -1.816 -1.804) (xy -1.692 -1.804)
				(xy -1.692 -1.818) (xy -1.428 -1.818) (xy -1.428 -1.801) (xy -1.432 -1.775) (xy -1.442 -1.748) (xy -1.457 -1.722)
				(xy -1.469 -1.707) (xy -1.495 -1.688) (xy -1.526 -1.676) (xy -1.56 -1.672) (xy -1.593 -1.676) (xy -1.619 -1.685)
				(xy -1.646 -1.704) (xy -1.668 -1.73) (xy -1.683 -1.76) (xy -1.691 -1.792) (xy -1.692 -1.804) (xy -1.816 -1.804)
				(xy -1.814 -1.786) (xy -1.812 -1.777) (xy -1.797 -1.724) (xy -1.775 -1.676) (xy -1.747 -1.636) (xy -1.713 -1.603)
				(xy -1.673 -1.578) (xy -1.629 -1.561) (xy -1.597 -1.554) (xy -1.544 -1.552) (xy -1.494 -1.56)
			)
			(stroke
				(width 0.01)
				(type solid)
			)
			(fill yes)
			(layer "B.Mask")
		)
		(fp_poly
			(pts
				(xy 2.835 -1.557) (xy 2.883 -1.57) (xy 2.926 -1.592) (xy 2.964 -1.621) (xy 2.996 -1.657) (xy 3.021 -1.699)
				(xy 3.038 -1.747) (xy 3.04 -1.757) (xy 3.043 -1.776) (xy 3.045 -1.802) (xy 3.047 -1.832) (xy 3.047 -1.858)
				(xy 3.047 -1.925) (xy 2.65 -1.925) (xy 2.653 -1.951) (xy 2.663 -1.991) (xy 2.68 -2.024) (xy 2.703 -2.049)
				(xy 2.733 -2.067) (xy 2.77 -2.077) (xy 2.801 -2.079) (xy 2.845 -2.075) (xy 2.883 -2.063) (xy 2.916 -2.042)
				(xy 2.92 -2.039) (xy 2.929 -2.031) (xy 2.935 -2.026) (xy 2.941 -2.025) (xy 2.949 -2.027) (xy 2.959 -2.034)
				(xy 2.974 -2.047) (xy 2.994 -2.064) (xy 3.01 -2.078) (xy 3.023 -2.088) (xy 3.03 -2.095) (xy 3.032 -2.096)
				(xy 3.03 -2.1) (xy 3.022 -2.11) (xy 3.01 -2.122) (xy 3.009 -2.123) (xy 2.98 -2.147) (xy 2.945 -2.169)
				(xy 2.906 -2.185) (xy 2.887 -2.191) (xy 2.861 -2.196) (xy 2.828 -2.198) (xy 2.793 -2.198) (xy 2.759 -2.197)
				(xy 2.729 -2.193) (xy 2.721 -2.191) (xy 2.675 -2.175) (xy 2.634 -2.15) (xy 2.599 -2.118) (xy 2.569 -2.077)
				(xy 2.547 -2.029) (xy 2.536 -1.996) (xy 2.532 -1.973) (xy 2.529 -1.942) (xy 2.527 -1.906) (xy 2.527 -1.869)
				(xy 2.528 -1.832) (xy 2.529 -1.818) (xy 2.65 -1.818) (xy 2.922 -1.818) (xy 2.918 -1.799) (xy 2.908 -1.758)
				(xy 2.891 -1.725) (xy 2.869 -1.7) (xy 2.84 -1.683) (xy 2.826 -1.678) (xy 2.788 -1.672) (xy 2.753 -1.675)
				(xy 2.722 -1.687) (xy 2.695 -1.706) (xy 2.674 -1.734) (xy 2.659 -1.768) (xy 2.654 -1.794) (xy 2.65 -1.818)
				(xy 2.529 -1.818) (xy 2.53 -1.798) (xy 2.534 -1.769) (xy 2.536 -1.76) (xy 2.554 -1.707) (xy 2.578 -1.662)
				(xy 2.609 -1.624) (xy 2.645 -1.593) (xy 2.687 -1.571) (xy 2.734 -1.557) (xy 2.783 -1.553) (xy 2.835 -1.557)
			)
			(stroke
				(width 0.01)
				(type solid)
			)
			(fill yes)
			(layer "B.Mask")
		)
		(fp_poly
			(pts
				(xy 2.148 -2.561) (xy 2.193 -2.574) (xy 2.235 -2.595) (xy 2.273 -2.623) (xy 2.304 -2.657) (xy 2.326 -2.691)
				(xy 2.338 -2.718) (xy 2.346 -2.745) (xy 2.352 -2.774) (xy 2.355 -2.808) (xy 2.357 -2.85) (xy 2.357 -2.858)
				(xy 2.357 -2.931) (xy 1.96 -2.931) (xy 1.963 -2.955) (xy 1.973 -2.993) (xy 1.991 -3.026) (xy 2.015 -3.053)
				(xy 2.039 -3.069) (xy 2.057 -3.076) (xy 2.08 -3.08) (xy 2.103 -3.082) (xy 2.144 -3.081) (xy 2.18 -3.071)
				(xy 2.214 -3.054) (xy 2.227 -3.045) (xy 2.24 -3.035) (xy 2.25 -3.029) (xy 2.253 -3.027) (xy 2.258 -3.03)
				(xy 2.269 -3.039) (xy 2.284 -3.05) (xy 2.3 -3.064) (xy 2.315 -3.078) (xy 2.329 -3.09) (xy 2.338 -3.099)
				(xy 2.341 -3.103) (xy 2.337 -3.11) (xy 2.327 -3.121) (xy 2.312 -3.134) (xy 2.294 -3.148) (xy 2.276 -3.161)
				(xy 2.259 -3.171) (xy 2.252 -3.175) (xy 2.204 -3.192) (xy 2.152 -3.202) (xy 2.098 -3.204) (xy 2.046 -3.198)
				(xy 2.032 -3.195) (xy 1.984 -3.178) (xy 1.943 -3.154) (xy 1.909 -3.123) (xy 1.881 -3.084) (xy 1.859 -3.037)
				(xy 1.847 -3.003) (xy 1.841 -2.972) (xy 1.838 -2.934) (xy 1.836 -2.893) (xy 1.837 -2.851) (xy 1.839 -2.824)
				(xy 1.96 -2.824) (xy 2.23 -2.824) (xy 2.23 -2.813) (xy 2.225 -2.783) (xy 2.214 -2.753) (xy 2.196 -2.725)
				(xy 2.175 -2.702) (xy 2.151 -2.686) (xy 2.128 -2.68) (xy 2.101 -2.677) (xy 2.072 -2.678) (xy 2.051 -2.683)
				(xy 2.023 -2.696) (xy 2 -2.717) (xy 1.981 -2.746) (xy 1.968 -2.779) (xy 1.963 -2.8) (xy 1.96 -2.824)
				(xy 1.839 -2.824) (xy 1.839 -2.811) (xy 1.844 -2.776) (xy 1.848 -2.76) (xy 1.866 -2.708) (xy 1.889 -2.663)
				(xy 1.919 -2.627) (xy 1.954 -2.598) (xy 1.996 -2.575) (xy 2.007 -2.571) (xy 2.054 -2.559) (xy 2.101 -2.556)
				(xy 2.148 -2.561)
			)
			(stroke
				(width 0.01)
				(type solid)
			)
			(fill yes)
			(layer "B.Mask")
		)
		(fp_poly
			(pts
				(xy -2.733 -1.557) (xy -2.685 -1.57) (xy -2.642 -1.592) (xy -2.604 -1.622) (xy -2.581 -1.649) (xy -2.562 -1.676)
				(xy -2.548 -1.706) (xy -2.537 -1.739) (xy -2.53 -1.777) (xy -2.527 -1.821) (xy -2.526 -1.873) (xy -2.527 -1.907)
				(xy -2.529 -1.956) (xy -2.534 -1.997) (xy -2.542 -2.031) (xy -2.553 -2.06) (xy -2.567 -2.086) (xy -2.587 -2.111)
				(xy -2.603 -2.129) (xy -2.637 -2.158) (xy -2.673 -2.178) (xy -2.714 -2.192) (xy -2.76 -2.198) (xy -2.789 -2.199)
				(xy -2.813 -2.198) (xy -2.835 -2.196) (xy -2.852 -2.194) (xy -2.857 -2.194) (xy -2.898 -2.179) (xy -2.937 -2.155)
				(xy -2.97 -2.126) (xy -2.993 -2.101) (xy -3.011 -2.077) (xy -3.024 -2.051) (xy -3.034 -2.022) (xy -3.041 -1.988)
				(xy -3.045 -1.947) (xy -3.047 -1.91) (xy -3.047 -1.882) (xy -2.919 -1.882) (xy -2.919 -1.968) (xy -2.903 -2.001)
				(xy -2.885 -2.031) (xy -2.863 -2.051) (xy -2.837 -2.064) (xy -2.804 -2.07) (xy -2.779 -2.07) (xy -2.755 -2.069)
				(xy -2.737 -2.065) (xy -2.722 -2.058) (xy -2.717 -2.055) (xy -2.697 -2.041) (xy -2.681 -2.025) (xy -2.67 -2.004)
				(xy -2.662 -1.978) (xy -2.657 -1.945) (xy -2.654 -1.903) (xy -2.654 -1.899) (xy -2.653 -1.848) (xy -2.656 -1.806)
				(xy -2.662 -1.772) (xy -2.673 -1.744) (xy -2.687 -1.722) (xy -2.707 -1.705) (xy -2.723 -1.695) (xy -2.755 -1.684)
				(xy -2.788 -1.68) (xy -2.821 -1.684) (xy -2.851 -1.695) (xy -2.877 -1.713) (xy -2.892 -1.729) (xy -2.901 -1.745)
				(xy -2.908 -1.76) (xy -2.913 -1.778) (xy -2.916 -1.8) (xy -2.918 -1.828) (xy -2.919 -1.864) (xy -2.919 -1.882)
				(xy -3.047 -1.882) (xy -3.048 -1.844) (xy -3.043 -1.786) (xy -3.034 -1.736) (xy -3.021 -1.695) (xy -3.004 -1.664)
				(xy -2.972 -1.624) (xy -2.935 -1.594) (xy -2.893 -1.571) (xy -2.846 -1.558) (xy -2.794 -1.553) (xy -2.787 -1.553)
				(xy -2.733 -1.557)
			)
			(stroke
				(width 0.01)
				(type solid)
			)
			(fill yes)
			(layer "B.Mask")
		)
		(fp_poly
			(pts
				(xy -0.229 -3.2) (xy -0.354 -3.197) (xy -0.355 -3.165) (xy -0.357 -3.133) (xy -0.374 -3.148) (xy -0.411 -3.175)
				(xy -0.453 -3.193) (xy -0.497 -3.203) (xy -0.542 -3.204) (xy -0.585 -3.195) (xy -0.586 -3.195) (xy -0.621 -3.181)
				(xy -0.651 -3.16) (xy -0.673 -3.141) (xy -0.689 -3.123) (xy -0.702 -3.106) (xy -0.712 -3.086) (xy -0.72 -3.064)
				(xy -0.726 -3.038) (xy -0.73 -3.007) (xy -0.732 -2.968) (xy -0.733 -2.922) (xy -0.733 -2.88) (xy -0.602 -2.88)
				(xy -0.602 -2.915) (xy -0.602 -2.942) (xy -0.601 -2.962) (xy -0.6 -2.977) (xy -0.598 -2.988) (xy -0.596 -2.998)
				(xy -0.592 -3.007) (xy -0.591 -3.01) (xy -0.574 -3.039) (xy -0.552 -3.059) (xy -0.525 -3.071) (xy -0.492 -3.076)
				(xy -0.472 -3.076) (xy -0.442 -3.072) (xy -0.418 -3.063) (xy -0.398 -3.048) (xy -0.382 -3.029) (xy -0.371 -3.004)
				(xy -0.363 -2.972) (xy -0.358 -2.933) (xy -0.356 -2.885) (xy -0.356 -2.88) (xy -0.358 -2.828) (xy -0.363 -2.785)
				(xy -0.373 -2.75) (xy -0.387 -2.724) (xy -0.406 -2.704) (xy -0.43 -2.692) (xy -0.46 -2.686) (xy -0.483 -2.685)
				(xy -0.517 -2.687) (xy -0.544 -2.696) (xy -0.565 -2.711) (xy -0.583 -2.734) (xy -0.591 -2.751) (xy -0.595 -2.76)
				(xy -0.598 -2.769) (xy -0.6 -2.779) (xy -0.601 -2.793) (xy -0.602 -2.811) (xy -0.602 -2.836) (xy -0.602 -2.869)
				(xy -0.602 -2.88) (xy -0.733 -2.88) (xy -0.733 -2.827) (xy -0.732 -2.783) (xy -0.729 -2.746) (xy -0.725 -2.716)
				(xy -0.719 -2.691) (xy -0.71 -2.67) (xy -0.699 -2.651) (xy -0.685 -2.633) (xy -0.668 -2.616) (xy -0.668 -2.615)
				(xy -0.632 -2.587) (xy -0.592 -2.567) (xy -0.55 -2.557) (xy -0.506 -2.556) (xy -0.463 -2.564) (xy -0.421 -2.582)
				(xy -0.411 -2.587) (xy -0.394 -2.598) (xy -0.377 -2.61) (xy -0.373 -2.614) (xy -0.356 -2.627) (xy -0.356 -2.306)
				(xy -0.229 -2.306) (xy -0.229 -3.2)
			)
			(stroke
				(width 0.01)
				(type solid)
			)
			(fill yes)
			(layer "B.Mask")
		)
		(fp_poly
			(pts
				(xy 0.605 -1.558) (xy 0.651 -1.574) (xy 0.694 -1.598) (xy 0.728 -1.627) (xy 0.75 -1.652) (xy 0.768 -1.678)
				(xy 0.781 -1.707) (xy 0.791 -1.739) (xy 0.797 -1.777) (xy 0.801 -1.822) (xy 0.802 -1.876) (xy 0.802 -1.877)
				(xy 0.801 -1.929) (xy 0.798 -1.973) (xy 0.792 -2.009) (xy 0.784 -2.04) (xy 0.774 -2.062) (xy 0.748 -2.103)
				(xy 0.715 -2.139) (xy 0.675 -2.167) (xy 0.632 -2.187) (xy 0.626 -2.189) (xy 0.599 -2.195) (xy 0.567 -2.198)
				(xy 0.532 -2.199) (xy 0.499 -2.197) (xy 0.471 -2.193) (xy 0.466 -2.192) (xy 0.428 -2.177) (xy 0.391 -2.155)
				(xy 0.359 -2.129) (xy 0.354 -2.123) (xy 0.332 -2.098) (xy 0.316 -2.073) (xy 0.303 -2.047) (xy 0.294 -2.017)
				(xy 0.287 -1.983) (xy 0.284 -1.943) (xy 0.282 -1.894) (xy 0.282 -1.877) (xy 0.409 -1.877) (xy 0.41 -1.918)
				(xy 0.412 -1.95) (xy 0.416 -1.976) (xy 0.423 -1.997) (xy 0.432 -2.015) (xy 0.445 -2.03) (xy 0.451 -2.037)
				(xy 0.471 -2.054) (xy 0.491 -2.064) (xy 0.514 -2.07) (xy 0.543 -2.072) (xy 0.569 -2.07) (xy 0.59 -2.065)
				(xy 0.601 -2.06) (xy 0.625 -2.047) (xy 0.642 -2.031) (xy 0.656 -2.009) (xy 0.661 -1.998) (xy 0.665 -1.989)
				(xy 0.668 -1.98) (xy 0.67 -1.969) (xy 0.671 -1.954) (xy 0.672 -1.935) (xy 0.673 -1.909) (xy 0.673 -1.877)
				(xy 0.673 -1.842) (xy 0.672 -1.817) (xy 0.671 -1.798) (xy 0.67 -1.784) (xy 0.668 -1.773) (xy 0.665 -1.764)
				(xy 0.661 -1.755) (xy 0.647 -1.73) (xy 0.632 -1.712) (xy 0.612 -1.698) (xy 0.601 -1.693) (xy 0.569 -1.683)
				(xy 0.535 -1.681) (xy 0.501 -1.686) (xy 0.471 -1.7) (xy 0.447 -1.719) (xy 0.434 -1.736) (xy 0.424 -1.753)
				(xy 0.417 -1.774) (xy 0.412 -1.8) (xy 0.41 -1.833) (xy 0.409 -1.873) (xy 0.409 -1.877) (xy 0.282 -1.877)
				(xy 0.283 -1.824) (xy 0.286 -1.78) (xy 0.292 -1.742) (xy 0.301 -1.711) (xy 0.313 -1.683) (xy 0.33 -1.657)
				(xy 0.35 -1.633) (xy 0.351 -1.632) (xy 0.385 -1.601) (xy 0.42 -1.578) (xy 0.46 -1.563) (xy 0.505 -1.554)
				(xy 0.555 -1.551) (xy 0.605 -1.558)
			)
			(stroke
				(width 0.01)
				(type solid)
			)
			(fill yes)
			(layer "B.Mask")
		)
		(fp_poly
			(pts
				(xy 0.004 -1.556) (xy 0.054 -1.566) (xy 0.102 -1.582) (xy 0.146 -1.605) (xy 0.154 -1.61) (xy 0.193 -1.636)
				(xy 0.178 -1.655) (xy 0.166 -1.668) (xy 0.152 -1.686) (xy 0.138 -1.7) (xy 0.114 -1.727) (xy 0.07 -1.705)
				(xy 0.032 -1.688) (xy -0.007 -1.677) (xy -0.044 -1.672) (xy -0.079 -1.672) (xy -0.11 -1.678) (xy -0.136 -1.69)
				(xy -0.154 -1.707) (xy -0.162 -1.724) (xy -0.164 -1.745) (xy -0.164 -1.761) (xy -0.159 -1.772) (xy -0.15 -1.782)
				(xy -0.149 -1.783) (xy -0.139 -1.791) (xy -0.128 -1.797) (xy -0.114 -1.802) (xy -0.095 -1.805) (xy -0.07 -1.808)
				(xy -0.037 -1.811) (xy -0.02 -1.813) (xy 0.027 -1.817) (xy 0.065 -1.823) (xy 0.096 -1.832) (xy 0.122 -1.842)
				(xy 0.14 -1.854) (xy 0.166 -1.879) (xy 0.186 -1.91) (xy 0.2 -1.947) (xy 0.206 -1.987) (xy 0.206 -2.018)
				(xy 0.198 -2.06) (xy 0.181 -2.097) (xy 0.155 -2.129) (xy 0.122 -2.156) (xy 0.08 -2.177) (xy 0.042 -2.189)
				(xy 0.005 -2.196) (xy -0.038 -2.199) (xy -0.083 -2.198) (xy -0.125 -2.194) (xy -0.153 -2.189) (xy -0.177 -2.181)
				(xy -0.204 -2.171) (xy -0.229 -2.16) (xy -0.232 -2.159) (xy -0.251 -2.148) (xy -0.272 -2.136) (xy -0.292 -2.122)
				(xy -0.309 -2.109) (xy -0.323 -2.098) (xy -0.33 -2.09) (xy -0.331 -2.088) (xy -0.327 -2.084) (xy -0.318 -2.073)
				(xy -0.304 -2.059) (xy -0.288 -2.043) (xy -0.246 -2) (xy -0.221 -2.021) (xy -0.184 -2.047) (xy -0.145 -2.065)
				(xy -0.102 -2.075) (xy -0.053 -2.079) (xy -0.049 -2.079) (xy -0.023 -2.079) (xy -0.004 -2.078) (xy 0.011 -2.074)
				(xy 0.025 -2.069) (xy 0.029 -2.068) (xy 0.054 -2.052) (xy 0.071 -2.033) (xy 0.079 -2.01) (xy 0.078 -1.986)
				(xy 0.074 -1.975) (xy 0.068 -1.964) (xy 0.06 -1.956) (xy 0.048 -1.949) (xy 0.031 -1.944) (xy 0.007 -1.939)
				(xy -0.024 -1.935) (xy -0.052 -1.932) (xy -0.089 -1.929) (xy -0.119 -1.925) (xy -0.142 -1.921) (xy -0.16 -1.917)
				(xy -0.176 -1.912) (xy -0.192 -1.906) (xy -0.201 -1.901) (xy -0.235 -1.879) (xy -0.262 -1.85) (xy -0.28 -1.816)
				(xy -0.29 -1.776) (xy -0.292 -1.75) (xy -0.291 -1.727) (xy -0.289 -1.705) (xy -0.286 -1.689) (xy -0.286 -1.688)
				(xy -0.273 -1.659) (xy -0.253 -1.63) (xy -0.229 -1.604) (xy -0.221 -1.599) (xy -0.185 -1.577) (xy -0.143 -1.562)
				(xy -0.096 -1.554) (xy -0.047 -1.552) (xy 0.004 -1.556)
			)
			(stroke
				(width 0.01)
				(type solid)
			)
			(fill yes)
			(layer "B.Mask")
		)
		(fp_poly
			(pts
				(xy 1.038 -2.556) (xy 1.091 -2.563) (xy 1.137 -2.576) (xy 1.177 -2.595) (xy 1.209 -2.62) (xy 1.234 -2.65)
				(xy 1.242 -2.665) (xy 1.247 -2.677) (xy 1.251 -2.691) (xy 1.255 -2.708) (xy 1.258 -2.727) (xy 1.26 -2.751)
				(xy 1.262 -2.78) (xy 1.263 -2.815) (xy 1.263 -2.858) (xy 1.264 -2.908) (xy 1.263 -2.967) (xy 1.263 -2.989)
				(xy 1.262 -3.197) (xy 1.135 -3.197) (xy 1.133 -3.171) (xy 1.132 -3.144) (xy 1.119 -3.159) (xy 1.096 -3.179)
				(xy 1.065 -3.193) (xy 1.026 -3.202) (xy 0.98 -3.204) (xy 0.976 -3.204) (xy 0.955 -3.204) (xy 0.937 -3.203)
				(xy 0.925 -3.202) (xy 0.924 -3.201) (xy 0.879 -3.189) (xy 0.839 -3.17) (xy 0.806 -3.144) (xy 0.781 -3.113)
				(xy 0.763 -3.077) (xy 0.753 -3.037) (xy 0.753 -3.005) (xy 0.873 -3.005) (xy 0.874 -3.023) (xy 0.878 -3.035)
				(xy 0.887 -3.047) (xy 0.89 -3.05) (xy 0.903 -3.063) (xy 0.917 -3.072) (xy 0.935 -3.078) (xy 0.957 -3.081)
				(xy 0.986 -3.082) (xy 1.013 -3.082) (xy 1.043 -3.081) (xy 1.065 -3.079) (xy 1.08 -3.077) (xy 1.091 -3.073)
				(xy 1.096 -3.071) (xy 1.112 -3.058) (xy 1.123 -3.039) (xy 1.13 -3.012) (xy 1.132 -2.977) (xy 1.132 -2.975)
				(xy 1.132 -2.931) (xy 1.035 -2.931) (xy 0.999 -2.931) (xy 0.973 -2.931) (xy 0.953 -2.932) (xy 0.939 -2.934)
				(xy 0.928 -2.936) (xy 0.919 -2.939) (xy 0.916 -2.94) (xy 0.893 -2.954) (xy 0.88 -2.971) (xy 0.874 -2.994)
				(xy 0.873 -3.005) (xy 0.753 -3.005) (xy 0.753 -2.994) (xy 0.761 -2.951) (xy 0.768 -2.931) (xy 0.776 -2.915)
				(xy 0.786 -2.901) (xy 0.802 -2.884) (xy 0.804 -2.882) (xy 0.82 -2.867) (xy 0.835 -2.854) (xy 0.85 -2.845)
				(xy 0.867 -2.838) (xy 0.887 -2.833) (xy 0.912 -2.829) (xy 0.943 -2.827) (xy 0.982 -2.826) (xy 1.015 -2.825)
				(xy 1.133 -2.823) (xy 1.132 -2.771) (xy 1.131 -2.746) (xy 1.129 -2.73) (xy 1.127 -2.719) (xy 1.123 -2.711)
				(xy 1.117 -2.705) (xy 1.098 -2.691) (xy 1.07 -2.682) (xy 1.032 -2.677) (xy 1.006 -2.677) (xy 0.972 -2.678)
				(xy 0.945 -2.682) (xy 0.924 -2.688) (xy 0.907 -2.699) (xy 0.9 -2.706) (xy 0.882 -2.723) (xy 0.834 -2.686)
				(xy 0.816 -2.672) (xy 0.801 -2.66) (xy 0.79 -2.652) (xy 0.787 -2.648) (xy 0.791 -2.639) (xy 0.801 -2.626)
				(xy 0.816 -2.612) (xy 0.832 -2.6) (xy 0.864 -2.581) (xy 0.902 -2.568) (xy 0.946 -2.559) (xy 0.98 -2.556)
				(xy 1.038 -2.556)
			)
			(stroke
				(width 0.01)
				(type solid)
			)
			(fill yes)
			(layer "B.Mask")
		)
		(fp_poly
			(pts
				(xy -1.521 -2.559) (xy -1.485 -2.562) (xy -1.454 -2.568) (xy -1.427 -2.577) (xy -1.401 -2.589) (xy -1.371 -2.61)
				(xy -1.345 -2.639) (xy -1.325 -2.67) (xy -1.321 -2.679) (xy -1.309 -2.71) (xy -1.309 -3.197) (xy -1.433 -3.2)
				(xy -1.433 -3.172) (xy -1.434 -3.157) (xy -1.435 -3.147) (xy -1.436 -3.144) (xy -1.44 -3.147) (xy -1.449 -3.156)
				(xy -1.453 -3.161) (xy -1.472 -3.178) (xy -1.496 -3.19) (xy -1.526 -3.198) (xy -1.563 -3.202) (xy -1.578 -3.203)
				(xy -1.603 -3.203) (xy -1.627 -3.203) (xy -1.647 -3.201) (xy -1.656 -3.2) (xy -1.686 -3.191) (xy -1.717 -3.176)
				(xy -1.746 -3.159) (xy -1.765 -3.143) (xy -1.79 -3.111) (xy -1.807 -3.075) (xy -1.816 -3.037) (xy -1.817 -2.998)
				(xy -1.817 -2.997) (xy -1.697 -2.997) (xy -1.696 -3.02) (xy -1.687 -3.042) (xy -1.67 -3.06) (xy -1.668 -3.062)
				(xy -1.654 -3.07) (xy -1.64 -3.076) (xy -1.624 -3.08) (xy -1.602 -3.081) (xy -1.574 -3.082) (xy -1.558 -3.082)
				(xy -1.529 -3.081) (xy -1.508 -3.08) (xy -1.494 -3.078) (xy -1.483 -3.075) (xy -1.474 -3.07) (xy -1.458 -3.058)
				(xy -1.447 -3.041) (xy -1.44 -3.017) (xy -1.435 -2.985) (xy -1.435 -2.977) (xy -1.432 -2.931) (xy -1.533 -2.931)
				(xy -1.568 -2.931) (xy -1.595 -2.931) (xy -1.615 -2.932) (xy -1.63 -2.934) (xy -1.641 -2.936) (xy -1.65 -2.938)
				(xy -1.655 -2.941) (xy -1.676 -2.955) (xy -1.69 -2.974) (xy -1.697 -2.997) (xy -1.817 -2.997) (xy -1.811 -2.96)
				(xy -1.797 -2.924) (xy -1.775 -2.892) (xy -1.747 -2.864) (xy -1.715 -2.845) (xy -1.7 -2.838) (xy -1.685 -2.833)
				(xy -1.668 -2.83) (xy -1.648 -2.827) (xy -1.623 -2.825) (xy -1.591 -2.824) (xy -1.551 -2.824) (xy -1.54 -2.824)
				(xy -1.432 -2.824) (xy -1.434 -2.776) (xy -1.436 -2.747) (xy -1.441 -2.726) (xy -1.448 -2.711) (xy -1.46 -2.699)
				(xy -1.474 -2.689) (xy -1.483 -2.685) (xy -1.492 -2.682) (xy -1.505 -2.68) (xy -1.524 -2.68) (xy -1.55 -2.679)
				(xy -1.56 -2.679) (xy -1.594 -2.68) (xy -1.62 -2.682) (xy -1.639 -2.686) (xy -1.654 -2.692) (xy -1.666 -2.701)
				(xy -1.675 -2.711) (xy -1.686 -2.724) (xy -1.735 -2.686) (xy -1.754 -2.672) (xy -1.769 -2.659) (xy -1.78 -2.65)
				(xy -1.784 -2.646) (xy -1.78 -2.64) (xy -1.77 -2.629) (xy -1.756 -2.616) (xy -1.74 -2.604) (xy -1.724 -2.592)
				(xy -1.711 -2.584) (xy -1.71 -2.583) (xy -1.688 -2.574) (xy -1.668 -2.566) (xy -1.647 -2.562) (xy -1.623 -2.559)
				(xy -1.593 -2.558) (xy -1.565 -2.558) (xy -1.521 -2.559)
			)
			(stroke
				(width 0.01)
				(type solid)
			)
			(fill yes)
			(layer "B.Mask")
		)
		(fp_poly
			(pts
				(xy 0.035 -2.777) (xy 0.047 -2.822) (xy 0.059 -2.864) (xy 0.069 -2.903) (xy 0.078 -2.936) (xy 0.086 -2.963)
				(xy 0.092 -2.984) (xy 0.095 -2.996) (xy 0.096 -2.999) (xy 0.098 -2.999) (xy 0.103 -2.991) (xy 0.109 -2.975)
				(xy 0.118 -2.95) (xy 0.129 -2.917) (xy 0.143 -2.874) (xy 0.152 -2.849) (xy 0.165 -2.807) (xy 0.179 -2.766)
				(xy 0.192 -2.726) (xy 0.204 -2.689) (xy 0.214 -2.658) (xy 0.221 -2.634) (xy 0.224 -2.627) (xy 0.244 -2.565)
				(xy 0.338 -2.565) (xy 0.406 -2.774) (xy 0.42 -2.819) (xy 0.434 -2.861) (xy 0.446 -2.899) (xy 0.457 -2.932)
				(xy 0.466 -2.96) (xy 0.473 -2.981) (xy 0.477 -2.993) (xy 0.478 -2.997) (xy 0.48 -2.998) (xy 0.482 -2.996)
				(xy 0.485 -2.99) (xy 0.49 -2.978) (xy 0.495 -2.96) (xy 0.502 -2.936) (xy 0.511 -2.905) (xy 0.523 -2.865)
				(xy 0.536 -2.817) (xy 0.543 -2.789) (xy 0.556 -2.744) (xy 0.568 -2.701) (xy 0.578 -2.663) (xy 0.587 -2.629)
				(xy 0.595 -2.602) (xy 0.601 -2.582) (xy 0.605 -2.57) (xy 0.606 -2.567) (xy 0.611 -2.566) (xy 0.625 -2.566)
				(xy 0.645 -2.566) (xy 0.669 -2.566) (xy 0.673 -2.566) (xy 0.739 -2.567) (xy 0.656 -2.827) (xy 0.64 -2.878)
				(xy 0.624 -2.928) (xy 0.609 -2.976) (xy 0.595 -3.02) (xy 0.582 -3.06) (xy 0.571 -3.094) (xy 0.563 -3.121)
				(xy 0.557 -3.139) (xy 0.556 -3.143) (xy 0.538 -3.2) (xy 0.425 -3.197) (xy 0.358 -2.975) (xy 0.341 -2.917)
				(xy 0.327 -2.87) (xy 0.315 -2.831) (xy 0.305 -2.801) (xy 0.297 -2.78) (xy 0.292 -2.766) (xy 0.289 -2.761)
				(xy 0.288 -2.761) (xy 0.286 -2.768) (xy 0.281 -2.783) (xy 0.274 -2.806) (xy 0.265 -2.836) (xy 0.254 -2.871)
				(xy 0.242 -2.911) (xy 0.23 -2.953) (xy 0.223 -2.976) (xy 0.21 -3.02) (xy 0.197 -3.062) (xy 0.186 -3.099)
				(xy 0.177 -3.132) (xy 0.169 -3.158) (xy 0.163 -3.177) (xy 0.16 -3.189) (xy 0.159 -3.191) (xy 0.157 -3.195)
				(xy 0.151 -3.198) (xy 0.141 -3.199) (xy 0.124 -3.2) (xy 0.101 -3.2) (xy 0.073 -3.199) (xy 0.055 -3.198)
				(xy 0.045 -3.196) (xy 0.043 -3.194) (xy 0.041 -3.188) (xy 0.036 -3.173) (xy 0.029 -3.15) (xy 0.019 -3.121)
				(xy 0.008 -3.084) (xy -0.006 -3.043) (xy -0.02 -2.996) (xy -0.036 -2.946) (xy -0.053 -2.893) (xy -0.057 -2.883)
				(xy -0.074 -2.83) (xy -0.09 -2.779) (xy -0.105 -2.732) (xy -0.119 -2.689) (xy -0.131 -2.652) (xy -0.141 -2.621)
				(xy -0.148 -2.596) (xy -0.154 -2.58) (xy -0.156 -2.572) (xy -0.156 -2.569) (xy -0.151 -2.567) (xy -0.14 -2.566)
				(xy -0.123 -2.565) (xy -0.096 -2.565) (xy -0.091 -2.565) (xy -0.023 -2.565) (xy 0.035 -2.777)
			)
			(stroke
				(width 0.01)
				(type solid)
			)
			(fill yes)
			(layer "B.Mask")
		)
		(fp_poly
			(pts
				(xy -2.065 -1.559) (xy -2.024 -1.576) (xy -1.986 -1.601) (xy -1.973 -1.612) (xy -1.957 -1.63) (xy -1.943 -1.649)
				(xy -1.932 -1.668) (xy -1.924 -1.69) (xy -1.918 -1.716) (xy -1.914 -1.747) (xy -1.911 -1.785) (xy -1.91 -1.831)
				(xy -1.91 -1.877) (xy -1.91 -1.93) (xy -1.912 -1.974) (xy -1.914 -2.011) (xy -1.919 -2.041) (xy -1.925 -2.067)
				(xy -1.934 -2.088) (xy -1.945 -2.107) (xy -1.959 -2.125) (xy -1.972 -2.139) (xy -1.993 -2.157) (xy -2.018 -2.173)
				(xy -2.031 -2.18) (xy -2.047 -2.188) (xy -2.06 -2.192) (xy -2.074 -2.195) (xy -2.091 -2.196) (xy -2.114 -2.197)
				(xy -2.122 -2.197) (xy -2.147 -2.196) (xy -2.165 -2.195) (xy -2.179 -2.193) (xy -2.191 -2.189) (xy -2.205 -2.183)
				(xy -2.21 -2.18) (xy -2.231 -2.169) (xy -2.251 -2.156) (xy -2.265 -2.146) (xy -2.286 -2.127) (xy -2.286 -2.627)
				(xy -2.266 -2.608) (xy -2.248 -2.595) (xy -2.227 -2.582) (xy -2.217 -2.577) (xy -2.173 -2.562) (xy -2.129 -2.556)
				(xy -2.086 -2.559) (xy -2.045 -2.57) (xy -2.007 -2.589) (xy -1.974 -2.616) (xy -1.946 -2.648) (xy -1.926 -2.687)
				(xy -1.919 -2.707) (xy -1.917 -2.715) (xy -1.915 -2.724) (xy -1.914 -2.737) (xy -1.913 -2.753) (xy -1.912 -2.774)
				(xy -1.911 -2.8) (xy -1.911 -2.833) (xy -1.911 -2.874) (xy -1.911 -2.923) (xy -1.911 -2.967) (xy -1.911 -3.2)
				(xy -2.035 -3.197) (xy -2.038 -2.984) (xy -2.038 -2.932) (xy -2.039 -2.889) (xy -2.039 -2.854) (xy -2.04 -2.826)
				(xy -2.041 -2.805) (xy -2.042 -2.788) (xy -2.043 -2.776) (xy -2.045 -2.767) (xy -2.046 -2.76) (xy -2.049 -2.755)
				(xy -2.051 -2.75) (xy -2.072 -2.721) (xy -2.098 -2.701) (xy -2.128 -2.688) (xy -2.161 -2.683) (xy -2.195 -2.687)
				(xy -2.22 -2.697) (xy -2.24 -2.71) (xy -2.259 -2.729) (xy -2.274 -2.75) (xy -2.278 -2.757) (xy -2.28 -2.765)
				(xy -2.281 -2.781) (xy -2.283 -2.806) (xy -2.284 -2.839) (xy -2.285 -2.881) (xy -2.286 -2.933) (xy -2.286 -2.984)
				(xy -2.289 -3.197) (xy -2.413 -3.2) (xy -2.413 -1.877) (xy -2.286 -1.877) (xy -2.285 -1.926) (xy -2.281 -1.966)
				(xy -2.274 -1.998) (xy -2.262 -2.024) (xy -2.247 -2.043) (xy -2.228 -2.058) (xy -2.215 -2.064) (xy -2.194 -2.07)
				(xy -2.168 -2.072) (xy -2.141 -2.071) (xy -2.117 -2.066) (xy -2.106 -2.063) (xy -2.079 -2.044) (xy -2.058 -2.019)
				(xy -2.05 -2.001) (xy -2.045 -1.984) (xy -2.042 -1.959) (xy -2.04 -1.929) (xy -2.038 -1.895) (xy -2.038 -1.861)
				(xy -2.039 -1.829) (xy -2.041 -1.8) (xy -2.044 -1.777) (xy -2.045 -1.772) (xy -2.057 -1.738) (xy -2.073 -1.712)
				(xy -2.094 -1.695) (xy -2.122 -1.684) (xy -2.156 -1.681) (xy -2.159 -1.681) (xy -2.192 -1.683) (xy -2.22 -1.691)
				(xy -2.243 -1.705) (xy -2.26 -1.725) (xy -2.273 -1.753) (xy -2.281 -1.788) (xy -2.285 -1.832) (xy -2.286 -1.877)
				(xy -2.413 -1.877) (xy -2.413 -1.559) (xy -2.286 -1.559) (xy -2.286 -1.62) (xy -2.26 -1.6) (xy -2.225 -1.577)
				(xy -2.19 -1.563) (xy -2.154 -1.554) (xy -2.109 -1.552) (xy -2.065 -1.559)
			)
			(stroke
				(width 0.01)
				(type solid)
			)
			(fill yes)
			(layer "B.Mask")
		)
		(fp_poly
			(pts
				(xy 0.063 3.201) (xy 0.118 3.201) (xy 0.164 3.201) (xy 0.202 3.2) (xy 0.233 3.2) (xy 0.258 3.2)
				(xy 0.277 3.199) (xy 0.292 3.198) (xy 0.302 3.197) (xy 0.309 3.196) (xy 0.314 3.195) (xy 0.317 3.193)
				(xy 0.319 3.192) (xy 0.321 3.189) (xy 0.324 3.183) (xy 0.327 3.174) (xy 0.33 3.161) (xy 0.334 3.144)
				(xy 0.339 3.12) (xy 0.345 3.091) (xy 0.352 3.054) (xy 0.361 3.01) (xy 0.371 2.958) (xy 0.382 2.897)
				(xy 0.385 2.878) (xy 0.395 2.824) (xy 0.405 2.772) (xy 0.414 2.724) (xy 0.423 2.68) (xy 0.43 2.642)
				(xy 0.437 2.61) (xy 0.442 2.586) (xy 0.446 2.569) (xy 0.448 2.562) (xy 0.456 2.55) (xy 0.464 2.544)
				(xy 0.476 2.539) (xy 0.495 2.53) (xy 0.521 2.519) (xy 0.552 2.506) (xy 0.587 2.492) (xy 0.624 2.477)
				(xy 0.664 2.461) (xy 0.704 2.445) (xy 0.743 2.43) (xy 0.78 2.415) (xy 0.814 2.402) (xy 0.843 2.391)
				(xy 0.868 2.382) (xy 0.885 2.376) (xy 0.895 2.373) (xy 0.896 2.373) (xy 0.911 2.376) (xy 0.931 2.386)
				(xy 0.948 2.397) (xy 0.962 2.406) (xy 0.983 2.421) (xy 1.011 2.44) (xy 1.043 2.462) (xy 1.079 2.487)
				(xy 1.118 2.513) (xy 1.158 2.541) (xy 1.198 2.568) (xy 1.238 2.595) (xy 1.275 2.621) (xy 1.309 2.644)
				(xy 1.338 2.665) (xy 1.362 2.681) (xy 1.377 2.691) (xy 1.398 2.705) (xy 1.418 2.717) (xy 1.433 2.725)
				(xy 1.442 2.728) (xy 1.443 2.728) (xy 1.448 2.726) (xy 1.456 2.72) (xy 1.468 2.71) (xy 1.486 2.694)
				(xy 1.508 2.673) (xy 1.535 2.647) (xy 1.568 2.614) (xy 1.608 2.575) (xy 1.654 2.53) (xy 1.675 2.509)
				(xy 1.721 2.462) (xy 1.761 2.422) (xy 1.794 2.388) (xy 1.822 2.36) (xy 1.844 2.337) (xy 1.862 2.318)
				(xy 1.875 2.304) (xy 1.884 2.293) (xy 1.89 2.284) (xy 1.893 2.279) (xy 1.894 2.275) (xy 1.892 2.269)
				(xy 1.886 2.257) (xy 1.875 2.239) (xy 1.86 2.215) (xy 1.839 2.183) (xy 1.814 2.145) (xy 1.783 2.1)
				(xy 1.747 2.046) (xy 1.721 2.009) (xy 1.69 1.964) (xy 1.661 1.921) (xy 1.634 1.88) (xy 1.609 1.844)
				(xy 1.588 1.811) (xy 1.57 1.785) (xy 1.557 1.764) (xy 1.549 1.75) (xy 1.546 1.743) (xy 1.547 1.735)
				(xy 1.552 1.719) (xy 1.56 1.696) (xy 1.571 1.667) (xy 1.585 1.634) (xy 1.6 1.597) (xy 1.616 1.557)
				(xy 1.633 1.516) (xy 1.651 1.476) (xy 1.668 1.436) (xy 1.685 1.398) (xy 1.701 1.363) (xy 1.715 1.333)
				(xy 1.727 1.309) (xy 1.736 1.291) (xy 1.742 1.281) (xy 1.744 1.279) (xy 1.751 1.277) (xy 1.767 1.273)
				(xy 1.791 1.268) (xy 1.822 1.261) (xy 1.86 1.254) (xy 1.903 1.245) (xy 1.951 1.236) (xy 2.002 1.226)
				(xy 2.049 1.217) (xy 2.103 1.207) (xy 2.154 1.198) (xy 2.201 1.188) (xy 2.244 1.18) (xy 2.281 1.173)
				(xy 2.311 1.166) (xy 2.335 1.161) (xy 2.35 1.157) (xy 2.355 1.156) (xy 2.367 1.148) (xy 2.367 0.834)
				(xy 2.367 0.768) (xy 2.367 0.712) (xy 2.367 0.664) (xy 2.366 0.625) (xy 2.366 0.592) (xy 2.365 0.566)
				(xy 2.364 0.546) (xy 2.363 0.531) (xy 2.361 0.52) (xy 2.358 0.512) (xy 2.355 0.507) (xy 2.352 0.504)
				(xy 2.348 0.503) (xy 2.343 0.501) (xy 2.34 0.501) (xy 2.333 0.499) (xy 2.317 0.496) (xy 2.293 0.492)
				(xy 2.261 0.486) (xy 2.224 0.479) (xy 2.181 0.471) (xy 2.134 0.462) (xy 2.084 0.453) (xy 2.054 0.448)
				(xy 2.002 0.438) (xy 1.953 0.429) (xy 1.907 0.42) (xy 1.866 0.412) (xy 1.831 0.404) (xy 1.802 0.398)
				(xy 1.78 0.394) (xy 1.767 0.391) (xy 1.764 0.39) (xy 1.76 0.387) (xy 1.757 0.384) (xy 1.753 0.379)
				(xy 1.748 0.371) (xy 1.742 0.36) (xy 1.735 0.344) (xy 1.726 0.324) (xy 1.715 0.297) (xy 1.701 0.264)
				(xy 1.685 0.223) (xy 1.665 0.174) (xy 1.653 0.145) (xy 1.63 0.086) (xy 1.61 0.037) (xy 1.594 -0.005)
				(xy 1.582 -0.038) (xy 1.572 -0.064) (xy 1.566 -0.084) (xy 1.562 -0.097) (xy 1.561 -0.104) (xy 1.562 -0.105)
				(xy 1.565 -0.111) (xy 1.574 -0.125) (xy 1.587 -0.146) (xy 1.604 -0.173) (xy 1.626 -0.205) (xy 1.65 -0.241)
				(xy 1.677 -0.281) (xy 1.706 -0.324) (xy 1.729 -0.358) (xy 1.768 -0.413) (xy 1.8 -0.461) (xy 1.827 -0.502)
				(xy 1.85 -0.535) (xy 1.867 -0.562) (xy 1.88 -0.583) (xy 1.889 -0.598) (xy 1.893 -0.608) (xy 1.894 -0.612)
				(xy 1.893 -0.616) (xy 1.89 -0.622) (xy 1.885 -0.63) (xy 1.876 -0.64) (xy 1.863 -0.655) (xy 1.846 -0.673)
				(xy 1.825 -0.695) (xy 1.798 -0.723) (xy 1.765 -0.756) (xy 1.727 -0.795) (xy 1.682 -0.839) (xy 1.635 -0.886)
				(xy 1.595 -0.926) (xy 1.561 -0.96) (xy 1.532 -0.989) (xy 1.508 -1.012) (xy 1.488 -1.03) (xy 1.473 -1.044)
				(xy 1.461 -1.054) (xy 1.452 -1.061) (xy 1.445 -1.065) (xy 1.44 -1.066) (xy 1.438 -1.066) (xy 1.433 -1.064)
				(xy 1.421 -1.055) (xy 1.401 -1.043) (xy 1.376 -1.026) (xy 1.345 -1.005) (xy 1.31 -0.981) (xy 1.27 -0.954)
				(xy 1.228 -0.925) (xy 1.193 -0.901) (xy 1.138 -0.864) (xy 1.089 -0.83) (xy 1.046 -0.802) (xy 1.01 -0.778)
				(xy 0.981 -0.759) (xy 0.96 -0.746) (xy 0.946 -0.738) (xy 0.94 -0.736) (xy 0.932 -0.738) (xy 0.917 -0.745)
				(xy 0.895 -0.755) (xy 0.869 -0.768) (xy 0.84 -0.783) (xy 0.816 -0.795) (xy 0.781 -0.814) (xy 0.753 -0.828)
				(xy 0.732 -0.838) (xy 0.717 -0.845) (xy 0.707 -0.849) (xy 0.699 -0.85) (xy 0.694 -0.849) (xy 0.691 -0.847)
				(xy 0.687 -0.84) (xy 0.682 -0.829) (xy 0.674 -0.814) (xy 0.665 -0.793) (xy 0.653 -0.767) (xy 0.639 -0.735)
				(xy 0.623 -0.696) (xy 0.604 -0.651) (xy 0.582 -0.598) (xy 0.556 -0.538) (xy 0.528 -0.469) (xy 0.496 -0.391)
				(xy 0.47 -0.329) (xy 0.436 -0.247) (xy 0.406 -0.173) (xy 0.379 -0.108) (xy 0.355 -0.05) (xy 0.335 0)
				(xy 0.317 0.043) (xy 0.303 0.079) (xy 0.291 0.11) (xy 0.281 0.135) (xy 0.273 0.155) (xy 0.268 0.171)
				(xy 0.264 0.183) (xy 0.262 0.191) (xy 0.262 0.196) (xy 0.262 0.198) (xy 0.269 0.207) (xy 0.283 0.219)
				(xy 0.302 0.233) (xy 0.303 0.234) (xy 0.354 0.268) (xy 0.398 0.3) (xy 0.435 0.331) (xy 0.469 0.363)
				(xy 0.5 0.397) (xy 0.507 0.405) (xy 0.556 0.472) (xy 0.596 0.543) (xy 0.627 0.619) (xy 0.643 0.672)
				(xy 0.651 0.718) (xy 0.657 0.77) (xy 0.66 0.824) (xy 0.659 0.878) (xy 0.654 0.927) (xy 0.652 0.936)
				(xy 0.634 1.015) (xy 0.607 1.09) (xy 0.571 1.161) (xy 0.528 1.227) (xy 0.477 1.287) (xy 0.419 1.341)
				(xy 0.355 1.387) (xy 0.285 1.426) (xy 0.21 1.456) (xy 0.205 1.458) (xy 0.131 1.477) (xy 0.054 1.487)
				(xy -0.025 1.489) (xy -0.103 1.482) (xy -0.178 1.466) (xy -0.206 1.458) (xy -0.281 1.428) (xy -0.351 1.39)
				(xy -0.416 1.344) (xy -0.474 1.29) (xy -0.526 1.23) (xy -0.571 1.164) (xy -0.607 1.093) (xy -0.63 1.034)
				(xy -0.649 0.96) (xy -0.659 0.883) (xy -0.661 0.804) (xy -0.654 0.726) (xy -0.638 0.651) (xy -0.63 0.623)
				(xy -0.618 0.591) (xy -0.602 0.554) (xy -0.584 0.518) (xy -0.566 0.485) (xy -0.553 0.463) (xy -0.509 0.407)
				(xy -0.457 0.352) (xy -0.397 0.299) (xy -0.33 0.25) (xy -0.289 0.224) (xy -0.273 0.212) (xy -0.263 0.2)
				(xy -0.262 0.197) (xy -0.263 0.19) (xy -0.268 0.175) (xy -0.277 0.151) (xy -0.288 0.121) (xy -0.302 0.084)
				(xy -0.319 0.042) (xy -0.338 -0.005) (xy -0.358 -0.056) (xy -0.381 -0.111) (xy -0.404 -0.168) (xy -0.428 -0.228)
				(xy -0.453 -0.288) (xy -0.478 -0.349) (xy -0.504 -0.41) (xy -0.529 -0.47) (xy -0.553 -0.527) (xy -0.576 -0.583)
				(xy -0.598 -0.635) (xy -0.619 -0.683) (xy -0.638 -0.727) (xy -0.655 -0.765) (xy -0.669 -0.797) (xy -0.68 -0.822)
				(xy -0.689 -0.839) (xy -0.694 -0.848) (xy -0.695 -0.849) (xy -0.699 -0.85) (xy -0.706 -0.849) (xy -0.717 -0.845)
				(xy -0.732 -0.839) (xy -0.752 -0.829) (xy -0.779 -0.815) (xy -0.814 -0.797) (xy -0.817 -0.795) (xy -0.848 -0.779)
				(xy -0.877 -0.764) (xy -0.902 -0.752) (xy -0.922 -0.743) (xy -0.936 -0.737) (xy -0.941 -0.736) (xy -0.949 -0.739)
				(xy -0.964 -0.748) (xy -0.987 -0.761) (xy -1.015 -0.78) (xy -1.05 -0.803) (xy -1.072 -0.818) (xy -1.138 -0.863)
				(xy -1.195 -0.903) (xy -1.245 -0.937) (xy -1.289 -0.966) (xy -1.325 -0.991) (xy -1.356 -1.012) (xy -1.381 -1.029)
				(xy -1.401 -1.042) (xy -1.416 -1.052) (xy -1.427 -1.059) (xy -1.435 -1.064) (xy -1.439 -1.066) (xy -1.44 -1.066)
				(xy -1.449 -1.064) (xy -1.453 -1.061) (xy -1.458 -1.057) (xy -1.47 -1.046) (xy -1.487 -1.029) (xy -1.509 -1.007)
				(xy -1.537 -0.98) (xy -1.568 -0.95) (xy -1.602 -0.915) (xy -1.639 -0.879) (xy -1.678 -0.84) (xy -1.678 -0.839)
				(xy -1.726 -0.792) (xy -1.767 -0.751) (xy -1.801 -0.716) (xy -1.829 -0.687) (xy -1.852 -0.663) (xy -1.869 -0.644)
				(xy -1.882 -0.63) (xy -1.89 -0.62) (xy -1.894 -0.613) (xy -1.895 -0.61) (xy -1.892 -0.603) (xy -1.884 -0.588)
				(xy -1.87 -0.565) (xy -1.85 -0.536) (xy -1.826 -0.499) (xy -1.797 -0.455) (xy -1.763 -0.405) (xy -1.73 -0.358)
				(xy -1.7 -0.313) (xy -1.671 -0.271) (xy -1.645 -0.232) (xy -1.621 -0.197) (xy -1.601 -0.166) (xy -1.584 -0.141)
				(xy -1.572 -0.121) (xy -1.565 -0.109) (xy -1.563 -0.105) (xy -1.563 -0.099) (xy -1.566 -0.087) (xy -1.572 -0.07)
				(xy -1.58 -0.045) (xy -1.592 -0.013) (xy -1.607 0.026) (xy -1.626 0.074) (xy -1.648 0.13) (xy -1.654 0.145)
				(xy -1.676 0.199) (xy -1.695 0.245) (xy -1.71 0.282) (xy -1.723 0.313) (xy -1.733 0.337) (xy -1.741 0.356)
				(xy -1.748 0.369) (xy -1.753 0.379) (xy -1.758 0.385) (xy -1.761 0.388) (xy -1.763 0.389) (xy -1.767 0.39)
				(xy -1.774 0.392) (xy -1.784 0.395) (xy -1.799 0.398) (xy -1.818 0.402) (xy -1.843 0.407) (xy -1.873 0.413)
				(xy -1.91 0.42) (xy -1.954 0.429) (xy -2.005 0.438) (xy -2.065 0.449) (xy -2.133 0.462) (xy -2.211 0.477)
				(xy -2.22 0.478) (xy -2.26 0.486) (xy -2.29 0.491) (xy -2.313 0.496) (xy -2.33 0.499) (xy -2.341 0.502)
				(xy -2.349 0.504) (xy -2.353 0.506) (xy -2.356 0.508) (xy -2.359 0.51) (xy -2.36 0.511) (xy -2.361 0.514)
				(xy -2.363 0.518) (xy -2.364 0.526) (xy -2.365 0.536) (xy -2.366 0.551) (xy -2.366 0.571) (xy -2.367 0.597)
				(xy -2.367 0.629) (xy -2.368 0.668) (xy -2.368 0.715) (xy -2.368 0.771) (xy -2.368 0.834) (xy -2.368 1.148)
				(xy -2.356 1.155) (xy -2.349 1.158) (xy -2.333 1.162) (xy -2.309 1.167) (xy -2.278 1.173) (xy -2.24 1.181)
				(xy -2.197 1.189) (xy -2.149 1.198) (xy -2.098 1.208) (xy -2.051 1.217) (xy -1.996 1.227) (xy -1.945 1.237)
				(xy -1.897 1.246) (xy -1.854 1.254) (xy -1.817 1.262) (xy -1.787 1.268) (xy -1.764 1.273) (xy -1.75 1.277)
				(xy -1.745 1.279) (xy -1.741 1.285) (xy -1.733 1.3) (xy -1.722 1.322) (xy -1.709 1.35) (xy -1.694 1.382)
				(xy -1.677 1.419) (xy -1.66 1.458) (xy -1.642 1.498) (xy -1.625 1.539) (xy -1.608 1.58) (xy -1.592 1.618)
				(xy -1.578 1.653) (xy -1.565 1.684) (xy -1.556 1.709) (xy -1.549 1.729) (xy -1.546 1.74) (xy -1.546 1.742)
				(xy -1.549 1.749) (xy -1.558 1.763) (xy -1.571 1.784) (xy -1.588 1.811) (xy -1.61 1.843) (xy -1.634 1.88)
				(xy -1.661 1.92) (xy -1.691 1.963) (xy -1.722 2.008) (xy -1.762 2.067) (xy -1.796 2.117) (xy -1.825 2.16)
				(xy -1.848 2.196) (xy -1.867 2.225) (xy -1.881 2.247) (xy -1.89 2.262) (xy -1.895 2.272) (xy -1.895 2.275)
				(xy -1.894 2.279) (xy -1.891 2.285) (xy -1.884 2.293) (xy -1.875 2.305) (xy -1.861 2.32) (xy -1.843 2.339)
				(xy -1.82 2.363) (xy -1.792 2.392) (xy -1.758 2.426) (xy -1.718 2.466) (xy -1.676 2.509) (xy -1.627 2.557)
				(xy -1.585 2.599) (xy -1.549 2.634) (xy -1.52 2.663) (xy -1.495 2.686) (xy -1.476 2.704) (xy -1.462 2.716)
				(xy -1.452 2.724) (xy -1.446 2.728) (xy -1.444 2.728) (xy -1.437 2.726) (xy -1.423 2.717) (xy -1.401 2.703)
				(xy -1.372 2.685) (xy -1.337 2.661) (xy -1.295 2.634) (xy -1.248 2.602) (xy -1.196 2.566) (xy -1.173 2.551)
				(xy -1.118 2.513) (xy -1.071 2.481) (xy -1.031 2.454) (xy -0.998 2.432) (xy -0.97 2.413) (xy -0.948 2.399)
				(xy -0.931 2.389) (xy -0.917 2.381) (xy -0.907 2.376) (xy -0.901 2.373) (xy -0.897 2.373) (xy -0.888 2.375)
				(xy -0.87 2.38) (xy -0.845 2.39) (xy -0.813 2.402) (xy -0.774 2.417) (xy -0.73 2.434) (xy -0.681 2.454)
				(xy -0.629 2.475) (xy -0.586 2.493) (xy -0.55 2.508) (xy -0.522 2.52) (xy -0.499 2.529) (xy -0.482 2.537)
				(xy -0.47 2.543) (xy -0.461 2.548) (xy -0.455 2.551) (xy -0.452 2.554) (xy -0.449 2.557) (xy -0.448 2.56)
				(xy -0.447 2.566) (xy -0.443 2.582) (xy -0.438 2.605) (xy -0.432 2.637) (xy -0.425 2.674) (xy -0.417 2.717)
				(xy -0.407 2.765) (xy -0.398 2.817) (xy -0.388 2.871) (xy -0.387 2.876) (xy -0.375 2.94) (xy -0.364 2.995)
				(xy -0.356 3.042) (xy -0.348 3.081) (xy -0.342 3.112) (xy -0.337 3.137) (xy -0.332 3.157) (xy -0.328 3.171)
				(xy -0.325 3.181) (xy -0.323 3.188) (xy -0.32 3.191) (xy -0.32 3.192) (xy -0.317 3.194) (xy -0.313 3.195)
				(xy -0.307 3.197) (xy -0.298 3.198) (xy -0.286 3.199) (xy -0.269 3.199) (xy -0.247 3.2) (xy -0.219 3.2)
				(xy -0.184 3.201) (xy -0.142 3.201) (xy -0.092 3.201) (xy -0.033 3.201) (xy -0.001 3.201) (xy 0.063 3.201)
			)
			(stroke
				(width 0.01)
				(type solid)
			)
			(fill yes)
			(layer "B.Mask")
		)
	)
	(footprint "antmicro-footprints:Conn_JST_SH_1x4_SM04B-SRSS-TB-LF-SN"
		(layer "B.Cu")
		(at 207.2 117.6 -90)
		(property "Reference" "J3"
			(at 0 3.7 90)
			(layer "B.SilkS")
			(effects
				(font
					(size 0.7 0.7)
					(thickness 0.15)
				)
				(justify left bottom mirror)
			)
		)
		(property "Value" "JST_SH_1x4_SM04B-SRSS-TB-LF-SN"
			(at 0 -3.9 90)
			(layer "B.Fab")
			(effects
				(font
					(size 0.7 0.7)
					(thickness 0.15)
				)
				(justify left bottom mirror)
			)
		)
		(property "Description" "Pin Header, Right Angle, Wire-to-Board, 1 mm, 1 Rows, 4 Contacts, Surface Mount Right Angle, SH"
			(at 0 0 270)
			(layer "F.Fab")
			(hide yes)
			(effects
				(font
					(size 1.27 1.27)
					(thickness 0.15)
				)
			)
		)
		(property "Author" "Antmicro"
			(at 89.6 324.8 0)
			(layer "B.Fab")
			(hide yes)
			(effects
				(font
					(size 1 1)
					(thickness 0.15)
				)
				(justify mirror)
			)
		)
		(property "License" "Apache-2.0"
			(at 89.6 324.8 0)
			(layer "B.Fab")
			(hide yes)
			(effects
				(font
					(size 1 1)
					(thickness 0.15)
				)
				(justify mirror)
			)
		)
		(property "MPN" "SM04B-SRSS-TB(LF)(SN)"
			(at 89.6 324.8 0)
			(layer "B.Fab")
			(hide yes)
			(effects
				(font
					(size 1 1)
					(thickness 0.15)
				)
				(justify mirror)
			)
		)
		(property "Manufacturer" "JST Automotive Connectors"
			(at 89.6 324.8 0)
			(layer "B.Fab")
			(hide yes)
			(effects
				(font
					(size 1 1)
					(thickness 0.15)
				)
				(justify mirror)
			)
		)
		(sheetfile "environment-sensor.kicad_sch")
		(attr smd)
		(fp_line
			(start -3.2 2)
			(end -3.2 -0.6)
			(stroke
				(width 0.15)
				(type solid)
			)
			(layer "B.SilkS")
		)
		(fp_line
			(start -2 2)
			(end -3.2 2)
			(stroke
				(width 0.15)
				(type solid)
			)
			(layer "B.SilkS")
		)
		(fp_line
			(start 2 2)
			(end 3.2 2)
			(stroke
				(width 0.15)
				(type solid)
			)
			(layer "B.SilkS")
		)
		(fp_line
			(start 3.2 2)
			(end 3.2 -0.6)
			(stroke
				(width 0.15)
				(type solid)
			)
			(layer "B.SilkS")
		)
		(fp_line
			(start -2 -2.6)
			(end 2 -2.6)
			(stroke
				(width 0.15)
				(type solid)
			)
			(layer "B.SilkS")
		)
		(fp_circle
			(center -2.1 2.5)
			(end -2.05 2.5)
			(stroke
				(width 0.15)
				(type solid)
			)
			(fill yes)
			(layer "B.SilkS")
		)
		(fp_rect
			(start -3.65 3.14)
			(end 3.65 -2.9)
			(stroke
				(width 0.05)
				(type solid)
			)
			(fill no)
			(layer "B.CrtYd")
		)
		(fp_rect
			(start -3 2.475)
			(end 3 -2.475)
			(stroke
				(width 0.15)
				(type solid)
			)
			(fill no)
			(layer "B.Fab")
		)
		(pad "1" smd roundrect
			(at -1.5 2.12 90)
			(size 0.6 1.55)
			(layers "B.Cu" "B.Mask" "B.Paste")
			(roundrect_rratio 0.25)
			(net 1 "GND")
			(pintype "passive")
		)
		(pad "2" smd roundrect
			(at -0.5 2.12 90)
			(size 0.6 1.55)
			(layers "B.Cu" "B.Mask" "B.Paste")
			(roundrect_rratio 0.25)
			(net 2 "+3V3")
			(pintype "passive")
		)
		(pad "3" smd roundrect
			(at 0.5 2.12 90)
			(size 0.6 1.55)
			(layers "B.Cu" "B.Mask" "B.Paste")
			(roundrect_rratio 0.25)
			(net 9 "I2C_1_SDA")
			(pintype "passive")
		)
		(pad "4" smd roundrect
			(at 1.5 2.12 90)
			(size 0.6 1.55)
			(layers "B.Cu" "B.Mask" "B.Paste")
			(roundrect_rratio 0.25)
			(net 8 "I2C_1_SCL")
			(pintype "passive")
		)
		(pad "MP" smd roundrect
			(at -2.8 -1.755 270)
			(size 1.2 1.8)
			(layers "B.Cu" "B.Mask" "B.Paste")
			(roundrect_rratio 0.25)
			(net 89 "unconnected-(J3-PadMP)")
			(pintype "passive+no_connect")
		)
		(pad "MP" smd roundrect
			(at 2.8 -1.755 270)
			(size 1.2 1.8)
			(layers "B.Cu" "B.Mask" "B.Paste")
			(roundrect_rratio 0.25)
			(net 89 "unconnected-(J3-PadMP)")
			(pintype "passive+no_connect")
		)
	)
	(footprint "antmicro-footprints:BAT_BAT-HLD-012-SMT-TR"
		(layer "B.Cu")
		(at 176.4 133 180)
		(descr "Linx Technologies Battery Holder, CR1216/1225, Surface Mount, from SnapEDA: https://www.snapeda.com/parts/BAT-HLD-012-SMT-TR/Linx/view-part/?ref=search&t=BAT-HLD-012-SMT-TR")
		(tags "battery holder retainer cr1216 cr1225 smt lithium ")
		(property "Reference" "BAT1"
			(at 6.8 -5.8 180)
			(layer "B.SilkS")
			(effects
				(font
					(size 0.65 0.65)
					(thickness 0.15)
				)
				(justify mirror)
			)
		)
		(property "Value" "BAT-HLD-012-SMT-TR"
			(at 12.858 -6.589 0)
			(layer "B.Fab")
			(effects
				(font
					(size 1.4 1.4)
					(thickness 0.15)
				)
				(justify mirror)
			)
		)
		(property "Description" "BATTERY HOLDER, CR1216/1225, SMT"
			(at 0 0 180)
			(layer "F.Fab")
			(hide yes)
			(effects
				(font
					(size 1.27 1.27)
					(thickness 0.15)
				)
			)
		)
		(property "Author" "Antmicro"
			(at 352.8 266 0)
			(layer "B.Fab")
			(hide yes)
			(effects
				(font
					(size 1 1)
					(thickness 0.15)
				)
				(justify mirror)
			)
		)
		(property "License" "Apache-2.0"
			(at 352.8 266 0)
			(layer "B.Fab")
			(hide yes)
			(effects
				(font
					(size 1 1)
					(thickness 0.15)
				)
				(justify mirror)
			)
		)
		(property "MPN" "BAT-HLD-012-SMT-TR"
			(at 352.8 266 0)
			(layer "B.Fab")
			(hide yes)
			(effects
				(font
					(size 1 1)
					(thickness 0.15)
				)
				(justify mirror)
			)
		)
		(property "Manufacturer" "Linx Technologies"
			(at 352.8 266 0)
			(layer "B.Fab")
			(hide yes)
			(effects
				(font
					(size 1 1)
					(thickness 0.15)
				)
				(justify mirror)
			)
		)
		(sheetfile "environment-sensor.kicad_sch")
		(attr smd)
		(fp_line
			(start 6.749 4.55)
			(end 6.749 2.92)
			(stroke
				(width 0.15)
				(type solid)
			)
			(layer "B.SilkS")
		)
		(fp_line
			(start 6.749 -4.95)
			(end 6.749 -2.818)
			(stroke
				(width 0.15)
				(type solid)
			)
			(layer "B.SilkS")
		)
		(fp_line
			(start 5.499 -4.95)
			(end 6.749 -4.95)
			(stroke
				(width 0.15)
				(type solid)
			)
			(layer "B.SilkS")
		)
		(fp_line
			(start 3.249 4.55)
			(end 6.749 4.55)
			(stroke
				(width 0.15)
				(type solid)
			)
			(layer "B.SilkS")
		)
		(fp_line
			(start -6.75 4.55)
			(end -3.25 4.55)
			(stroke
				(width 0.15)
				(type solid)
			)
			(layer "B.SilkS")
		)
		(fp_line
			(start -6.75 2.92)
			(end -6.75 4.55)
			(stroke
				(width 0.15)
				(type solid)
			)
			(layer "B.SilkS")
		)
		(fp_line
			(start -6.75 -2.818)
			(end -6.75 -4.95)
			(stroke
				(width 0.15)
				(type solid)
			)
			(layer "B.SilkS")
		)
		(fp_line
			(start -6.75 -4.95)
			(end -5.5 -4.95)
			(stroke
				(width 0.15)
				(type solid)
			)
			(layer "B.SilkS")
		)
		(fp_rect
			(start -9.17 5.549)
			(end 9.168 -5.548)
			(stroke
				(width 0.05)
				(type solid)
			)
			(fill no)
			(layer "B.CrtYd")
		)
		(fp_line
			(start 6.749 4.55)
			(end 6.749 -4.95)
			(stroke
				(width 0.15)
				(type solid)
			)
			(layer "B.Fab")
		)
		(fp_line
			(start 6.749 -4.95)
			(end 5.499 -4.95)
			(stroke
				(width 0.15)
				(type solid)
			)
			(layer "B.Fab")
		)
		(fp_line
			(start -5.25 4.55)
			(end 6.749 4.55)
			(stroke
				(width 0.15)
				(type solid)
			)
			(layer "B.Fab")
		)
		(fp_line
			(start -5.5 -4.95)
			(end -6.75 -4.95)
			(stroke
				(width 0.15)
				(type solid)
			)
			(layer "B.Fab")
		)
		(fp_line
			(start -6.75 2.9)
			(end -5.25 4.55)
			(stroke
				(width 0.15)
				(type solid)
			)
			(layer "B.Fab")
		)
		(fp_line
			(start -6.75 -4.95)
			(end -6.75 2.9)
			(stroke
				(width 0.15)
				(type solid)
			)
			(layer "B.Fab")
		)
		(fp_arc
			(start 5.499 -4.95)
			(mid 2.917754 -3.500268)
			(end 0 -2.999)
			(stroke
				(width 0.15)
				(type solid)
			)
			(layer "B.Fab")
		)
		(fp_arc
			(start 0 -2.999)
			(mid -2.918394 -3.499785)
			(end -5.5 -4.95)
			(stroke
				(width 0.15)
				(type solid)
			)
			(layer "B.Fab")
		)
		(pad "N" smd circle
			(at 0 0 180)
			(size 10.2 10.2)
			(layers "B.Cu" "B.Mask")
			(net 1 "GND")
			(pintype "power_out")
		)
		(pad "P1" smd rect
			(at -7.651 0.052 180)
			(size 2.5 5.1)
			(layers "B.Cu" "B.Mask" "B.Paste")
			(net 28 "Net-(U3-VBAT)")
			(pintype "power_out")
		)
		(pad "P2" smd rect
			(at 7.65 0.052 180)
			(size 2.5 5.1)
			(layers "B.Cu" "B.Mask" "B.Paste")
			(net 28 "Net-(U3-VBAT)")
			(pintype "passive")
		)
	)
	(footprint "antmicro-footprints:antmicro-logo_scaled_12mm"
		(layer "B.Cu")
		(at 170 120.2 -90)
		(property "Reference" "N1"
			(at 0 1.5 90)
			(layer "B.SilkS")
			(hide yes)
			(effects
				(font
					(size 0.7 0.7)
					(thickness 0.15)
				)
				(justify left bottom mirror)
			)
		)
		(property "Value" "antmicro_logo"
			(at 0 -2 90)
			(layer "B.SilkS")
			(hide yes)
			(effects
				(font
					(size 0.7 0.7)
					(thickness 0.15)
				)
				(justify left bottom mirror)
			)
		)
		(property "Description" "Mechanical part"
			(at 0 0 270)
			(layer "F.Fab")
			(hide yes)
			(effects
				(font
					(size 1.27 1.27)
					(thickness 0.15)
				)
			)
		)
		(property "Author" "Antmicro"
			(at 49.8 290.2 0)
			(layer "B.Fab")
			(hide yes)
			(effects
				(font
					(size 1 1)
					(thickness 0.15)
				)
				(justify mirror)
			)
		)
		(property "License" "Apache-2.0"
			(at 49.8 290.2 0)
			(layer "B.Fab")
			(hide yes)
			(effects
				(font
					(size 1 1)
					(thickness 0.15)
				)
				(justify mirror)
			)
		)
		(property "MPN" ""
			(at 49.8 290.2 0)
			(layer "B.Fab")
			(hide yes)
			(effects
				(font
					(size 1 1)
					(thickness 0.15)
				)
				(justify mirror)
			)
		)
		(property "Manufacturer" ""
			(at 49.8 290.2 0)
			(layer "B.Fab")
			(hide yes)
			(effects
				(font
					(size 1 1)
					(thickness 0.15)
				)
				(justify mirror)
			)
		)
		(property "Public" "False"
			(at 49.8 290.2 0)
			(layer "B.Fab")
			(hide yes)
			(effects
				(font
					(size 1 1)
					(thickness 0.15)
				)
				(justify mirror)
			)
		)
		(sheetfile "environment-sensor.kicad_sch")
		(attr exclude_from_bom allow_soldermask_bridges)
		(fp_line
			(start -4.231 0.492)
			(end -4.231 -0.496)
			(stroke
				(width 0.13)
				(type solid)
			)
			(layer "B.Cu")
		)
		(fp_line
			(start -4.46 0.241)
			(end -4.587 0.368)
			(stroke
				(width 0.13)
				(type solid)
			)
			(layer "B.Cu")
		)
		(fp_line
			(start -4.46 0.241)
			(end -4.231 0.241)
			(stroke
				(width 0.13)
				(type solid)
			)
			(layer "B.Cu")
		)
		(fp_line
			(start -4.002 0.241)
			(end -3.875 0.368)
			(stroke
				(width 0.13)
				(type solid)
			)
			(layer "B.Cu")
		)
		(fp_line
			(start -4.002 0.241)
			(end -4.231 0.241)
			(stroke
				(width 0.13)
				(type solid)
			)
			(layer "B.Cu")
		)
		(fp_line
			(start -4.625 0.002)
			(end -4.269 0.002)
			(stroke
				(width 0.13)
				(type solid)
			)
			(layer "B.Cu")
		)
		(fp_line
			(start -3.837 0)
			(end -4.193 0)
			(stroke
				(width 0.13)
				(type solid)
			)
			(layer "B.Cu")
		)
		(fp_line
			(start -4.46 -0.216)
			(end -4.231 -0.216)
			(stroke
				(width 0.13)
				(type solid)
			)
			(layer "B.Cu")
		)
		(fp_line
			(start -4.46 -0.216)
			(end -4.587 -0.343)
			(stroke
				(width 0.13)
				(type solid)
			)
			(layer "B.Cu")
		)
		(fp_line
			(start -4.002 -0.216)
			(end -4.231 -0.216)
			(stroke
				(width 0.13)
				(type solid)
			)
			(layer "B.Cu")
		)
		(fp_line
			(start -4.002 -0.216)
			(end -3.875 -0.343)
			(stroke
				(width 0.13)
				(type solid)
			)
			(layer "B.Cu")
		)
		(fp_circle
			(center -4.231 0.609)
			(end -4.114 0.609)
			(stroke
				(width 0.13)
				(type solid)
			)
			(fill no)
			(layer "B.Cu")
		)
		(fp_circle
			(center -4.65 0.444)
			(end -4.561 0.444)
			(stroke
				(width 0.13)
				(type solid)
			)
			(fill no)
			(layer "B.Cu")
		)
		(fp_circle
			(center -3.812 0.444)
			(end -3.723 0.444)
			(stroke
				(width 0.13)
				(type solid)
			)
			(fill no)
			(layer "B.Cu")
		)
		(fp_circle
			(center -4.714 0.002)
			(end -4.625 0.002)
			(stroke
				(width 0.13)
				(type solid)
			)
			(fill no)
			(layer "B.Cu")
		)
		(fp_circle
			(center -3.749 0)
			(end -3.66 0)
			(stroke
				(width 0.13)
				(type solid)
			)
			(fill no)
			(layer "B.Cu")
		)
		(fp_circle
			(center -4.65 -0.419)
			(end -4.561 -0.419)
			(stroke
				(width 0.13)
				(type solid)
			)
			(fill no)
			(layer "B.Cu")
		)
		(fp_circle
			(center -3.812 -0.419)
			(end -3.723 -0.419)
			(stroke
				(width 0.13)
				(type solid)
			)
			(fill no)
			(layer "B.Cu")
		)
		(fp_circle
			(center -4.231 -0.607)
			(end -4.114 -0.607)
			(stroke
				(width 0.13)
				(type solid)
			)
			(fill no)
			(layer "B.Cu")
		)
		(fp_poly
			(pts
				(xy 3.132 -0.649) (xy 2.878 -0.649) (xy 2.878 0.678) (xy 3.132 0.678) (xy 3.132 -0.649)
			)
			(stroke
				(width 0.01)
				(type solid)
			)
			(fill yes)
			(layer "B.Cu")
		)
		(fp_poly
			(pts
				(xy 4.835 0.699) (xy 4.878 0.681) (xy 4.882 0.671) (xy 4.866 0.57) (xy 4.82 0.518) (xy 4.772 0.51)
				(xy 4.684 0.512) (xy 4.621 0.511) (xy 4.543 0.508) (xy 4.543 -0.649) (xy 4.289 -0.649) (xy 4.289 0.619)
				(xy 4.436 0.663) (xy 4.543 0.687) (xy 4.654 0.702) (xy 4.756 0.706) (xy 4.835 0.699)
			)
			(stroke
				(width 0.01)
				(type solid)
			)
			(fill yes)
			(layer "B.Cu")
		)
		(fp_poly
			(pts
				(xy -0.341 0.69) (xy -0.208 0.652) (xy -0.207 0.651) (xy -0.141 0.618) (xy -0.091 0.58) (xy -0.055 0.53)
				(xy -0.029 0.46) (xy -0.013 0.363) (xy -0.005 0.23) (xy -0.001 0.054) (xy 0 -0.111) (xy 0 -0.649)
				(xy -0.254 -0.649) (xy -0.254 -0.133) (xy -0.256 0.07) (xy -0.26 0.225) (xy -0.27 0.337) (xy -0.286 0.415)
				(xy -0.312 0.466) (xy -0.349 0.497) (xy -0.399 0.517) (xy -0.424 0.523) (xy -0.51 0.53) (xy -0.609 0.524)
				(xy -0.622 0.523) (xy -0.734 0.504) (xy -0.734 -0.649) (xy -0.988 -0.649) (xy -0.988 0.619) (xy -0.842 0.663)
				(xy -0.678 0.696) (xy -0.504 0.705) (xy -0.341 0.69)
			)
			(stroke
				(width 0.01)
				(type solid)
			)
			(fill yes)
			(layer "B.Cu")
		)
		(fp_poly
			(pts
				(xy 3.995 0.682) (xy 4.079 0.647) (xy 4.112 0.594) (xy 4.099 0.526) (xy 4.075 0.484) (xy 4.044 0.471)
				(xy 3.987 0.485) (xy 3.96 0.494) (xy 3.871 0.516) (xy 3.799 0.508) (xy 3.77 0.498) (xy 3.681 0.446)
				(xy 3.62 0.369) (xy 3.582 0.259) (xy 3.562 0.104) (xy 3.561 0.086) (xy 3.564 -0.106) (xy 3.594 -0.264)
				(xy 3.65 -0.381) (xy 3.705 -0.437) (xy 3.791 -0.47) (xy 3.897 -0.477) (xy 3.994 -0.457) (xy 4.008 -0.451)
				(xy 4.056 -0.439) (xy 4.09 -0.476) (xy 4.091 -0.477) (xy 4.118 -0.556) (xy 4.096 -0.61) (xy 4.031 -0.646)
				(xy 3.943 -0.665) (xy 3.832 -0.674) (xy 3.724 -0.671) (xy 3.643 -0.658) (xy 3.64 -0.656) (xy 3.516 -0.581)
				(xy 3.412 -0.461) (xy 3.369 -0.383) (xy 3.334 -0.298) (xy 3.314 -0.211) (xy 3.304 -0.105) (xy 3.302 0.018)
				(xy 3.304 0.149) (xy 3.312 0.243) (xy 3.331 0.318) (xy 3.364 0.394) (xy 3.381 0.428) (xy 3.472 0.565)
				(xy 3.582 0.652) (xy 3.718 0.694) (xy 3.859 0.699) (xy 3.995 0.682)
			)
			(stroke
				(width 0.01)
				(type solid)
			)
			(fill yes)
			(layer "B.Cu")
		)
		(fp_poly
			(pts
				(xy 0.507 0.678) (xy 0.62 0.678) (xy 0.693 0.674) (xy 0.725 0.656) (xy 0.733 0.611) (xy 0.733 0.593)
				(xy 0.729 0.539) (xy 0.705 0.515) (xy 0.645 0.509) (xy 0.62 0.508) (xy 0.507 0.508) (xy 0.507 0.077)
				(xy 0.51 -0.116) (xy 0.517 -0.26) (xy 0.531 -0.361) (xy 0.555 -0.426) (xy 0.59 -0.463) (xy 0.639 -0.478)
				(xy 0.666 -0.479) (xy 0.714 -0.486) (xy 0.73 -0.518) (xy 0.728 -0.571) (xy 0.716 -0.633) (xy 0.683 -0.661)
				(xy 0.62 -0.669) (xy 0.524 -0.663) (xy 0.436 -0.638) (xy 0.384 -0.609) (xy 0.345 -0.571) (xy 0.317 -0.514)
				(xy 0.299 -0.432) (xy 0.288 -0.316) (xy 0.283 -0.159) (xy 0.282 0.03) (xy 0.282 0.508) (xy 0.197 0.508)
				(xy 0.137 0.515) (xy 0.115 0.548) (xy 0.112 0.593) (xy 0.119 0.653) (xy 0.152 0.675) (xy 0.197 0.678)
				(xy 0.246 0.68) (xy 0.271 0.698) (xy 0.28 0.744) (xy 0.282 0.831) (xy 0.284 0.926) (xy 0.297 0.979)
				(xy 0.331 1.007) (xy 0.397 1.026) (xy 0.416 1.03) (xy 0.507 1.049) (xy 0.507 0.678)
			)
			(stroke
				(width 0.01)
				(type solid)
			)
			(fill yes)
			(layer "B.Cu")
		)
		(fp_poly
			(pts
				(xy 2.353 0.672) (xy 2.481 0.598) (xy 2.56 0.511) (xy 2.583 0.475) (xy 2.599 0.437) (xy 2.61 0.388)
				(xy 2.618 0.32) (xy 2.622 0.222) (xy 2.624 0.088) (xy 2.624 -0.093) (xy 2.624 -0.117) (xy 2.624 -0.649)
				(xy 2.37 -0.649) (xy 2.37 -0.139) (xy 2.369 0.028) (xy 2.365 0.178) (xy 2.359 0.301) (xy 2.351 0.386)
				(xy 2.343 0.422) (xy 2.279 0.487) (xy 2.185 0.521) (xy 2.08 0.522) (xy 1.98 0.488) (xy 1.94 0.46)
				(xy 1.922 0.438) (xy 1.909 0.405) (xy 1.901 0.353) (xy 1.895 0.272) (xy 1.892 0.155) (xy 1.891 -0.005)
				(xy 1.89 -0.117) (xy 1.89 -0.649) (xy 1.636 -0.649) (xy 1.636 -0.133) (xy 1.635 0.07) (xy 1.631 0.225)
				(xy 1.621 0.337) (xy 1.605 0.415) (xy 1.579 0.466) (xy 1.542 0.497) (xy 1.492 0.517) (xy 1.466 0.523)
				(xy 1.38 0.53) (xy 1.282 0.524) (xy 1.269 0.523) (xy 1.157 0.504) (xy 1.157 -0.649) (xy 0.903 -0.649)
				(xy 0.903 0.62) (xy 1.061 0.666) (xy 1.206 0.695) (xy 1.358 0.704) (xy 1.503 0.693) (xy 1.622 0.665)
				(xy 1.682 0.634) (xy 1.758 0.577) (xy 1.885 0.642) (xy 2.044 0.696) (xy 2.203 0.705) (xy 2.353 0.672)
			)
			(stroke
				(width 0.01)
				(type solid)
			)
			(fill yes)
			(layer "B.Cu")
		)
		(fp_poly
			(pts
				(xy 5.591 0.68) (xy 5.731 0.605) (xy 5.841 0.487) (xy 5.869 0.439) (xy 5.903 0.365) (xy 5.924 0.294)
				(xy 5.935 0.209) (xy 5.94 0.094) (xy 5.94 0.015) (xy 5.938 -0.125) (xy 5.93 -0.227) (xy 5.914 -0.305)
				(xy 5.886 -0.377) (xy 5.874 -0.401) (xy 5.794 -0.529) (xy 5.696 -0.612) (xy 5.568 -0.657) (xy 5.447 -0.671)
				(xy 5.333 -0.672) (xy 5.253 -0.66) (xy 5.184 -0.63) (xy 5.165 -0.618) (xy 5.058 -0.538) (xy 4.982 -0.444)
				(xy 4.933 -0.326) (xy 4.907 -0.175) (xy 4.9 -0.019) (xy 5.141 -0.019) (xy 5.157 -0.168) (xy 5.191 -0.3)
				(xy 5.239 -0.403) (xy 5.299 -0.463) (xy 5.381 -0.499) (xy 5.449 -0.5) (xy 5.528 -0.466) (xy 5.597 -0.414)
				(xy 5.644 -0.334) (xy 5.672 -0.218) (xy 5.685 -0.058) (xy 5.686 0.029) (xy 5.679 0.204) (xy 5.657 0.332)
				(xy 5.616 0.422) (xy 5.553 0.483) (xy 5.504 0.508) (xy 5.397 0.525) (xy 5.297 0.491) (xy 5.217 0.413)
				(xy 5.203 0.388) (xy 5.162 0.272) (xy 5.142 0.131) (xy 5.141 -0.019) (xy 4.9 -0.019) (xy 4.899 0.015)
				(xy 4.9 0.155) (xy 4.907 0.255) (xy 4.923 0.329) (xy 4.949 0.393) (xy 4.957 0.41) (xy 5.057 0.555)
				(xy 5.177 0.65) (xy 5.322 0.698) (xy 5.428 0.706) (xy 5.591 0.68)
			)
			(stroke
				(width 0.01)
				(type solid)
			)
			(fill yes)
			(layer "B.Cu")
		)
		(fp_poly
			(pts
				(xy -1.578 0.689) (xy -1.494 0.679) (xy -1.433 0.659) (xy -1.393 0.633) (xy -1.338 0.588) (xy -1.296 0.538)
				(xy -1.266 0.476) (xy -1.246 0.392) (xy -1.232 0.278) (xy -1.224 0.125) (xy -1.219 -0.075) (xy -1.219 -0.086)
				(xy -1.21 -0.581) (xy -1.289 -0.619) (xy -1.354 -0.638) (xy -1.456 -0.655) (xy -1.578 -0.666) (xy -1.623 -0.669)
				(xy -1.758 -0.672) (xy -1.852 -0.667) (xy -1.922 -0.652) (xy -1.974 -0.629) (xy -2.092 -0.544) (xy -2.161 -0.435)
				(xy -2.187 -0.293) (xy -2.187 -0.286) (xy -1.948 -0.286) (xy -1.926 -0.392) (xy -1.861 -0.463) (xy -1.751 -0.498)
				(xy -1.639 -0.502) (xy -1.482 -0.493) (xy -1.466 0.08) (xy -1.583 0.053) (xy -1.748 0.001) (xy -1.862 -0.073)
				(xy -1.928 -0.17) (xy -1.948 -0.286) (xy -2.187 -0.286) (xy -2.188 -0.268) (xy -2.164 -0.121) (xy -2.094 -0.001)
				(xy -1.974 0.094) (xy -1.805 0.164) (xy -1.644 0.201) (xy -1.548 0.22) (xy -1.495 0.239) (xy -1.472 0.265)
				(xy -1.468 0.302) (xy -1.491 0.407) (xy -1.556 0.48) (xy -1.659 0.517) (xy -1.794 0.517) (xy -1.891 0.497)
				(xy -1.981 0.475) (xy -2.033 0.469) (xy -2.064 0.482) (xy -2.082 0.501) (xy -2.111 0.555) (xy -2.117 0.581)
				(xy -2.091 0.621) (xy -2.017 0.655) (xy -1.904 0.679) (xy -1.763 0.691) (xy -1.703 0.692) (xy -1.578 0.689)
			)
			(stroke
				(width 0.01)
				(type solid)
			)
			(fill yes)
			(layer "B.Cu")
		)
		(fp_poly
			(pts
				(xy -4.178 1.906) (xy -4.093 1.869) (xy -3.982 1.813) (xy -3.857 1.744) (xy -3.837 1.733) (xy -3.695 1.651)
				(xy -3.521 1.552) (xy -3.336 1.446) (xy -3.156 1.344) (xy -3.091 1.306) (xy -2.948 1.224) (xy -2.82 1.146)
				(xy -2.715 1.08) (xy -2.644 1.032) (xy -2.618 1.01) (xy -2.604 0.99) (xy -2.594 0.962) (xy -2.585 0.918)
				(xy -2.579 0.854) (xy -2.574 0.763) (xy -2.571 0.639) (xy -2.57 0.476) (xy -2.569 0.268) (xy -2.569 0.032)
				(xy -2.569 -0.229) (xy -2.57 -0.439) (xy -2.573 -0.605) (xy -2.577 -0.73) (xy -2.582 -0.822) (xy -2.59 -0.885)
				(xy -2.599 -0.926) (xy -2.61 -0.949) (xy -2.646 -0.98) (xy -2.724 -1.034) (xy -2.834 -1.105) (xy -2.969 -1.186)
				(xy -3.119 -1.274) (xy -3.129 -1.28) (xy -3.301 -1.378) (xy -3.476 -1.478) (xy -3.641 -1.574) (xy -3.783 -1.656)
				(xy -3.87 -1.707) (xy -4.011 -1.787) (xy -4.117 -1.835) (xy -4.196 -1.858) (xy -4.232 -1.86) (xy -4.276 -1.852)
				(xy -4.341 -1.828) (xy -4.432 -1.785) (xy -4.554 -1.721) (xy -4.712 -1.633) (xy -4.909 -1.519) (xy -5.052 -1.436)
				(xy -5.237 -1.326) (xy -5.408 -1.224) (xy -5.559 -1.133) (xy -5.682 -1.056) (xy -5.771 -0.999) (xy -5.82 -0.965)
				(xy -5.825 -0.96) (xy -5.84 -0.943) (xy -5.852 -0.919) (xy -5.861 -0.883) (xy -5.868 -0.828) (xy -5.872 -0.749)
				(xy -5.876 -0.64) (xy -5.877 -0.495) (xy -5.878 -0.307) (xy -5.878 -0.071) (xy -5.878 0.031) (xy -5.278 0.031)
				(xy -5.276 -0.145) (xy -5.274 -0.304) (xy -5.269 -0.435) (xy -5.264 -0.53) (xy -5.257 -0.579) (xy -5.256 -0.584)
				(xy -5.225 -0.609) (xy -5.154 -0.656) (xy -5.052 -0.72) (xy -4.928 -0.795) (xy -4.793 -0.876) (xy -4.654 -0.958)
				(xy -4.521 -1.034) (xy -4.403 -1.1) (xy -4.311 -1.149) (xy -4.252 -1.178) (xy -4.237 -1.182) (xy -4.202 -1.17)
				(xy -4.126 -1.132) (xy -4.017 -1.075) (xy -3.884 -1.001) (xy -3.735 -0.916) (xy -3.708 -0.9) (xy -3.556 -0.811)
				(xy -3.421 -0.727) (xy -3.31 -0.655) (xy -3.23 -0.6) (xy -3.191 -0.566) (xy -3.189 -0.563) (xy -3.181 -0.521)
				(xy -3.174 -0.432) (xy -3.169 -0.31) (xy -3.165 -0.163) (xy -3.162 -0.004) (xy -3.161 0.157) (xy -3.162 0.308)
				(xy -3.165 0.44) (xy -3.17 0.54) (xy -3.177 0.598) (xy -3.178 0.604) (xy -3.208 0.633) (xy -3.278 0.683)
				(xy -3.38 0.749) (xy -3.504 0.826) (xy -3.642 0.908) (xy -3.783 0.989) (xy -3.92 1.066) (xy -4.042 1.131)
				(xy -4.141 1.181) (xy -4.207 1.209) (xy -4.227 1.214) (xy -4.267 1.2) (xy -4.346 1.163) (xy -4.454 1.108)
				(xy -4.583 1.039) (xy -4.721 0.963) (xy -4.86 0.884) (xy -4.99 0.808) (xy -5.102 0.741) (xy -5.186 0.687)
				(xy -5.229 0.656) (xy -5.245 0.636) (xy -5.258 0.605) (xy -5.267 0.555) (xy -5.273 0.479) (xy -5.276 0.369)
				(xy -5.277 0.217) (xy -5.278 0.031) (xy -5.878 0.031) (xy -5.878 0.032) (xy -5.878 0.971) (xy -5.811 1.025)
				(xy -5.754 1.065) (xy -5.659 1.125) (xy -5.534 1.2) (xy -5.386 1.288) (xy -5.221 1.383) (xy -5.049 1.482)
				(xy -4.875 1.58) (xy -4.708 1.673) (xy -4.554 1.757) (xy -4.422 1.827) (xy -4.318 1.881) (xy -4.25 1.912)
				(xy -4.227 1.92) (xy -4.178 1.906)
			)
			(stroke
				(width 0.01)
				(type solid)
			)
			(fill yes)
			(layer "B.Cu")
		)
		(fp_line
			(start -4.231 0.492)
			(end -4.231 -0.496)
			(stroke
				(width 0.13)
				(type solid)
			)
			(layer "B.Mask")
		)
		(fp_line
			(start -4.46 0.241)
			(end -4.587 0.368)
			(stroke
				(width 0.13)
				(type solid)
			)
			(layer "B.Mask")
		)
		(fp_line
			(start -4.46 0.241)
			(end -4.231 0.241)
			(stroke
				(width 0.13)
				(type solid)
			)
			(layer "B.Mask")
		)
		(fp_line
			(start -4.002 0.241)
			(end -3.875 0.368)
			(stroke
				(width 0.13)
				(type solid)
			)
			(layer "B.Mask")
		)
		(fp_line
			(start -4.002 0.241)
			(end -4.231 0.241)
			(stroke
				(width 0.13)
				(type solid)
			)
			(layer "B.Mask")
		)
		(fp_line
			(start -4.625 0.002)
			(end -4.269 0.002)
			(stroke
				(width 0.13)
				(type solid)
			)
			(layer "B.Mask")
		)
		(fp_line
			(start -3.837 0)
			(end -4.193 0)
			(stroke
				(width 0.13)
				(type solid)
			)
			(layer "B.Mask")
		)
		(fp_line
			(start -4.46 -0.216)
			(end -4.231 -0.216)
			(stroke
				(width 0.13)
				(type solid)
			)
			(layer "B.Mask")
		)
		(fp_line
			(start -4.46 -0.216)
			(end -4.587 -0.343)
			(stroke
				(width 0.13)
				(type solid)
			)
			(layer "B.Mask")
		)
		(fp_line
			(start -4.002 -0.216)
			(end -4.231 -0.216)
			(stroke
				(width 0.13)
				(type solid)
			)
			(layer "B.Mask")
		)
		(fp_line
			(start -4.002 -0.216)
			(end -3.875 -0.343)
			(stroke
				(width 0.13)
				(type solid)
			)
			(layer "B.Mask")
		)
		(fp_circle
			(center -4.231 0.609)
			(end -4.114 0.609)
			(stroke
				(width 0.13)
				(type solid)
			)
			(fill no)
			(layer "B.Mask")
		)
		(fp_circle
			(center -4.65 0.444)
			(end -4.561 0.444)
			(stroke
				(width 0.13)
				(type solid)
			)
			(fill no)
			(layer "B.Mask")
		)
		(fp_circle
			(center -3.812 0.444)
			(end -3.723 0.444)
			(stroke
				(width 0.13)
				(type solid)
			)
			(fill no)
			(layer "B.Mask")
		)
		(fp_circle
			(center -4.714 0.002)
			(end -4.625 0.002)
			(stroke
				(width 0.13)
				(type solid)
			)
			(fill no)
			(layer "B.Mask")
		)
		(fp_circle
			(center -3.748 0)
			(end -3.66 0)
			(stroke
				(width 0.13)
				(type solid)
			)
			(fill no)
			(layer "B.Mask")
		)
		(fp_circle
			(center -4.65 -0.419)
			(end -4.561 -0.419)
			(stroke
				(width 0.13)
				(type solid)
			)
			(fill no)
			(layer "B.Mask")
		)
		(fp_circle
			(center -3.812 -0.419)
			(end -3.723 -0.419)
			(stroke
				(width 0.13)
				(type solid)
			)
			(fill no)
			(layer "B.Mask")
		)
		(fp_circle
			(center -4.231 -0.607)
			(end -4.114 -0.607)
			(stroke
				(width 0.13)
				(type solid)
			)
			(fill no)
			(layer "B.Mask")
		)
		(fp_poly
			(pts
				(xy 3.132 -0.649) (xy 2.878 -0.649) (xy 2.878 0.678) (xy 3.132 0.678) (xy 3.132 -0.649)
			)
			(stroke
				(width 0.01)
				(type solid)
			)
			(fill yes)
			(layer "B.Mask")
		)
		(fp_poly
			(pts
				(xy 4.835 0.699) (xy 4.878 0.681) (xy 4.882 0.671) (xy 4.866 0.57) (xy 4.82 0.518) (xy 4.772 0.51)
				(xy 4.684 0.512) (xy 4.621 0.511) (xy 4.543 0.508) (xy 4.543 -0.649) (xy 4.289 -0.649) (xy 4.289 0.619)
				(xy 4.436 0.663) (xy 4.543 0.687) (xy 4.654 0.702) (xy 4.756 0.706) (xy 4.835 0.699)
			)
			(stroke
				(width 0.01)
				(type solid)
			)
			(fill yes)
			(layer "B.Mask")
		)
		(fp_poly
			(pts
				(xy -0.341 0.69) (xy -0.208 0.652) (xy -0.207 0.651) (xy -0.141 0.618) (xy -0.091 0.58) (xy -0.055 0.53)
				(xy -0.029 0.46) (xy -0.013 0.363) (xy -0.005 0.23) (xy -0.001 0.054) (xy 0 -0.111) (xy 0 -0.649)
				(xy -0.254 -0.649) (xy -0.254 -0.133) (xy -0.256 0.07) (xy -0.26 0.225) (xy -0.27 0.337) (xy -0.286 0.415)
				(xy -0.312 0.466) (xy -0.349 0.497) (xy -0.399 0.517) (xy -0.424 0.523) (xy -0.51 0.53) (xy -0.609 0.524)
				(xy -0.622 0.523) (xy -0.734 0.504) (xy -0.734 -0.649) (xy -0.988 -0.649) (xy -0.988 0.619) (xy -0.842 0.663)
				(xy -0.678 0.696) (xy -0.504 0.705) (xy -0.341 0.69)
			)
			(stroke
				(width 0.01)
				(type solid)
			)
			(fill yes)
			(layer "B.Mask")
		)
		(fp_poly
			(pts
				(xy 3.995 0.682) (xy 4.079 0.647) (xy 4.112 0.594) (xy 4.099 0.526) (xy 4.075 0.484) (xy 4.044 0.471)
				(xy 3.987 0.485) (xy 3.96 0.494) (xy 3.871 0.516) (xy 3.799 0.508) (xy 3.77 0.498) (xy 3.681 0.446)
				(xy 3.62 0.369) (xy 3.582 0.259) (xy 3.562 0.104) (xy 3.561 0.086) (xy 3.564 -0.106) (xy 3.594 -0.264)
				(xy 3.65 -0.381) (xy 3.705 -0.437) (xy 3.791 -0.47) (xy 3.897 -0.477) (xy 3.994 -0.457) (xy 4.008 -0.451)
				(xy 4.056 -0.439) (xy 4.09 -0.476) (xy 4.091 -0.477) (xy 4.118 -0.556) (xy 4.096 -0.61) (xy 4.031 -0.646)
				(xy 3.943 -0.665) (xy 3.832 -0.674) (xy 3.724 -0.671) (xy 3.643 -0.658) (xy 3.64 -0.656) (xy 3.516 -0.581)
				(xy 3.412 -0.461) (xy 3.369 -0.383) (xy 3.334 -0.298) (xy 3.314 -0.211) (xy 3.304 -0.105) (xy 3.302 0.018)
				(xy 3.304 0.149) (xy 3.312 0.243) (xy 3.331 0.318) (xy 3.364 0.394) (xy 3.381 0.428) (xy 3.472 0.565)
				(xy 3.582 0.652) (xy 3.718 0.694) (xy 3.859 0.699) (xy 3.995 0.682)
			)
			(stroke
				(width 0.01)
				(type solid)
			)
			(fill yes)
			(layer "B.Mask")
		)
		(fp_poly
			(pts
				(xy 0.507 0.678) (xy 0.62 0.678) (xy 0.693 0.674) (xy 0.725 0.656) (xy 0.733 0.611) (xy 0.733 0.593)
				(xy 0.729 0.539) (xy 0.705 0.515) (xy 0.645 0.509) (xy 0.62 0.508) (xy 0.507 0.508) (xy 0.507 0.077)
				(xy 0.51 -0.116) (xy 0.517 -0.26) (xy 0.531 -0.361) (xy 0.555 -0.426) (xy 0.59 -0.463) (xy 0.639 -0.478)
				(xy 0.666 -0.479) (xy 0.714 -0.486) (xy 0.73 -0.518) (xy 0.728 -0.571) (xy 0.716 -0.633) (xy 0.683 -0.661)
				(xy 0.62 -0.669) (xy 0.524 -0.663) (xy 0.436 -0.638) (xy 0.384 -0.609) (xy 0.345 -0.571) (xy 0.317 -0.514)
				(xy 0.299 -0.432) (xy 0.288 -0.316) (xy 0.283 -0.159) (xy 0.282 0.03) (xy 0.282 0.508) (xy 0.197 0.508)
				(xy 0.137 0.515) (xy 0.115 0.548) (xy 0.112 0.593) (xy 0.119 0.653) (xy 0.152 0.675) (xy 0.197 0.678)
				(xy 0.246 0.68) (xy 0.271 0.698) (xy 0.28 0.744) (xy 0.282 0.831) (xy 0.284 0.926) (xy 0.297 0.979)
				(xy 0.331 1.007) (xy 0.397 1.026) (xy 0.416 1.03) (xy 0.507 1.049) (xy 0.507 0.678)
			)
			(stroke
				(width 0.01)
				(type solid)
			)
			(fill yes)
			(layer "B.Mask")
		)
		(fp_poly
			(pts
				(xy 2.353 0.672) (xy 2.481 0.598) (xy 2.56 0.511) (xy 2.583 0.475) (xy 2.599 0.437) (xy 2.61 0.388)
				(xy 2.618 0.32) (xy 2.622 0.222) (xy 2.624 0.088) (xy 2.624 -0.093) (xy 2.624 -0.117) (xy 2.624 -0.649)
				(xy 2.37 -0.649) (xy 2.37 -0.139) (xy 2.369 0.028) (xy 2.365 0.178) (xy 2.359 0.301) (xy 2.351 0.386)
				(xy 2.343 0.422) (xy 2.279 0.487) (xy 2.185 0.521) (xy 2.08 0.522) (xy 1.98 0.488) (xy 1.94 0.46)
				(xy 1.922 0.438) (xy 1.909 0.405) (xy 1.901 0.353) (xy 1.895 0.272) (xy 1.892 0.155) (xy 1.891 -0.005)
				(xy 1.89 -0.117) (xy 1.89 -0.649) (xy 1.636 -0.649) (xy 1.636 -0.133) (xy 1.635 0.07) (xy 1.631 0.225)
				(xy 1.621 0.337) (xy 1.605 0.415) (xy 1.579 0.466) (xy 1.542 0.497) (xy 1.492 0.517) (xy 1.466 0.523)
				(xy 1.38 0.53) (xy 1.282 0.524) (xy 1.269 0.523) (xy 1.157 0.504) (xy 1.157 -0.649) (xy 0.903 -0.649)
				(xy 0.903 0.62) (xy 1.061 0.666) (xy 1.206 0.695) (xy 1.358 0.704) (xy 1.503 0.693) (xy 1.622 0.665)
				(xy 1.682 0.634) (xy 1.758 0.577) (xy 1.885 0.642) (xy 2.044 0.696) (xy 2.203 0.705) (xy 2.353 0.672)
			)
			(stroke
				(width 0.01)
				(type solid)
			)
			(fill yes)
			(layer "B.Mask")
		)
		(fp_poly
			(pts
				(xy 5.591 0.68) (xy 5.731 0.605) (xy 5.841 0.487) (xy 5.869 0.439) (xy 5.903 0.365) (xy 5.924 0.294)
				(xy 5.935 0.209) (xy 5.94 0.094) (xy 5.94 0.015) (xy 5.938 -0.125) (xy 5.93 -0.227) (xy 5.914 -0.305)
				(xy 5.886 -0.377) (xy 5.874 -0.401) (xy 5.794 -0.529) (xy 5.696 -0.612) (xy 5.568 -0.657) (xy 5.447 -0.671)
				(xy 5.333 -0.672) (xy 5.253 -0.66) (xy 5.184 -0.63) (xy 5.165 -0.618) (xy 5.058 -0.538) (xy 4.982 -0.444)
				(xy 4.933 -0.326) (xy 4.907 -0.175) (xy 4.9 -0.019) (xy 5.141 -0.019) (xy 5.157 -0.168) (xy 5.191 -0.3)
				(xy 5.239 -0.403) (xy 5.299 -0.463) (xy 5.381 -0.499) (xy 5.449 -0.5) (xy 5.528 -0.466) (xy 5.597 -0.414)
				(xy 5.644 -0.334) (xy 5.672 -0.218) (xy 5.685 -0.058) (xy 5.686 0.029) (xy 5.679 0.204) (xy 5.657 0.332)
				(xy 5.616 0.422) (xy 5.553 0.483) (xy 5.504 0.508) (xy 5.397 0.525) (xy 5.297 0.491) (xy 5.217 0.413)
				(xy 5.203 0.388) (xy 5.162 0.272) (xy 5.142 0.131) (xy 5.141 -0.019) (xy 4.9 -0.019) (xy 4.899 0.015)
				(xy 4.9 0.155) (xy 4.907 0.255) (xy 4.923 0.329) (xy 4.949 0.393) (xy 4.957 0.41) (xy 5.057 0.555)
				(xy 5.177 0.65) (xy 5.322 0.698) (xy 5.428 0.706) (xy 5.591 0.68)
			)
			(stroke
				(width 0.01)
				(type solid)
			)
			(fill yes)
			(layer "B.Mask")
		)
		(fp_poly
			(pts
				(xy -1.578 0.689) (xy -1.494 0.679) (xy -1.433 0.659) (xy -1.393 0.633) (xy -1.338 0.588) (xy -1.296 0.538)
				(xy -1.266 0.476) (xy -1.246 0.392) (xy -1.232 0.278) (xy -1.224 0.125) (xy -1.219 -0.075) (xy -1.219 -0.086)
				(xy -1.21 -0.581) (xy -1.289 -0.619) (xy -1.354 -0.638) (xy -1.456 -0.655) (xy -1.578 -0.666) (xy -1.623 -0.669)
				(xy -1.758 -0.672) (xy -1.852 -0.667) (xy -1.922 -0.652) (xy -1.974 -0.629) (xy -2.092 -0.544) (xy -2.161 -0.435)
				(xy -2.187 -0.293) (xy -2.187 -0.286) (xy -1.948 -0.286) (xy -1.926 -0.392) (xy -1.861 -0.463) (xy -1.751 -0.498)
				(xy -1.639 -0.502) (xy -1.482 -0.493) (xy -1.466 0.08) (xy -1.583 0.053) (xy -1.748 0.001) (xy -1.862 -0.073)
				(xy -1.928 -0.17) (xy -1.948 -0.286) (xy -2.187 -0.286) (xy -2.188 -0.268) (xy -2.164 -0.121) (xy -2.094 -0.001)
				(xy -1.974 0.094) (xy -1.805 0.164) (xy -1.644 0.201) (xy -1.548 0.22) (xy -1.495 0.239) (xy -1.472 0.265)
				(xy -1.468 0.302) (xy -1.491 0.407) (xy -1.556 0.48) (xy -1.659 0.517) (xy -1.794 0.517) (xy -1.891 0.497)
				(xy -1.981 0.475) (xy -2.033 0.469) (xy -2.064 0.482) (xy -2.082 0.501) (xy -2.111 0.555) (xy -2.117 0.581)
				(xy -2.091 0.621) (xy -2.017 0.655) (xy -1.904 0.679) (xy -1.763 0.691) (xy -1.703 0.692) (xy -1.578 0.689)
			)
			(stroke
				(width 0.01)
				(type solid)
			)
			(fill yes)
			(layer "B.Mask")
		)
		(fp_poly
			(pts
				(xy -4.178 1.906) (xy -4.093 1.869) (xy -3.982 1.813) (xy -3.857 1.744) (xy -3.837 1.733) (xy -3.695 1.651)
				(xy -3.521 1.552) (xy -3.336 1.446) (xy -3.156 1.344) (xy -3.091 1.306) (xy -2.948 1.224) (xy -2.82 1.146)
				(xy -2.715 1.08) (xy -2.644 1.032) (xy -2.618 1.01) (xy -2.604 0.99) (xy -2.594 0.962) (xy -2.585 0.918)
				(xy -2.579 0.854) (xy -2.574 0.763) (xy -2.571 0.639) (xy -2.57 0.476) (xy -2.569 0.268) (xy -2.569 0.032)
				(xy -2.569 -0.229) (xy -2.57 -0.439) (xy -2.573 -0.605) (xy -2.577 -0.73) (xy -2.582 -0.822) (xy -2.59 -0.885)
				(xy -2.599 -0.926) (xy -2.61 -0.949) (xy -2.646 -0.98) (xy -2.724 -1.034) (xy -2.834 -1.105) (xy -2.969 -1.186)
				(xy -3.119 -1.274) (xy -3.129 -1.28) (xy -3.301 -1.378) (xy -3.476 -1.478) (xy -3.641 -1.574) (xy -3.783 -1.656)
				(xy -3.87 -1.707) (xy -4.011 -1.787) (xy -4.117 -1.835) (xy -4.196 -1.858) (xy -4.232 -1.86) (xy -4.276 -1.852)
				(xy -4.341 -1.828) (xy -4.432 -1.785) (xy -4.554 -1.721) (xy -4.712 -1.633) (xy -4.909 -1.519) (xy -5.052 -1.436)
				(xy -5.237 -1.326) (xy -5.408 -1.224) (xy -5.559 -1.133) (xy -5.682 -1.056) (xy -5.771 -0.999) (xy -5.82 -0.965)
				(xy -5.825 -0.96) (xy -5.84 -0.943) (xy -5.852 -0.919) (xy -5.861 -0.883) (xy -5.868 -0.828) (xy -5.872 -0.749)
				(xy -5.876 -0.64) (xy -5.877 -0.495) (xy -5.878 -0.307) (xy -5.878 -0.071) (xy -5.878 0.031) (xy -5.278 0.031)
				(xy -5.276 -0.145) (xy -5.274 -0.304) (xy -5.269 -0.435) (xy -5.264 -0.53) (xy -5.257 -0.579) (xy -5.256 -0.584)
				(xy -5.225 -0.609) (xy -5.154 -0.656) (xy -5.052 -0.72) (xy -4.928 -0.795) (xy -4.793 -0.876) (xy -4.654 -0.958)
				(xy -4.521 -1.034) (xy -4.403 -1.1) (xy -4.311 -1.149) (xy -4.252 -1.178) (xy -4.237 -1.182) (xy -4.202 -1.17)
				(xy -4.126 -1.132) (xy -4.017 -1.075) (xy -3.884 -1.001) (xy -3.735 -0.916) (xy -3.708 -0.9) (xy -3.556 -0.811)
				(xy -3.421 -0.727) (xy -3.31 -0.655) (xy -3.23 -0.6) (xy -3.191 -0.566) (xy -3.189 -0.563) (xy -3.181 -0.521)
				(xy -3.174 -0.432) (xy -3.169 -0.31) (xy -3.165 -0.163) (xy -3.162 -0.004) (xy -3.161 0.157) (xy -3.162 0.308)
				(xy -3.165 0.44) (xy -3.17 0.54) (xy -3.177 0.598) (xy -3.178 0.604) (xy -3.208 0.633) (xy -3.278 0.683)
				(xy -3.38 0.749) (xy -3.504 0.826) (xy -3.642 0.908) (xy -3.783 0.989) (xy -3.92 1.066) (xy -4.042 1.131)
				(xy -4.141 1.181) (xy -4.207 1.209) (xy -4.227 1.214) (xy -4.267 1.2) (xy -4.346 1.163) (xy -4.454 1.108)
				(xy -4.583 1.039) (xy -4.721 0.963) (xy -4.86 0.884) (xy -4.99 0.808) (xy -5.102 0.741) (xy -5.186 0.687)
				(xy -5.229 0.656) (xy -5.245 0.636) (xy -5.258 0.605) (xy -5.267 0.555) (xy -5.273 0.479) (xy -5.276 0.369)
				(xy -5.277 0.217) (xy -5.278 0.031) (xy -5.878 0.031) (xy -5.878 0.032) (xy -5.878 0.971) (xy -5.811 1.025)
				(xy -5.754 1.065) (xy -5.659 1.125) (xy -5.534 1.2) (xy -5.386 1.288) (xy -5.221 1.383) (xy -5.049 1.482)
				(xy -4.875 1.58) (xy -4.708 1.673) (xy -4.554 1.757) (xy -4.422 1.827) (xy -4.318 1.881) (xy -4.25 1.912)
				(xy -4.227 1.92) (xy -4.178 1.906)
			)
			(stroke
				(width 0.01)
				(type solid)
			)
			(fill yes)
			(layer "B.Mask")
		)
	)
	(gr_line
		(start 210 121.65)
		(end 210 113.5)
		(stroke
			(width 0.12)
			(type solid)
		)
		(layer "Edge.Cuts")
	)
	(gr_arc
		(start 208.95 123.65)
		(mid 207.95 122.65)
		(end 208.95 121.65)
		(stroke
			(width 0.12)
			(type solid)
		)
		(layer "Edge.Cuts")
	)
	(gr_arc
		(start 204.95 121.65)
		(mid 205.95 122.65)
		(end 204.95 123.65)
		(stroke
			(width 0.12)
			(type solid)
		)
		(layer "Edge.Cuts")
	)
	(gr_line
		(start 210 123.65)
		(end 210 140)
		(stroke
			(width 0.12)
			(type solid)
		)
		(layer "Edge.Cuts")
	)
	(gr_line
		(start 199.95 113.5)
		(end 210 113.5)
		(stroke
			(width 0.12)
			(type solid)
		)
		(layer "Edge.Cuts")
	)
	(gr_line
		(start 160 113.5)
		(end 160 140)
		(stroke
			(width 0.12)
			(type solid)
		)
		(layer "Edge.Cuts")
	)
	(gr_line
		(start 208.95 123.65)
		(end 210 123.65)
		(stroke
			(width 0.12)
			(type solid)
		)
		(layer "Edge.Cuts")
	)
	(gr_line
		(start 197.95 113.5)
		(end 160 113.5)
		(stroke
			(width 0.12)
			(type solid)
		)
		(layer "Edge.Cuts")
	)
	(gr_arc
		(start 198.948209 123.648406)
		(mid 198.241102 123.355513)
		(end 197.948209 122.648406)
		(stroke
			(width 0.12)
			(type solid)
		)
		(layer "Edge.Cuts")
	)
	(gr_line
		(start 199.95 121.65)
		(end 204.95 121.65)
		(stroke
			(width 0.12)
			(type solid)
		)
		(layer "Edge.Cuts")
	)
	(gr_line
		(start 199.95 121.65)
		(end 199.95 118.45)
		(stroke
			(width 0.12)
			(type solid)
		)
		(layer "Edge.Cuts")
	)
	(gr_line
		(start 197.95 114.45)
		(end 197.95 113.5)
		(stroke
			(width 0.12)
			(type solid)
		)
		(layer "Edge.Cuts")
	)
	(gr_line
		(start 197.95 118.45)
		(end 197.948209 122.648406)
		(stroke
			(width 0.12)
			(type solid)
		)
		(layer "Edge.Cuts")
	)
	(gr_arc
		(start 197.95 118.45)
		(mid 198.95 117.45)
		(end 199.95 118.45)
		(stroke
			(width 0.12)
			(type solid)
		)
		(layer "Edge.Cuts")
	)
	(gr_line
		(start 208.95 121.65)
		(end 210 121.65)
		(stroke
			(width 0.12)
			(type solid)
		)
		(layer "Edge.Cuts")
	)
	(gr_line
		(start 199.95 114.45)
		(end 199.95 113.5)
		(stroke
			(width 0.12)
			(type solid)
		)
		(layer "Edge.Cuts")
	)
	(gr_arc
		(start 199.95 114.45)
		(mid 198.95 115.45)
		(end 197.95 114.45)
		(stroke
			(width 0.12)
			(type solid)
		)
		(layer "Edge.Cuts")
	)
	(gr_line
		(start 198.948209 123.648406)
		(end 204.95 123.65)
		(stroke
			(width 0.12)
			(type solid)
		)
		(layer "Edge.Cuts")
	)
	(gr_line
		(start 160 140)
		(end 210 140)
		(stroke
			(width 0.12)
			(type solid)
		)
		(layer "Edge.Cuts")
	)
	(segment
		(start 199.913 115.829)
		(end 200.342 115.4)
		(width 0.25)
		(layer "F.Cu")
		(net 1)
	)
	(segment
		(start 188.194 126.144)
		(end 188.194 125.571)
		(width 0.25)
		(layer "F.Cu")
		(net 1)
	)
	(segment
		(start 168.24 123.44)
		(end 168.65 123.85)
		(width 0.25)
		(layer "F.Cu")
		(net 1)
	)
	(segment
		(start 201.85 121)
		(end 203.75 121)
		(width 0.25)
		(layer "F.Cu")
		(net 1)
	)
	(segment
		(start 197.375741 129.594)
		(end 198.368 129.594)
		(width 0.25)
		(layer "F.Cu")
		(net 1)
	)
	(segment
		(start 207.875 115.025)
		(end 207.225 115.675)
		(width 0.25)
		(layer "F.Cu")
		(net 1)
	)
	(segment
		(start 207.15 120.085)
		(end 205.815 120.085)
		(width 0.25)
		(layer "F.Cu")
		(net 1)
	)
	(segment
		(start 179.008 115.223)
		(end 179.007 115.224)
		(width 0.25)
		(layer "F.Cu")
		(net 1)
	)
	(segment
		(start 177.6455 121.498)
		(end 177.6455 121.9125)
		(width 0.25)
		(layer "F.Cu")
		(net 1)
	)
	(segment
		(start 187.094 123.28)
		(end 186.99 123.176)
		(width 0.25)
		(layer "F.Cu")
		(net 1)
	)
	(segment
		(start 175.203 124.174)
		(end 175.209 124.168)
		(width 0.25)
		(layer "F.Cu")
		(net 1)
	)
	(segment
		(start 182.441 133.15)
		(end 182.441 132.615)
		(width 0.25)
		(layer "F.Cu")
		(net 1)
	)
	(segment
		(start 191.601 126.626)
		(end 191.544 126.569)
		(width 0.25)
		(layer "F.Cu")
		(net 1)
	)
	(segment
		(start 167.925 129.95)
		(end 168.035 130.06)
		(width 0.25)
		(layer "F.Cu")
		(net 1)
	)
	(segment
		(start 175.6475 119.27)
		(end 175.8955 119.022)
		(width 0.25)
		(layer "F.Cu")
		(net 1)
	)
	(segment
		(start 202.5 115.09)
		(end 202.16 115.09)
		(width 0.25)
		(layer "F.Cu")
		(net 1)
	)
	(segment
		(start 191.816 118.124)
		(end 193.028173 118.124)
		(width 0.25)
		(layer "F.Cu")
		(net 1)
	)
	(segment
		(start 205.815 120.085)
		(end 205.58 120.32)
		(width 0.25)
		(layer "F.Cu")
		(net 1)
	)
	(segment
		(start 173.6495 121.84)
		(end 173.8015 121.84)
		(width 0.25)
		(layer "F.Cu")
		(net 1)
	)
	(segment
		(start 200.342 115.4)
		(end 200.45 115.4)
		(width 0.25)
		(layer "F.Cu")
		(net 1)
	)
	(segment
		(start 203.3955 128.249)
		(end 203.397 128.2505)
		(width 0.25)
		(layer "F.Cu")
		(net 1)
	)
	(segment
		(start 188.659622 118.453622)
		(end 189.27 117.843244)
		(width 0.25)
		(layer "F.Cu")
		(net 1)
	)
	(segment
		(start 189.27 117.843244)
		(end 189.27 117.597)
		(width 0.25)
		(layer "F.Cu")
		(net 1)
	)
	(segment
		(start 167.925 123.55)
		(end 168.035 123.44)
		(width 0.25)
		(layer "F.Cu")
		(net 1)
	)
	(segment
		(start 179.076 116.321)
		(end 179.076 115.291)
		(width 0.25)
		(layer "F.Cu")
		(net 1)
	)
	(segment
		(start 206.475001 115.675)
		(end 206.075 115.675)
		(width 0.25)
		(layer "F.Cu")
		(net 1)
	)
	(segment
		(start 205.43 116.32)
		(end 205.15 116.32)
		(width 0.25)
		(layer "F.Cu")
		(net 1)
	)
	(segment
		(start 202.5 115.09)
		(end 202.5 114.45)
		(width 0.25)
		(layer "F.Cu")
		(net 1)
	)
	(segment
		(start 182.441 135.9)
		(end 180.21 135.9)
		(width 0.25)
		(layer "F.Cu")
		(net 1)
	)
	(segment
		(start 205.15 116.32)
		(end 204.72 116.32)
		(width 0.25)
		(layer "F.Cu")
		(net 1)
	)
	(segment
		(start 169.5 129.8)
		(end 168.8 129.8)
		(width 0.25)
		(layer "F.Cu")
		(net 1)
	)
	(segment
		(start 169.534901 126.767)
		(end 169.947 126.767)
		(width 0.25)
		(layer "F.Cu")
		(net 1)
	)
	(segment
		(start 191.687 118.253)
		(end 191.816 118.124)
		(width 0.25)
		(layer "F.Cu")
		(net 1)
	)
	(segment
		(start 168.8 129.8)
		(end 168.65 129.65)
		(width 0.25)
		(layer "F.Cu")
		(net 1)
	)
	(segment
		(start 198.368 129.594)
		(end 198.963 128.999)
		(width 0.25)
		(layer "F.Cu")
		(net 1)
	)
	(segment
		(start 201.175 117.95)
		(end 201.175 120.325)
		(width 0.25)
		(layer "F.Cu")
		(net 1)
	)
	(segment
		(start 182.244 120.6235)
		(end 182.244 119.5925)
		(width 0.25)
		(layer "F.Cu")
		(net 1)
	)
	(segment
		(start 177.1455 120.272)
		(end 175.8955 119.022)
		(width 0.25)
		(layer "F.Cu")
		(net 1)
	)
	(segment
		(start 197.222741 129.747)
		(end 197.226494 129.743247)
		(width 0.25)
		(layer "F.Cu")
		(net 1)
	)
	(segment
		(start 206.075 115.675)
		(end 205.43 116.32)
		(width 0.25)
		(layer "F.Cu")
		(net 1)
	)
	(segment
		(start 203.085 130.686)
		(end 202.037 130.686)
		(width 0.25)
		(layer "F.Cu")
		(net 1)
	)
	(segment
		(start 182.441 132.615)
		(end 182.426 132.6)
		(width 0.25)
		(layer "F.Cu")
		(net 1)
	)
	(segment
		(start 194.05 137.915)
		(end 194.05 137.849502)
		(width 0.25)
		(layer "F.Cu")
		(net 1)
	)
	(segment
		(start 204.47 121)
		(end 205.15 120.32)
		(width 0.25)
		(layer "F.Cu")
		(net 1)
	)
	(segment
		(start 187.094 124.603)
		(end 187.094 123.28)
		(width 0.25)
		(layer "F.Cu")
		(net 1)
	)
	(segment
		(start 173.6 134.45)
		(end 174.685 134.45)
		(width 0.25)
		(layer "F.Cu")
		(net 1)
	)
	(segment
		(start 182.425 130.4)
		(end 182.2 130.4)
		(width 0.25)
		(layer "F.Cu")
		(net 1)
	)
	(segment
		(start 181.55 131.05)
		(end 180.5 131.05)
		(width 0.25)
		(layer "F.Cu")
		(net 1)
	)
	(segment
		(start 173.538326 124.734619)
		(end 174.098945 124.174)
		(width 0.25)
		(layer "F.Cu")
		(net 1)
	)
	(segment
		(start 169.475 129.775)
		(end 169.5 129.8)
		(width 0.25)
		(layer "F.Cu")
		(net 1)
	)
	(segment
		(start 168.035 130.06)
		(end 168.24 130.06)
		(width 0.25)
		(layer "F.Cu")
		(net 1)
	)
	(segment
		(start 176.1445 116.547)
		(end 176.1445 118.773)
		(width 0.25)
		(layer "F.Cu")
		(net 1)
	)
	(segment
		(start 203.75 115.35)
		(end 203.75 114.55)
		(width 0.25)
		(layer "F.Cu")
		(net 1)
	)
	(segment
		(start 193.85 136.215)
		(end 193.85 137.065686)
		(width 0.25)
		(layer "F.Cu")
		(net 1)
	)
	(segment
		(start 207.225 115.675)
		(end 206.475001 115.675)
		(width 0.25)
		(layer "F.Cu")
		(net 1)
	)
	(segment
		(start 174.098945 124.174)
		(end 175.203 124.174)
		(width 0.25)
		(layer "F.Cu")
		(net 1)
	)
	(segment
		(start 189.35 127.815)
		(end 189.35 126.85)
		(width 0.25)
		(layer "F.Cu")
		(net 1)
	)
	(segment
		(start 188.3 126.25)
		(end 188.194 126.144)
		(width 0.25)
		(layer "F.Cu")
		(net 1)
	)
	(segment
		(start 193.85 136.215)
		(end 193.85 135.05)
		(width 0.25)
		(layer "F.Cu")
		(net 1)
	)
	(segment
		(start 182.244 119.5925)
		(end 182.251 119.5855)
		(width 0.25)
		(layer "F.Cu")
		(net 1)
	)
	(segment
		(start 181.443 118.7775)
		(end 182.251 119.5855)
		(width 0.25)
		(layer "F.Cu")
		(net 1)
	)
	(segment
		(start 173.084 137.666)
		(end 172.975 137.775)
		(width 0.25)
		(layer "F.Cu")
		(net 1)
	)
	(segment
		(start 169.475 128.45)
		(end 169.475 129.775)
		(width 0.25)
		(layer "F.Cu")
		(net 1)
	)
	(segment
		(start 195.323173 115.829)
		(end 199.913 115.829)
		(width 0.25)
		(layer "F.Cu")
		(net 1)
	)
	(segment
		(start 182.441 133.7)
		(end 182.441 133.15)
		(width 0.25)
		(layer "F.Cu")
		(net 1)
	)
	(segment
		(start 191.544 126.569)
		(end 191.544 125.572)
		(width 0.25)
		(layer "F.Cu")
		(net 1)
	)
	(segment
		(start 179.076 115.291)
		(end 179.008 115.223)
		(width 0.25)
		(layer "F.Cu")
		(net 1)
	)
	(segment
		(start 202.849 128.249)
		(end 203.3955 128.249)
		(width 0.25)
		(layer "F.Cu")
		(net 1)
	)
	(segment
		(start 169.5 123.7)
		(end 168.8 123.7)
		(width 0.25)
		(layer "F.Cu")
		(net 1)
	)
	(segment
		(start 173.084 137.3)
		(end 173.084 137.666)
		(width 0.25)
		(layer "F.Cu")
		(net 1)
	)
	(segment
		(start 173.8015 121.84)
		(end 174.1435 121.498)
		(width 0.25)
		(layer "F.Cu")
		(net 1)
	)
	(segment
		(start 168.24 130.06)
		(end 168.65 129.65)
		(width 0.25)
		(layer "F.Cu")
		(net 1)
	)
	(segment
		(start 181.443 117.68)
		(end 181.443 118.7775)
		(width 0.25)
		(layer "F.Cu")
		(net 1)
	)
	(segment
		(start 191.85 135.05)
		(end 191.9 135)
		(width 0.25)
		(layer "F.Cu")
		(net 1)
	)
	(segment
		(start 201.175 120.325)
		(end 201.85 121)
		(width 0.25)
		(layer "F.Cu")
		(net 1)
	)
	(segment
		(start 195.848 129.747)
		(end 197.222741 129.747)
		(width 0.25)
		(layer "F.Cu")
		(net 1)
	)
	(segment
		(start 175.6475 121.498)
		(end 175.6475 119.27)
		(width 0.25)
		(layer "F.Cu")
		(net 1)
	)
	(segment
		(start 201.885 115.365)
		(end 201.25 115.365)
		(width 0.25)
		(layer "F.Cu")
		(net 1)
	)
	(segment
		(start 188.75 126.25)
		(end 189.35 126.85)
		(width 0.25)
		(layer "F.Cu")
		(net 1)
	)
	(segment
		(start 194.05 137.916)
		(end 192.95 137.916)
		(width 0.25)
		(layer "F.Cu")
		(net 1)
	)
	(segment
		(start 188.75 126.25)
		(end 188.3 126.25)
		(width 0.25)
		(layer "F.Cu")
		(net 1)
	)
	(segment
		(start 200.485 115.365)
		(end 200.45 115.4)
		(width 0.25)
		(layer "F.Cu")
		(net 1)
	)
	(segment
		(start 203.75 121)
		(end 204.47 121)
		(width 0.25)
		(layer "F.Cu")
		(net 1)
	)
	(segment
		(start 202.037 130.686)
		(end 201.985 130.634)
		(width 0.25)
		(layer "F.Cu")
		(net 1)
	)
	(segment
		(start 172.226 122.313)
		(end 172.226 122.726)
		(width 0.25)
		(layer "F.Cu")
		(net 1)
	)
	(segment
		(start 204.72 116.32)
		(end 203.75 115.35)
		(width 0.25)
		(layer "F.Cu")
		(net 1)
	)
	(segment
		(start 168.035 123.44)
		(end 168.24 123.44)
		(width 0.25)
		(layer "F.Cu")
		(net 1)
	)
	(segment
		(start 201.25 115.365)
		(end 200.485 115.365)
		(width 0.25)
		(layer "F.Cu")
		(net 1)
	)
	(segment
		(start 194.05 137.265686)
		(end 194.05 137.916)
		(width 0.25)
		(layer "F.Cu")
		(net 1)
	)
	(segment
		(start 179.1955 120.263)
		(end 179.1865 120.272)
		(width 0.25)
		(layer "F.Cu")
		(net 1)
	)
	(segment
		(start 180.21 135.9)
		(end 179.81 136.3)
		(width 0.25)
		(layer "F.Cu")
		(net 1)
	)
	(segment
		(start 191.85 136.215)
		(end 191.85 135.05)
		(width 0.25)
		(layer "F.Cu")
		(net 1)
	)
	(segment
		(start 169.526227 126.758326)
		(end 169.534901 126.767)
		(width 0.25)
		(layer "F.Cu")
		(net 1)
	)
	(segment
		(start 179.1865 120.272)
		(end 178.3695 120.272)
		(width 0.25)
		(layer "F.Cu")
		(net 1)
	)
	(segment
		(start 193.85 137.065686)
		(end 194.05 137.265686)
		(width 0.25)
		(layer "F.Cu")
		(net 1)
	)
	(segment
		(start 202.16 115.09)
		(end 201.885 115.365)
		(width 0.25)
		(layer "F.Cu")
		(net 1)
	)
	(segment
		(start 174.685 134.45)
		(end 175.05 134.085)
		(width 0.25)
		(layer "F.Cu")
		(net 1)
	)
	(segment
		(start 172.226 122.726)
		(end 172.6 123.1)
		(width 0.25)
		(layer "F.Cu")
		(net 1)
	)
	(segment
		(start 177.6455 121.9125)
		(end 177.984 122.251)
		(width 0.25)
		(layer "F.Cu")
		(net 1)
	)
	(segment
		(start 178.3695 120.272)
		(end 177.1455 120.272)
		(width 0.25)
		(layer "F.Cu")
		(net 1)
	)
	(segment
		(start 208.525 115.025)
		(end 207.875 115.025)
		(width 0.25)
		(layer "F.Cu")
		(net 1)
	)
	(segment
		(start 205.15 116.32)
		(end 205.15 117.35)
		(width 0.25)
		(layer "F.Cu")
		(net 1)
	)
	(segment
		(start 166.14 123.55)
		(end 167.925 123.55)
		(width 0.25)
		(layer "F.Cu")
		(net 1)
	)
	(segment
		(start 193.028173 118.124)
		(end 195.323173 115.829)
		(width 0.25)
		(layer "F.Cu")
		(net 1)
	)
	(segment
		(start 166.14 129.95)
		(end 167.925 129.95)
		(width 0.25)
		(layer "F.Cu")
		(net 1)
	)
	(segment
		(start 205.58 120.32)
		(end 205.15 120.32)
		(width 0.25)
		(layer "F.Cu")
		(net 1)
	)
	(segment
		(start 168.8 123.7)
		(end 168.65 123.85)
		(width 0.25)
		(layer "F.Cu")
		(net 1)
	)
	(segment
		(start 197.226494 129.743247)
		(end 197.375741 129.594)
		(width 0.25)
		(layer "F.Cu")
		(net 1)
	)
	(segment
		(start 193.85 135.05)
		(end 193.9 135)
		(width 0.25)
		(layer "F.Cu")
		(net 1)
	)
	(segment
		(start 179.007 115.224)
		(end 179.007 115.447)
		(width 0.25)
		(layer "F.Cu")
		(net 1)
	)
	(segment
		(start 176.1445 118.773)
		(end 175.8955 119.022)
		(width 0.25)
		(layer "F.Cu")
		(net 1)
	)
	(segment
		(start 182.2 130.4)
		(end 181.55 131.05)
		(width 0.25)
		(layer "F.Cu")
		(net 1)
	)
	(via
		(at 173.538326 124.734619)
		(size 0.6)
		(drill 0.25)
		(layers "F.Cu" "B.Cu")
		(net 1)
	)
	(via
		(at 168.15 121.7)
		(size 0.6)
		(drill 0.25)
		(layers "F.Cu" "B.Cu")
		(net 1)
	)
	(via
		(at 202.8 133.3)
		(size 0.6)
		(drill 0.25)
		(layers "F.Cu" "B.Cu")
		(free yes)
		(net 1)
	)
	(via
		(at 179.8 134.35)
		(size 0.6)
		(drill 0.25)
		(layers "F.Cu" "B.Cu")
		(net 1)
	)
	(via
		(at 197.226494 129.743247)
		(size 0.6)
		(drill 0.25)
		(layers "F.Cu" "B.Cu")
		(net 1)
	)
	(via
		(at 202.8 131.65)
		(size 0.6)
		(drill 0.25)
		(layers "F.Cu" "B.Cu")
		(net 1)
	)
	(via
		(at 186.967 135.925)
		(size 0.6)
		(drill 0.25)
		(layers "F.Cu" "B.Cu")
		(free yes)
		(net 1)
	)
	(via
		(at 173.1 135.25)
		(size 0.6)
		(drill 0.25)
		(layers "F.Cu" "B.Cu")
		(net 1)
	)
	(via
		(at 180.5 131.05)
		(size 0.6)
		(drill 0.25)
		(layers "F.Cu" "B.Cu")
		(net 1)
	)
	(via
		(at 200.45 115.4)
		(size 0.6)
		(drill 0.25)
		(layers "F.Cu" "B.Cu")
		(net 1)
	)
	(via
		(at 176.85 137.3)
		(size 0.6)
		(drill 0.25)
		(layers "F.Cu" "B.Cu")
		(net 1)
	)
	(via
		(at 167.15 122.7)
		(size 0.6)
		(drill 0.25)
		(layers "F.Cu" "B.Cu")
		(net 1)
	)
	(via
		(at 203.175 134.45)
		(size 0.6)
		(drill 0.25)
		(layers "F.Cu" "B.Cu")
		(free yes)
		(net 1)
	)
	(via
		(at 191.687 118.253)
		(size 0.6)
		(drill 0.25)
		(layers "F.Cu" "B.Cu")
		(net 1)
	)
	(via
		(at 200.5 137.4)
		(size 0.6)
		(drill 0.25)
		(layers "F.Cu" "B.Cu")
		(free yes)
		(net 1)
	)
	(via
		(at 196.6 135.5)
		(size 0.6)
		(drill 0.25)
		(layers "F.Cu" "B.Cu")
		(free yes)
		(net 1)
	)
	(via
		(at 172.226 115.433)
		(size 0.6)
		(drill 0.25)
		(layers "F.Cu" "B.Cu")
		(free yes)
		(net 1)
	)
	(via
		(at 170.85 137.3)
		(size 0.6)
		(drill 0.25)
		(layers "F.Cu" "B.Cu")
		(net 1)
	)
	(via
		(at 169.526227 126.758326)
		(size 0.6)
		(drill 0.25)
		(layers "F.Cu" "B.Cu")
		(net 1)
	)
	(via
		(at 203.75 121)
		(size 0.6)
		(drill 0.25)
		(layers "F.Cu" "B.Cu")
		(net 1)
	)
	(via
		(at 203.397 128.2505)
		(size 0.6)
		(drill 0.25)
		(layers "F.Cu" "B.Cu")
		(net 1)
	)
	(via
		(at 177.984 122.251)
		(size 0.6)
		(drill 0.25)
		(layers "F.Cu" "B.Cu")
		(net 1)
	)
	(via
		(at 176.85 136.15)
		(size 0.6)
		(drill 0.25)
		(layers "F.Cu" "B.Cu")
		(net 1)
	)
	(via
		(at 189.5 128.9)
		(size 0.6)
		(drill 0.25)
		(layers "F.Cu" "B.Cu")
		(free yes)
		(net 1)
	)
	(via
		(at 173.8 135.25)
		(size 0.6)
		(drill 0.25)
		(layers "F.Cu" "B.Cu")
		(net 1)
	)
	(via
		(at 193.9 135)
		(size 0.6)
		(drill 0.25)
		(layers "F.Cu" "B.Cu")
		(free yes)
		(net 1)
	)
	(via
		(at 165.4 132.7)
		(size 0.6)
		(drill 0.25)
		(layers "F.Cu" "B.Cu")
		(free yes)
		(net 1)
	)
	(via
		(at 175.05 134.9)
		(size 0.6)
		(drill 0.25)
		(layers "F.Cu" "B.Cu")
		(net 1)
	)
	(via
		(at 179.8 138.35)
		(size 0.6)
		(drill 0.25)
		(layers "F.Cu" "B.Cu")
		(net 1)
	)
	(via
		(at 170.85 135)
		(size 0.6)
		(drill 0.25)
		(layers "F.Cu" "B.Cu")
		(net 1)
	)
	(via
		(at 203.75 114.55)
		(size 0.6)
		(drill 0.25)
		(layers "F.Cu" "B.Cu")
		(net 1)
	)
	(via
		(at 191.9 135)
		(size 0.6)
		(drill 0.25)
		(layers "F.Cu" "B.Cu")
		(free yes)
		(net 1)
	)
	(via
		(at 193.5 133.6)
		(size 0.6)
		(drill 0.25)
		(layers "F.Cu" "B.Cu")
		(free yes)
		(net 1)
	)
	(via
		(at 202.5 114.45)
		(size 0.6)
		(drill 0.25)
		(layers "F.Cu" "B.Cu")
		(net 1)
	)
	(via
		(at 166.8 132.15)
		(size 0.6)
		(drill 0.25)
		(layers "F.Cu" "B.Cu")
		(net 1)
	)
	(via
		(at 186.99 123.176)
		(size 0.6)
		(drill 0.25)
		(layers "F.Cu" "B.Cu")
		(free yes)
		(net 1)
	)
	(via
		(at 179.076 116.321)
		(size 0.6)
		(drill 0.25)
		(layers "F.Cu" "B.Cu")
		(net 1)
	)
	(via
		(at 178.3 129.35)
		(size 0.6)
		(drill 0.25)
		(layers "F.Cu" "B.Cu")
		(net 1)
	)
	(via
		(at 189.8 133.4)
		(size 0.6)
		(drill 0.25)
		(layers "F.Cu" "B.Cu")
		(free yes)
		(net 1)
	)
	(via
		(at 189.3 137.9)
		(size 0.6)
		(drill 0.25)
		(layers "F.Cu" "B.Cu")
		(free yes)
		(net 1)
	)
	(via
		(at 168.65 129.65)
		(size 0.6)
		(drill 0.25)
		(layers "F.Cu" "B.Cu")
		(net 1)
	)
	(via
		(at 170.85 136.15)
		(size 0.6)
		(drill 0.25)
		(layers "F.Cu" "B.Cu")
		(net 1)
	)
	(via
		(at 191.601 126.626)
		(size 0.6)
		(drill 0.25)
		(layers "F.Cu" "B.Cu")
		(net 1)
	)
	(via
		(at 167.15 121.7)
		(size 0.6)
		(drill 0.25)
		(layers "F.Cu" "B.Cu")
		(net 1)
	)
	(via
		(at 196.422 138.524)
		(size 0.6)
		(drill 0.25)
		(layers "F.Cu" "B.Cu")
		(free yes)
		(net 1)
	)
	(via
		(at 206.787 130.792)
		(size 0.6)
		(drill 0.25)
		(layers "F.Cu" "B.Cu")
		(free yes)
		(net 1)
	)
	(via
		(at 188.75 126.25)
		(size 0.6)
		(drill 0.25)
		(layers "F.Cu" "B.Cu")
		(free yes)
		(net 1)
	)
	(via
		(at 179.81 136.3)
		(size 0.6)
		(drill 0.25)
		(layers "F.Cu" "B.Cu")
		(net 1)
	)
	(via
		(at 181.443 117.68)
		(size 0.6)
		(drill 0.25)
		(layers "F.Cu" "B.Cu")
		(net 1)
	)
	(via
		(at 173.6495 121.84)
		(size 0.6)
		(drill 0.25)
		(layers "F.Cu" "B.Cu")
		(net 1)
	)
	(via
		(at 168.15 122.7)
		(size 0.6)
		(drill 0.25)
		(layers "F.Cu" "B.Cu")
		(net 1)
	)
	(via
		(at 168.65 123.85)
		(size 0.6)
		(drill 0.25)
		(layers "F.Cu" "B.Cu")
		(net 1)
	)
	(via
		(at 191.4 132.5)
		(size 0.6)
		(drill 0.25)
		(layers "F.Cu" "B.Cu")
		(free yes)
		(net 1)
	)
	(via
		(at 188.659622 118.453622)
		(size 0.6)
		(drill 0.25)
		(layers "F.Cu" "B.Cu")
		(net 1)
	)
	(via
		(at 179.1955 120.263)
		(size 0.6)
		(drill 0.25)
		(layers "F.Cu" "B.Cu")
		(net 1)
	)
	(via
		(at 188 127.5)
		(size 0.6)
		(drill 0.25)
		(layers "F.Cu" "B.Cu")
		(free yes)
		(net 1)
	)
	(segment
		(start 203.5 116.05)
		(end 202.5 115.05)
		(width 0.25)
		(layer "B.Cu")
		(net 1)
	)
	(segment
		(start 204.8 116.05)
		(end 203.5 116.05)
		(width 0.25)
		(layer "B.Cu")
		(net 1)
	)
	(segment
		(start 202.5 115.05)
		(end 202.5 114.45)
		(width 0.25)
		(layer "B.Cu")
		(net 1)
	)
	(segment
		(start 202.4 115.45)
		(end 200.5 115.45)
		(width 0.25)
		(layer "In1.Cu")
		(net 1)
	)
	(segment
		(start 203.75 114.55)
		(end 203.3 114.55)
		(width 0.25)
		(layer "In1.Cu")
		(net 1)
	)
	(segment
		(start 203.75 121)
		(end 203.75 114.55)
		(width 0.25)
		(layer "In1.Cu")
		(net 1)
	)
	(segment
		(start 200.5 115.45)
		(end 200.45 115.4)
		(width 0.25)
		(layer "In1.Cu")
		(net 1)
	)
	(segment
		(start 203.3 114.55)
		(end 202.4 115.45)
		(width 0.25)
		(layer "In1.Cu")
		(net 1)
	)
	(segment
		(start 182.195 117.703)
		(end 182.195 118.5135)
		(width 0.25)
		(layer "F.Cu")
		(net 2)
	)
	(segment
		(start 188.194 124.603)
		(end 188.062 124.603)
		(width 0.25)
		(layer "F.Cu")
		(net 2)
	)
	(segment
		(start 205.15 119.35)
		(end 205.15 118.32)
		(width 0.25)
		(layer "F.Cu")
		(net 2)
	)
	(segment
		(start 188.85 127.043)
		(end 188.632 126.825)
		(width 0.25)
		(layer "F.Cu")
		(net 2)
	)
	(segment
		(start 198.579 138.112)
		(end 197.214 138.112)
		(width 0.25)
		(layer "F.Cu")
		(net 2)
	)
	(segment
		(start 204.8255 129.75)
		(end 203.147 129.75)
		(width 0.25)
		(layer "F.Cu")
		(net 2)
	)
	(segment
		(start 198.015 130.3)
		(end 197.385 130.3)
		(width 0.25)
		(layer "F.Cu")
		(net 2)
	)
	(segment
		(start 188.632 126.825)
		(end 188.511827 126.825)
		(width 0.25)
		(layer "F.Cu")
		(net 2)
	)
	(segment
		(start 188.511827 126.825)
		(end 188.396827 126.71)
		(width 0.25)
		(layer "F.Cu")
		(net 2)
	)
	(segment
		(start 185.994 124.603)
		(end 186.126 124.603)
		(width 0.25)
		(layer "F.Cu")
		(net 2)
	)
	(segment
		(start 205.75 116.725001)
		(end 205.75 118.15)
		(width 0.25)
		(layer "F.Cu")
		(net 2)
	)
	(segment
		(start 196.815 129.247)
		(end 197.063 128.999)
		(width 0.25)
		(layer "F.Cu")
		(net 2)
	)
	(segment
		(start 186.126 124.603)
		(end 187.094 125.571)
		(width 0.25)
		(layer "F.Cu")
		(net 2)
	)
	(segment
		(start 188.396827 126.71)
		(end 187.63 126.71)
		(width 0.25)
		(layer "F.Cu")
		(net 2)
	)
	(segment
		(start 197.995 128.495)
		(end 197.995 128.999)
		(width 0.25)
		(layer "F.Cu")
		(net 2)
	)
	(segment
		(start 192.6 123.5)
		(end 192.644 123.544)
		(width 0.25)
		(layer "F.Cu")
		(net 2)
	)
	(segment
		(start 204.85 119.35)
		(end 204.35 119.85)
		(width 0.25)
		(layer "F.Cu")
		(net 2)
	)
	(segment
		(start 205.715 119.285)
		(end 205.65 119.35)
		(width 0.25)
		(layer "F.Cu")
		(net 2)
	)
	(segment
		(start 202.131 129.812)
		(end 201.985 129.666)
		(width 0.25)
		(layer "F.Cu")
		(net 2)
	)
	(segment
		(start 182.195 118.5135)
		(end 182.244 118.5625)
		(width 0.25)
		(layer "F.Cu")
		(net 2)
	)
	(segment
		(start 192.644 123.544)
		(end 192.644 124.602)
		(width 0.25)
		(layer "F.Cu")
		(net 2)
	)
	(segment
		(start 185.369 117.597)
		(end 184.395 117.597)
		(width 0.25)
		(layer "F.Cu")
		(net 2)
	)
	(segment
		(start 203.147 129.75)
		(end 203.085 129.812)
		(width 0.25)
		(layer "F.Cu")
		(net 2)
	)
	(segment
		(start 183.65 137.25)
		(end 183.75 137.25)
		(width 0.25)
		(layer "F.Cu")
		(net 2)
	)
	(segment
		(start 195.684 117)
		(end 200.05 117)
		(width 0.25)
		(layer "F.Cu")
		(net 2)
	)
	(segment
		(start 188.85 127.748)
		(end 188.85 127.043)
		(width 0.25)
		(layer "F.Cu")
		(net 2)
	)
	(segment
		(start 183.75 137.25)
		(end 184.05 136.95)
		(width 0.25)
		(layer "F.Cu")
		(net 2)
	)
	(segment
		(start 206.475001 116.325)
		(end 206.150001 116.325)
		(width 0.25)
		(layer "F.Cu")
		(net 2)
	)
	(segment
		(start 206.075 115.025)
		(end 205.75 115.35)
		(width 0.25)
		(layer "F.Cu")
		(net 2)
	)
	(segment
		(start 198.015 133.6)
		(end 197.243 133.6)
		(width 0.25)
		(layer "F.Cu")
		(net 2)
	)
	(segment
		(start 197.385 130.3)
		(end 197.193 130.492)
		(width 0.25)
		(layer "F.Cu")
		(net 2)
	)
	(segment
		(start 205.15 115.35)
		(end 205.15 114.55)
		(width 0.25)
		(layer "F.Cu")
		(net 2)
	)
	(segment
		(start 201.865 116.335)
		(end 201.25 116.335)
		(width 0.25)
		(layer "F.Cu")
		(net 2)
	)
	(segment
		(start 179.352 128.1555)
		(end 179.647 127.8605)
		(width 0.25)
		(layer "F.Cu")
		(net 2)
	)
	(segment
		(start 187.094 126.174)
		(end 187.094 125.571)
		(width 0.25)
		(layer "F.Cu")
		(net 2)
	)
	(segment
		(start 206.475001 115.025)
		(end 206.075 115.025)
		(width 0.25)
		(layer "F.Cu")
		(net 2)
	)
	(segment
		(start 198.385 128.105)
		(end 197.995 128.495)
		(width 0.25)
		(layer "F.Cu")
		(net 2)
	)
	(segment
		(start 200.6 117.55)
		(end 200.05 117)
		(width 0.25)
		(layer "F.Cu")
		(net 2)
	)
	(segment
		(start 196.951 137.849)
		(end 195.199 137.849)
		(width 0.25)
		(layer "F.Cu")
		(net 2)
	)
	(segment
		(start 182.5 137.45)
		(end 182.7 137.25)
		(width 0.25)
		(layer "F.Cu")
		(net 2)
	)
	(segment
		(start 197.063 128.999)
		(end 197.995 128.999)
		(width 0.25)
		(layer "F.Cu")
		(net 2)
	)
	(segment
		(start 207.15 119.285)
		(end 205.715 119.285)
		(width 0.25)
		(layer "F.Cu")
		(net 2)
	)
	(segment
		(start 201.25 116.335)
		(end 200.715 116.335)
		(width 0.25)
		(layer "F.Cu")
		(net 2)
	)
	(segment
		(start 190.238 119.079)
		(end 190.235 119.082)
		(width 0.25)
		(layer "F.Cu")
		(net 2)
	)
	(segment
		(start 197.759 137.227)
		(end 197.573 137.227)
		(width 0.25)
		(layer "F.Cu")
		(net 2)
	)
	(segment
		(start 197.243 133.6)
		(end 197.225 133.618)
		(width 0.25)
		(layer "F.Cu")
		(net 2)
	)
	(segment
		(start 203.75 118.32)
		(end 205.15 118.32)
		(width 0.25)
		(layer "F.Cu")
		(net 2)
	)
	(segment
		(start 200.715 116.335)
		(end 200.05 117)
		(width 0.25)
		(layer "F.Cu")
		(net 2)
	)
	(segment
		(start 206.150001 116.325)
		(end 205.75 116.725001)
		(width 0.25)
		(layer "F.Cu")
		(net 2)
	)
	(segment
		(start 173.6 132.55)
		(end 174.485 132.55)
		(width 0.25)
		(layer "F.Cu")
		(net 2)
	)
	(segment
		(start 202.09 116.11)
		(end 201.865 116.335)
		(width 0.25)
		(layer "F.Cu")
		(net 2)
	)
	(segment
		(start 185.090547 124.560547)
		(end 185.133 124.603)
		(width 0.25)
		(layer "F.Cu")
		(net 2)
	)
	(segment
		(start 194.35 137)
		(end 194.35 136.25)
		(width 0.25)
		(layer "F.Cu")
		(net 2)
	)
	(segment
		(start 208.525 115.675)
		(end 207.875 115.675)
		(width 0.25)
		(layer "F.Cu")
		(net 2)
	)
	(segment
		(start 179.647 127.8605)
		(end 179.647 126.797)
		(width 0.25)
		(layer "F.Cu")
		(net 2)
	)
	(segment
		(start 190.353 117.597)
		(end 190.238 117.597)
		(width 0.25)
		(layer "F.Cu")
		(net 2)
	)
	(segment
		(start 190.238 117.597)
		(end 190.238 119.079)
		(width 0.25)
		(layer "F.Cu")
		(net 2)
	)
	(segment
		(start 197.573 137.227)
		(end 196.951 137.849)
		(width 0.25)
		(layer "F.Cu")
		(net 2)
	)
	(segment
		(start 201.985 129.666)
		(end 201.202 129.666)
		(width 0.25)
		(layer "F.Cu")
		(net 2)
	)
	(segment
		(start 200.6 119)
		(end 200.6 117.55)
		(width 0.25)
		(layer "F.Cu")
		(net 2)
	)
	(segment
		(start 185.133 124.603)
		(end 185.994 124.603)
		(width 0.25)
		(layer "F.Cu")
		(net 2)
	)
	(segment
		(start 184.960547 124.560547)
		(end 185.090547 124.560547)
		(width 0.25)
		(layer "F.Cu")
		(net 2)
	)
	(segment
		(start 202.5 116.75)
		(end 202.5 116.11)
		(width 0.25)
		(layer "F.Cu")
		(net 2)
	)
	(segment
		(start 174.485 132.55)
		(end 175.05 133.115)
		(width 0.25)
		(layer "F.Cu")
		(net 2)
	)
	(segment
		(start 190.931 118.175)
		(end 190.353 117.597)
		(width 0.25)
		(layer "F.Cu")
		(net 2)
	)
	(segment
		(start 207.875 115.675)
		(end 207.225 116.325)
		(width 0.25)
		(layer "F.Cu")
		(net 2)
	)
	(segment
		(start 193.406 119.278)
		(end 195.684 117)
		(width 0.25)
		(layer "F.Cu")
		(net 2)
	)
	(segment
		(start 195.199 137.849)
		(end 194.35 137)
		(width 0.25)
		(layer "F.Cu")
		(net 2)
	)
	(segment
		(start 207.225 116.325)
		(end 206.475001 116.325)
		(width 0.25)
		(layer "F.Cu")
		(net 2)
	)
	(segment
		(start 205.75 118.15)
		(end 205.58 118.32)
		(width 0.25)
		(layer "F.Cu")
		(net 2)
	)
	(segment
		(start 187.63 126.71)
		(end 187.094 126.174)
		(width 0.25)
		(layer "F.Cu")
		(net 2)
	)
	(segment
		(start 183.24584 122.65734)
		(end 182.251 121.6625)
		(width 0.25)
		(layer "F.Cu")
		(net 2)
	)
	(segment
		(start 205.75 115.35)
		(end 205.15 115.35)
		(width 0.25)
		(layer "F.Cu")
		(net 2)
	)
	(segment
		(start 184.395 117.597)
		(end 184.362 117.63)
		(width 0.25)
		(layer "F.Cu")
		(net 2)
	)
	(segment
		(start 195.848 129.247)
		(end 196.815 129.247)
		(width 0.25)
		(layer "F.Cu")
		(net 2)
	)
	(segment
		(start 182.7 137.25)
		(end 183.65 137.25)
		(width 0.25)
		(layer "F.Cu")
		(net 2)
	)
	(segment
		(start 205.15 119.35)
		(end 204.85 119.35)
		(width 0.25)
		(layer "F.Cu")
		(net 2)
	)
	(segment
		(start 182.5 137.915)
		(end 182.5 137.45)
		(width 0.25)
		(layer "F.Cu")
		(net 2)
	)
	(segment
		(start 201.202 129.666)
		(end 201.2 129.668)
		(width 0.25)
		(layer "F.Cu")
		(net 2)
	)
	(segment
		(start 183.752903 122.65734)
		(end 183.24584 122.65734)
		(width 0.25)
		(layer "F.Cu")
		(net 2)
	)
	(segment
		(start 197.214 138.112)
		(end 196.951 137.849)
		(width 0.25)
		(layer "F.Cu")
		(net 2)
	)
	(segment
		(start 205.58 118.32)
		(end 205.15 118.32)
		(width 0.25)
		(layer "F.Cu")
		(net 2)
	)
	(segment
		(start 205.65 119.35)
		(end 205.15 119.35)
		(width 0.25)
		(layer "F.Cu")
		(net 2)
	)
	(segment
		(start 202.5 116.11)
		(end 202.09 116.11)
		(width 0.25)
		(layer "F.Cu")
		(net 2)
	)
	(segment
		(start 188.062 124.603)
		(end 187.094 125.571)
		(width 0.25)
		(layer "F.Cu")
		(net 2)
	)
	(segment
		(start 203.085 129.812)
		(end 202.131 129.812)
		(width 0.25)
		(layer "F.Cu")
		(net 2)
	)
	(via
		(at 184.05 136.95)
		(size 0.6)
		(drill 0.25)
		(layers "F.Cu" "B.Cu")
		(net 2)
	)
	(via
		(at 192.6 123.5)
		(size 0.6)
		(drill 0.25)
		(layers "F.Cu" "B.Cu")
		(net 2)
	)
	(via
		(at 205.15 114.55)
		(size 0.6)
		(drill 0.25)
		(layers "F.Cu" "B.Cu")
		(net 2)
	)
	(via
		(at 172.075 128.9)
		(size 0.6)
		(drill 0.25)
		(layers "F.Cu" "B.Cu")
		(net 2)
	)
	(via
		(at 182.195 117.703)
		(size 0.6)
		(drill 0.25)
		(layers "F.Cu" "B.Cu")
		(net 2)
	)
	(via
		(at 197.193 130.492)
		(size 0.6)
		(drill 0.25)
		(layers "F.Cu" "B.Cu")
		(net 2)
	)
	(via
		(at 172.929122 128.079122)
		(size 0.6)
		(drill 0.25)
		(layers "F.Cu" "B.Cu")
		(net 2)
	)
	(via
		(at 184.960547 124.560547)
		(size 0.6)
		(drill 0.25)
		(layers "F.Cu" "B.Cu")
		(net 2)
	)
	(via
		(at 204.35 119.85)
		(size 0.6)
		(drill 0.25)
		(layers "F.Cu" "B.Cu")
		(net 2)
	)
	(via
		(at 184.362 117.63)
		(size 0.6)
		(drill 0.25)
		(layers "F.Cu" "B.Cu")
		(net 2)
	)
	(via
		(at 190.931 118.175)
		(size 0.6)
		(drill 0.25)
		(layers "F.Cu" "B.Cu")
		(net 2)
	)
	(via
		(at 198.579 138.112)
		(size 0.6)
		(drill 0.25)
		(layers "F.Cu" "B.Cu")
		(net 2)
	)
	(via
		(at 197.225 133.618)
		(size 0.6)
		(drill 0.25)
		(layers "F.Cu" "B.Cu")
		(net 2)
	)
	(via
		(at 198.385 128.105)
		(size 0.6)
		(drill 0.25)
		(layers "F.Cu" "B.Cu")
		(net 2)
	)
	(via
		(at 193.406 119.278)
		(size 0.6)
		(drill 0.25)
		(layers "F.Cu" "B.Cu")
		(net 2)
	)
	(via
		(at 200.6 119)
		(size 0.6)
		(drill 0.25)
		(layers "F.Cu" "B.Cu")
		(net 2)
	)
	(via
		(at 179.352 128.1555)
		(size 0.6)
		(drill 0.25)
		(layers "F.Cu" "B.Cu")
		(net 2)
	)
	(via
		(at 183.752903 122.65734)
		(size 0.6)
		(drill 0.25)
		(layers "F.Cu" "B.Cu")
		(net 2)
	)
	(via
		(at 202.5 116.75)
		(size 0.6)
		(drill 0.25)
		(layers "F.Cu" "B.Cu")
		(net 2)
	)
	(via
		(at 172.1 128.025)
		(size 0.6)
		(drill 0.25)
		(layers "F.Cu" "B.Cu")
		(net 2)
	)
	(via
		(at 201.2 129.668)
		(size 0.6)
		(drill 0.25)
		(layers "F.Cu" "B.Cu")
		(net 2)
	)
	(segment
		(start 202.8 117.05)
		(end 202.5 116.75)
		(width 0.25)
		(layer "B.Cu")
		(net 2)
	)
	(segment
		(start 204.8 117.05)
		(end 202.8 117.05)
		(width 0.25)
		(layer "B.Cu")
		(net 2)
	)
	(segment
		(start 201.45 119.85)
		(end 200.6 119)
		(width 0.25)
		(layer "B.Cu")
		(net 2)
	)
	(segment
		(start 204.35 119.85)
		(end 201.45 119.85)
		(width 0.25)
		(layer "B.Cu")
		(net 2)
	)
	(segment
		(start 205.15 114.55)
		(end 205.15 119.35)
		(width 0.25)
		(layer "In1.Cu")
		(net 2)
	)
	(segment
		(start 204.65 119.85)
		(end 205.15 119.35)
		(width 0.25)
		(layer "In1.Cu")
		(net 2)
	)
	(segment
		(start 204.35 119.85)
		(end 204.65 119.85)
		(width 0.25)
		(layer "In1.Cu")
		(net 2)
	)
	(segment
		(start 165.565 131.865)
		(end 167.3 133.6)
		(width 0.25)
		(layer "F.Cu")
		(net 3)
	)
	(segment
		(start 169.065 136.15)
		(end 169.065 135)
		(width 0.25)
		(layer "F.Cu")
		(net 3)
	)
	(segment
		(start 169.065 134.765)
		(end 168.55 134.25)
		(width 0.25)
		(layer "F.Cu")
		(net 3)
	)
	(segment
		(start 165.565 131.07)
		(end 165.565 131.865)
		(width 0.25)
		(layer "F.Cu")
		(net 3)
	)
	(segment
		(start 167.3 133.6)
		(end 168.55 133.6)
		(width 0.25)
		(layer "F.Cu")
		(net 3)
	)
	(segment
		(start 168.55 134.25)
		(end 168.55 133.6)
		(width 0.25)
		(layer "F.Cu")
		(net 3)
	)
	(segment
		(start 169.065 135)
		(end 169.065 134.765)
		(width 0.25)
		(layer "F.Cu")
		(net 3)
	)
	(segment
		(start 161.385 122.43)
		(end 161.385 131.07)
		(width 0.25)
		(layer "In2.Cu")
		(net 3)
	)
	(segment
		(start 161.385 131.07)
		(end 165.565 131.07)
		(width 0.25)
		(layer "In2.Cu")
		(net 3)
	)
	(segment
		(start 165.565 122.43)
		(end 161.385 122.43)
		(width 0.25)
		(layer "In2.Cu")
		(net 3)
	)
	(segment
		(start 170.0445 125.5005)
		(end 170.495 125.05)
		(width 0.15)
		(layer "F.Cu")
		(net 4)
	)
	(segment
		(start 170.495 125.05)
		(end 170.495 123.725)
		(width 0.15)
		(layer "F.Cu")
		(net 4)
	)
	(segment
		(start 168.517537 125.5005)
		(end 170.0445 125.5005)
		(width 0.15)
		(layer "F.Cu")
		(net 4)
	)
	(segment
		(start 166.895264 125.256)
		(end 168.273037 125.256)
		(width 0.15)
		(layer "F.Cu")
		(net 4)
	)
	(segment
		(start 170.495 123.725)
		(end 170.47 123.7)
		(width 0.15)
		(layer "F.Cu")
		(net 4)
	)
	(segment
		(start 166.651264 125.5)
		(end 166.895264 125.256)
		(width 0.15)
		(layer "F.Cu")
		(net 4)
	)
	(segment
		(start 166.14 125.5)
		(end 166.651264 125.5)
		(width 0.15)
		(layer "F.Cu")
		(net 4)
	)
	(segment
		(start 168.273037 125.256)
		(end 168.517537 125.5005)
		(width 0.15)
		(layer "F.Cu")
		(net 4)
	)
	(segment
		(start 170.47 129.8)
		(end 170.47 128.475)
		(width 0.15)
		(layer "F.Cu")
		(net 5)
	)
	(segment
		(start 168.5 128)
		(end 170.045 128)
		(width 0.15)
		(layer "F.Cu")
		(net 5)
	)
	(segment
		(start 168 128.5)
		(end 168.5 128)
		(width 0.15)
		(layer "F.Cu")
		(net 5)
	)
	(segment
		(start 166.14 128.5)
		(end 168 128.5)
		(width 0.15)
		(layer "F.Cu")
		(net 5)
	)
	(segment
		(start 170.045 128)
		(end 170.495 128.45)
		(width 0.15)
		(layer "F.Cu")
		(net 5)
	)
	(segment
		(start 170.47 128.475)
		(end 170.495 128.45)
		(width 0.15)
		(layer "F.Cu")
		(net 5)
	)
	(segment
		(start 172.720999 119.832)
		(end 172.782999 119.77)
		(width 0.182)
		(layer "F.Cu")
		(net 6)
	)
	(segment
		(start 170.991712 126.578)
		(end 171.272 126.297712)
		(width 0.182)
		(layer "F.Cu")
		(net 6)
	)
	(segment
		(start 166.161 126.509)
		(end 166.152 126.5)
		(width 0.182)
		(layer "F.Cu")
		(net 6)
	)
	(segment
		(start 172.782999 119.77)
		(end 173.4205 119.77)
		(width 0.182)
		(layer "F.Cu")
		(net 6)
	)
	(segment
		(start 168.947 126.36)
		(end 169.138 126.169)
		(width 0.182)
		(layer "F.Cu")
		(net 6)
	)
	(segment
		(start 169.138 126.169)
		(end 170.179 126.169)
		(width 0.182)
		(layer "F.Cu")
		(net 6)
	)
	(segment
		(start 166.963 126.509)
		(end 166.161 126.509)
		(width 0.182)
		(layer "F.Cu")
		(net 6)
	)
	(segment
		(start 166.152 127.498)
		(end 166.195 127.541)
		(width 0.182)
		(layer "F.Cu")
		(net 6)
	)
	(segment
		(start 168.947 126.367)
		(end 168.947 126.36)
		(width 0.182)
		(layer "F.Cu")
		(net 6)
	)
	(segment
		(start 170.588 126.578)
		(end 170.991712 126.578)
		(width 0.182)
		(layer "F.Cu")
		(net 6)
	)
	(segment
		(start 168.0595 127.541)
		(end 168.06 127.5405)
		(width 0.182)
		(layer "F.Cu")
		(net 6)
	)
	(segment
		(start 166.195 127.541)
		(end 168.0595 127.541)
		(width 0.182)
		(layer "F.Cu")
		(net 6)
	)
	(segment
		(start 168.058 126.367)
		(end 167.105 126.367)
		(width 0.182)
		(layer "F.Cu")
		(net 6)
	)
	(segment
		(start 170.179 126.169)
		(end 170.588 126.578)
		(width 0.182)
		(layer "F.Cu")
		(net 6)
	)
	(segment
		(start 171.272 120.641712)
		(end 172.081712 119.832)
		(width 0.182)
		(layer "F.Cu")
		(net 6)
	)
	(segment
		(start 167.105 126.367)
		(end 166.963 126.509)
		(width 0.182)
		(layer "F.Cu")
		(net 6)
	)
	(segment
		(start 172.081712 119.832)
		(end 172.720999 119.832)
		(width 0.182)
		(layer "F.Cu")
		(net 6)
	)
	(segment
		(start 168.947 126.367)
		(end 168.058 126.367)
		(width 0.182)
		(layer "F.Cu")
		(net 6)
	)
	(segment
		(start 171.272 126.297712)
		(end 171.272 120.641712)
		(width 0.182)
		(layer "F.Cu")
		(net 6)
	)
	(via
		(at 168.058 126.367)
		(size 0.6)
		(drill 0.25)
		(layers "F.Cu" "B.Cu")
		(net 6)
	)
	(via
		(at 168.06 127.5405)
		(size 0.6)
		(drill 0.25)
		(layers "F.Cu" "B.Cu")
		(net 6)
	)
	(segment
		(start 168.06 127.5405)
		(end 168.06 126.369)
		(width 0.182)
		(layer "B.Cu")
		(net 6)
	)
	(segment
		(start 168.06 126.369)
		(end 168.058 126.367)
		(width 0.182)
		(layer "B.Cu")
		(net 6)
	)
	(segment
		(start 167.2135 126)
		(end 166.152 126)
		(width 0.182)
		(layer "F.Cu")
		(net 7)
	)
	(segment
		(start 167.437 127)
		(end 168.78 127)
		(width 0.182)
		(layer "F.Cu")
		(net 7)
	)
	(segment
		(start 171.65 120.798288)
		(end 172.238288 120.21)
		(width 0.182)
		(layer "F.Cu")
		(net 7)
	)
	(segment
		(start 172.782999 120.272)
		(end 173.4205 120.272)
		(width 0.182)
		(layer "F.Cu")
		(net 7)
	)
	(segment
		(start 170.628 126.956)
		(end 171.148288 126.956)
		(width 0.182)
		(layer "F.Cu")
		(net 7)
	)
	(segment
		(start 172.238288 120.21)
		(end 172.720999 120.21)
		(width 0.182)
		(layer "F.Cu")
		(net 7)
	)
	(segment
		(start 168.947 127.167)
		(end 169.004 127.167)
		(width 0.182)
		(layer "F.Cu")
		(net 7)
	)
	(segment
		(start 172.720999 120.21)
		(end 172.782999 120.272)
		(width 0.182)
		(layer "F.Cu")
		(net 7)
	)
	(segment
		(start 169.215 127.378)
		(end 170.206 127.378)
		(width 0.182)
		(layer "F.Cu")
		(net 7)
	)
	(segment
		(start 171.65 126.454288)
		(end 171.65 120.798288)
		(width 0.182)
		(layer "F.Cu")
		(net 7)
	)
	(segment
		(start 167.433 125.7805)
		(end 167.2135 126)
		(width 0.182)
		(layer "F.Cu")
		(net 7)
	)
	(segment
		(start 171.148288 126.956)
		(end 171.65 126.454288)
		(width 0.182)
		(layer "F.Cu")
		(net 7)
	)
	(segment
		(start 168.78 127)
		(end 168.947 127.167)
		(width 0.182)
		(layer "F.Cu")
		(net 7)
	)
	(segment
		(start 170.206 127.378)
		(end 170.628 126.956)
		(width 0.182)
		(layer "F.Cu")
		(net 7)
	)
	(segment
		(start 166.152 126.998)
		(end 167.435 126.998)
		(width 0.182)
		(layer "F.Cu")
		(net 7)
	)
	(segment
		(start 167.435 126.998)
		(end 167.437 127)
		(width 0.182)
		(layer "F.Cu")
		(net 7)
	)
	(segment
		(start 169.004 127.167)
		(end 169.215 127.378)
		(width 0.182)
		(layer "F.Cu")
		(net 7)
	)
	(via
		(at 167.433 125.7805)
		(size 0.6)
		(drill 0.25)
		(layers "F.Cu" "B.Cu")
		(net 7)
	)
	(via
		(at 167.437 127)
		(size 0.6)
		(drill 0.25)
		(layers "F.Cu" "B.Cu")
		(net 7)
	)
	(segment
		(start 167.437 127)
		(end 167.437 125.7845)
		(width 0.182)
		(layer "B.Cu")
		(net 7)
	)
	(segment
		(start 167.437 125.7845)
		(end 167.433 125.7805)
		(width 0.182)
		(layer "B.Cu")
		(net 7)
	)
	(segment
		(start 202.05 118.3)
		(end 202.8 119.05)
		(width 0.15)
		(layer "F.Cu")
		(net 8)
	)
	(segment
		(start 193.744 123.737)
		(end 193.744 124.602)
		(width 0.15)
		(layer "F.Cu")
		(net 8)
	)
	(segment
		(start 199.9 128.6)
		(end 199.9 130.05)
		(width 0.15)
		(layer "F.Cu")
		(net 8)
	)
	(segment
		(start 199.9 130.05)
		(end 199.65 130.3)
		(width 0.15)
		(layer "F.Cu")
		(net 8)
	)
	(segment
		(start 197.465 126.751)
		(end 194.7 123.986)
		(width 0.15)
		(layer "F.Cu")
		(net 8)
	)
	(segment
		(start 198.589 126.751)
		(end 197.465 126.751)
		(width 0.15)
		(layer "F.Cu")
		(net 8)
	)
	(segment
		(start 192.744 120.946)
		(end 192.744 118.745)
		(width 0.15)
		(layer "F.Cu")
		(net 8)
	)
	(segment
		(start 194.7 122.902)
		(end 192.744 120.946)
		(width 0.15)
		(layer "F.Cu")
		(net 8)
	)
	(segment
		(start 192.531 121.159)
		(end 192.744 120.946)
		(width 0.15)
		(layer "F.Cu")
		(net 8)
	)
	(segment
		(start 194.7 123.986)
		(end 194.7 122.902)
		(width 0.15)
		(layer "F.Cu")
		(net 8)
	)
	(segment
		(start 191.718 121.615)
		(end 190.235 121.615)
		(width 0.15)
		(layer "F.Cu")
		(net 8)
	)
	(segment
		(start 200.4 127.849)
		(end 201.849 127.849)
		(width 0.15)
		(layer "F.Cu")
		(net 8)
	)
	(segment
		(start 208.55 119.285)
		(end 208.55 118.6)
		(width 0.15)
		(layer "F.Cu")
		(net 8)
	)
	(segment
		(start 208.525 117.425)
		(end 207.95 118)
		(width 0.15)
		(layer "F.Cu")
		(net 8)
	)
	(segment
		(start 199.65 130.3)
		(end 198.985 130.3)
		(width 0.15)
		(layer "F.Cu")
		(net 8)
	)
	(segment
		(start 204.785 127.75)
		(end 204.76 127.725)
		(width 0.15)
		(layer "F.Cu")
		(net 8)
	)
	(segment
		(start 190.444 124.602)
		(end 190.444 124.419)
		(width 0.15)
		(layer "F.Cu")
		(net 8)
	)
	(segment
		(start 199.9 128.062)
		(end 200.113 127.849)
		(width 0.15)
		(layer "F.Cu")
		(net 8)
	)
	(segment
		(start 199.9 128.062)
		(end 199.9 128.6)
		(width 0.15)
		(layer "F.Cu")
		(net 8)
	)
	(segment
		(start 204.76 127.725)
		(end 202.1 127.725)
		(width 0.15)
		(layer "F.Cu")
		(net 8)
	)
	(segment
		(start 208.55 118.6)
		(end 207.95 118)
		(width 0.15)
		(layer "F.Cu")
		(net 8)
	)
	(segment
		(start 191.976 122.887)
		(end 191.976 121.873)
		(width 0.15)
		(layer "F.Cu")
		(net 8)
	)
	(segment
		(start 191.976 121.873)
		(end 191.718 121.615)
		(width 0.15)
		(layer "F.Cu")
		(net 8)
	)
	(segment
		(start 208.525 116.975)
		(end 208.525 117.425)
		(width 0.15)
		(layer "F.Cu")
		(net 8)
	)
	(segment
		(start 190.444 124.419)
		(end 191.976 122.887)
		(width 0.15)
		(layer "F.Cu")
		(net 8)
	)
	(segment
		(start 200.113 127.849)
		(end 200.4 127.849)
		(width 0.15)
		(layer "F.Cu")
		(net 8)
	)
	(segment
		(start 198.985 130.3)
		(end 198.985 131.4)
		(width 0.15)
		(layer "F.Cu")
		(net 8)
	)
	(segment
		(start 192.894 122.887)
		(end 193.744 123.737)
		(width 0.15)
		(layer "F.Cu")
		(net 8)
	)
	(segment
		(start 199.404 127.566)
		(end 198.589 126.751)
		(width 0.15)
		(layer "F.Cu")
		(net 8)
	)
	(segment
		(start 191.718 121.615)
		(end 192.174 121.159)
		(width 0.15)
		(layer "F.Cu")
		(net 8)
	)
	(segment
		(start 202.1 127.725)
		(end 201.925 127.9)
		(width 0.15)
		(layer "F.Cu")
		(net 8)
	)
	(segment
		(start 192.174 121.159)
		(end 192.531 121.159)
		(width 0.15)
		(layer "F.Cu")
		(net 8)
	)
	(segment
		(start 192.744 118.745)
		(end 192.79 118.699)
		(width 0.15)
		(layer "F.Cu")
		(net 8)
	)
	(segment
		(start 191.976 122.887)
		(end 192.894 122.887)
		(width 0.15)
		(layer "F.Cu")
		(net 8)
	)
	(segment
		(start 199.9 128.062)
		(end 199.404 127.566)
		(width 0.15)
		(layer "F.Cu")
		(net 8)
	)
	(via
		(at 207.95 118)
		(size 0.6)
		(drill 0.25)
		(layers "F.Cu" "B.Cu")
		(net 8)
	)
	(via
		(at 202.8 119.05)
		(size 0.6)
		(drill 0.25)
		(layers "F.Cu" "B.Cu")
		(net 8)
	)
	(via
		(at 192.79 118.699)
		(size 0.6)
		(drill 0.25)
		(layers "F.Cu" "B.Cu")
		(net 8)
	)
	(segment
		(start 202.8 119.05)
		(end 204.8 119.05)
		(width 0.15)
		(layer "B.Cu")
		(net 8)
	)
	(segment
		(start 202.439 119.05)
		(end 202.8 119.05)
		(width 0.15)
		(layer "B.Cu")
		(net 8)
	)
	(segment
		(start 199.947 116.558)
		(end 202.439 119.05)
		(width 0.15)
		(layer "B.Cu")
		(net 8)
	)
	(segment
		(start 192.79 118.699)
		(end 194.931 116.558)
		(width 0.15)
		(layer "B.Cu")
		(net 8)
	)
	(segment
		(start 194.931 116.558)
		(end 199.947 116.558)
		(width 0.15)
		(layer "B.Cu")
		(net 8)
	)
	(segment
		(start 207.95 118)
		(end 207.825 118.125)
		(width 0.15)
		(layer "In2.Cu")
		(net 8)
	)
	(segment
		(start 207.825 118.125)
		(end 203.725 118.125)
		(width 0.15)
		(layer "In2.Cu")
		(net 8)
	)
	(segment
		(start 203.725 118.125)
		(end 202.8 119.05)
		(width 0.15)
		(layer "In2.Cu")
		(net 8)
	)
	(segment
		(start 199 134.75)
		(end 199 133.615)
		(width 0.15)
		(layer "F.Cu")
		(net 9)
	)
	(segment
		(start 202.025 117.6)
		(end 202.55 117.6)
		(width 0.15)
		(layer "F.Cu")
		(net 9)
	)
	(segment
		(start 188.95 122.887)
		(end 190.235 122.887)
		(width 0.15)
		(layer "F.Cu")
		(net 9)
	)
	(segment
		(start 206.248 128.556)
		(end 206.052 128.752)
		(width 0.15)
		(layer "F.Cu")
		(net 9)
	)
	(segment
		(start 200.65 132.2)
		(end 200.35 132.5)
		(width 0.15)
		(layer "F.Cu")
		(net 9)
	)
	(segment
		(start 195 122.777736)
		(end 195 123.824)
		(width 0.15)
		(layer "F.Cu")
		(net 9)
	)
	(segment
		(start 201.925 128.6)
		(end 201.1 128.6)
		(width 0.15)
		(layer "F.Cu")
		(net 9)
	)
	(segment
		(start 188.925 122.912)
		(end 188.95 122.887)
		(width 0.15)
		(layer "F.Cu")
		(net 9)
	)
	(segment
		(start 200.65 129.05)
		(end 200.65 132.2)
		(width 0.15)
		(layer "F.Cu")
		(net 9)
	)
	(segment
		(start 204.785 128.75)
		(end 204.76 128.775)
		(width 0.15)
		(layer "F.Cu")
		(net 9)
	)
	(segment
		(start 208.975 116.325)
		(end 209.25 116.6)
		(width 0.15)
		(layer "F.Cu")
		(net 9)
	)
	(segment
		(start 197.627 126.451)
		(end 205.303 126.451)
		(width 0.15)
		(layer "F.Cu")
		(net 9)
	)
	(segment
		(start 209.25 117.85)
		(end 209.1 118)
		(width 0.15)
		(layer "F.Cu")
		(net 9)
	)
	(segment
		(start 202.55 117.6)
		(end 202.8 117.85)
		(width 0.15)
		(layer "F.Cu")
		(net 9)
	)
	(segment
		(start 188.458 122.395)
		(end 188.95 122.887)
		(width 0.15)
		(layer "F.Cu")
		(net 9)
	)
	(segment
		(start 208.55 120.085)
		(end 209.25 119.385)
		(width 0.15)
		(layer "F.Cu")
		(net 9)
	)
	(segment
		(start 209.25 118.15)
		(end 209.1 118)
		(width 0.15)
		(layer "F.Cu")
		(net 9)
	)
	(segment
		(start 204.76 128.775)
		(end 202.1 128.775)
		(width 0.15)
		(layer "F.Cu")
		(net 9)
	)
	(segment
		(start 194.542 121.166)
		(end 194.542 122.319736)
		(width 0.15)
		(layer "F.Cu")
		(net 9)
	)
	(segment
		(start 209.25 116.6)
		(end 209.25 117.85)
		(width 0.15)
		(layer "F.Cu")
		(net 9)
	)
	(segment
		(start 202.1 128.775)
		(end 201.925 128.6)
		(width 0.15)
		(layer "F.Cu")
		(net 9)
	)
	(segment
		(start 189.344 124.325)
		(end 188.925 123.906)
		(width 0.15)
		(layer "F.Cu")
		(net 9)
	)
	(segment
		(start 194.542 122.319736)
		(end 195 122.777736)
		(width 0.15)
		(layer "F.Cu")
		(net 9)
	)
	(segment
		(start 199 133.615)
		(end 198.985 133.6)
		(width 0.15)
		(layer "F.Cu")
		(net 9)
	)
	(segment
		(start 206.052 128.752)
		(end 204.8255 128.752)
		(width 0.15)
		(layer "F.Cu")
		(net 9)
	)
	(segment
		(start 198.985 133.6)
		(end 198.985 132.5)
		(width 0.15)
		(layer "F.Cu")
		(net 9)
	)
	(segment
		(start 208.525 116.325)
		(end 208.975 116.325)
		(width 0.15)
		(layer "F.Cu")
		(net 9)
	)
	(segment
		(start 206.248 127.396)
		(end 206.248 128.556)
		(width 0.15)
		(layer "F.Cu")
		(net 9)
	)
	(segment
		(start 189.344 124.602)
		(end 189.344 124.325)
		(width 0.15)
		(layer "F.Cu")
		(net 9)
	)
	(segment
		(start 200.35 132.5)
		(end 198.985 132.5)
		(width 0.15)
		(layer "F.Cu")
		(net 9)
	)
	(segment
		(start 201.1 128.6)
		(end 200.65 129.05)
		(width 0.15)
		(layer "F.Cu")
		(net 9)
	)
	(segment
		(start 209.25 119.385)
		(end 209.25 118.15)
		(width 0.15)
		(layer "F.Cu")
		(net 9)
	)
	(segment
		(start 188.925 123.906)
		(end 188.925 122.912)
		(width 0.15)
		(layer "F.Cu")
		(net 9)
	)
	(segment
		(start 195 123.824)
		(end 197.627 126.451)
		(width 0.15)
		(layer "F.Cu")
		(net 9)
	)
	(segment
		(start 205.303 126.451)
		(end 206.248 127.396)
		(width 0.15)
		(layer "F.Cu")
		(net 9)
	)
	(via
		(at 194.542 121.166)
		(size 0.6)
		(drill 0.25)
		(layers "F.Cu" "B.Cu")
		(net 9)
	)
	(via
		(at 202.8 117.85)
		(size 0.6)
		(drill 0.25)
		(layers "F.Cu" "B.Cu")
		(net 9)
	)
	(via
		(at 209.1 118)
		(size 0.6)
		(drill 0.25)
		(layers "F.Cu" "B.Cu")
		(net 9)
	)
	(via
		(at 188.458 122.395)
		(size 0.6)
		(drill 0.25)
		(layers "F.Cu" "B.Cu")
		(net 9)
	)
	(segment
		(start 194.703537 116.043)
		(end 188.458 122.288537)
		(width 0.15)
		(layer "B.Cu")
		(net 9)
	)
	(segment
		(start 202.021 117.85)
		(end 200.214 116.043)
		(width 0.15)
		(layer "B.Cu")
		(net 9)
	)
	(segment
		(start 203 118.05)
		(end 204.8 118.05)
		(width 0.15)
		(layer "B.Cu")
		(net 9)
	)
	(segment
		(start 188.458 122.395)
		(end 193.313 122.395)
		(width 0.15)
		(layer "B.Cu")
		(net 9)
	)
	(segment
		(start 200.214 116.043)
		(end 194.703537 116.043)
		(width 0.15)
		(layer "B.Cu")
		(net 9)
	)
	(segment
		(start 202.8 117.85)
		(end 203 118.05)
		(width 0.15)
		(layer "B.Cu")
		(net 9)
	)
	(segment
		(start 188.458 122.288537)
		(end 188.458 122.395)
		(width 0.15)
		(layer "B.Cu")
		(net 9)
	)
	(segment
		(start 202.8 117.85)
		(end 202.021 117.85)
		(width 0.15)
		(layer "B.Cu")
		(net 9)
	)
	(segment
		(start 193.313 122.395)
		(end 194.542 121.166)
		(width 0.15)
		(layer "B.Cu")
		(net 9)
	)
	(segment
		(start 203.575 117.075)
		(end 202.8 117.85)
		(width 0.15)
		(layer "In2.Cu")
		(net 9)
	)
	(segment
		(start 208.175 117.075)
		(end 203.575 117.075)
		(width 0.15)
		(layer "In2.Cu")
		(net 9)
	)
	(segment
		(start 209.1 118)
		(end 208.175 117.075)
		(width 0.15)
		(layer "In2.Cu")
		(net 9)
	)
	(segment
		(start 175.065 136.15)
		(end 174.4 136.815)
		(width 0.15)
		(layer "F.Cu")
		(net 10)
	)
	(segment
		(start 174.4 137.013)
		(end 172.9 138.513)
		(width 0.15)
		(layer "F.Cu")
		(net 10)
	)
	(segment
		(start 172.9 138.513)
		(end 172.9 138.7)
		(width 0.15)
		(layer "F.Cu")
		(net 10)
	)
	(segment
		(start 174.4 136.815)
		(end 174.4 137.013)
		(width 0.15)
		(layer "F.Cu")
		(net 10)
	)
	(segment
		(start 175.85 138.085)
		(end 175.065 137.3)
		(width 0.15)
		(layer "F.Cu")
		(net 11)
	)
	(segment
		(start 175.85 138.7)
		(end 175.85 138.085)
		(width 0.15)
		(layer "F.Cu")
		(net 11)
	)
	(segment
		(start 175.1 139.45)
		(end 174.35 138.7)
		(width 0.15)
		(layer "F.Cu")
		(net 12)
	)
	(segment
		(start 188.1525 136.4)
		(end 188.3025 136.25)
		(width 0.15)
		(layer "F.Cu")
		(net 12)
	)
	(segment
		(start 188.3025 136.25)
		(end 188.85 136.25)
		(width 0.15)
		(layer "F.Cu")
		(net 12)
	)
	(via
		(at 188.1525 136.4)
		(size 0.6)
		(drill 0.25)
		(layers "F.Cu" "B.Cu")
		(net 12)
	)
	(via
		(at 175.1 139.45)
		(size 0.6)
		(drill 0.25)
		(layers "F.Cu" "B.Cu")
		(net 12)
	)
	(segment
		(start 175.2 139.55)
		(end 175.1 139.45)
		(width 0.15)
		(layer "In2.Cu")
		(net 12)
	)
	(segment
		(start 188.1525 136.4)
		(end 187.35 137.2025)
		(width 0.15)
		(layer "In2.Cu")
		(net 12)
	)
	(segment
		(start 187.05 139.55)
		(end 175.2 139.55)
		(width 0.15)
		(layer "In2.Cu")
		(net 12)
	)
	(segment
		(start 187.35 137.2025)
		(end 187.35 139.25)
		(width 0.15)
		(layer "In2.Cu")
		(net 12)
	)
	(segment
		(start 187.35 139.25)
		(end 187.05 139.55)
		(width 0.15)
		(layer "In2.Cu")
		(net 12)
	)
	(segment
		(start 181.67 123.51)
		(end 181.38 123.8)
		(width 0.15)
		(layer "F.Cu")
		(net 13)
	)
	(segment
		(start 192.307147 129.369853)
		(end 192.348 129.329)
		(width 0.15)
		(layer "F.Cu")
		(net 13)
	)
	(segment
		(start 179.647 124.523)
		(end 179.647 125.827)
		(width 0.15)
		(layer "F.Cu")
		(net 13)
	)
	(segment
		(start 180.37 123.8)
		(end 179.647 124.523)
		(width 0.15)
		(layer "F.Cu")
		(net 13)
	)
	(segment
		(start 179.645 125.825)
		(end 178.615 125.825)
		(width 0.15)
		(layer "F.Cu")
		(net 13)
	)
	(segment
		(start 193.5 116)
		(end 192.71 116.79)
		(width 0.15)
		(layer "F.Cu")
		(net 13)
	)
	(segment
		(start 179.647 125.827)
		(end 179.645 125.825)
		(width 0.15)
		(layer "F.Cu")
		(net 13)
	)
	(segment
		(start 192.71 116.79)
		(end 192.254 116.79)
		(width 0.15)
		(layer "F.Cu")
		(net 13)
	)
	(segment
		(start 181.38 123.8)
		(end 180.37 123.8)
		(width 0.15)
		(layer "F.Cu")
		(net 13)
	)
	(segment
		(start 192.348 129.329)
		(end 192.348 127.748)
		(width 0.15)
		(layer "F.Cu")
		(net 13)
	)
	(via
		(at 192.307147 129.369853)
		(size 0.6)
		(drill 0.25)
		(layers "F.Cu" "B.Cu")
		(net 13)
	)
	(via
		(at 181.67 123.51)
		(size 0.6)
		(drill 0.25)
		(layers "F.Cu" "B.Cu")
		(net 13)
	)
	(via
		(at 192.254 116.79)
		(size 0.6)
		(drill 0.25)
		(layers "F.Cu" "B.Cu")
		(net 13)
	)
	(segment
		(start 184.255 123.512)
		(end 188.488378 119.278622)
		(width 0.15)
		(layer "B.Cu")
		(net 13)
	)
	(segment
		(start 190.977 116.79)
		(end 192.254 116.79)
		(width 0.15)
		(layer "B.Cu")
		(net 13)
	)
	(segment
		(start 183.747884 124.188843)
		(end 184.255 123.681727)
		(width 0.15)
		(layer "B.Cu")
		(net 13)
	)
	(segment
		(start 182.98341 124.188843)
		(end 183.747884 124.188843)
		(width 0.15)
		(layer "B.Cu")
		(net 13)
	)
	(segment
		(start 184.255 123.681727)
		(end 184.255 123.512)
		(width 0.15)
		(layer "B.Cu")
		(net 13)
	)
	(segment
		(start 182.304567 123.51)
		(end 182.98341 124.188843)
		(width 0.15)
		(layer "B.Cu")
		(net 13)
	)
	(segment
		(start 181.67 123.51)
		(end 182.304567 123.51)
		(width 0.15)
		(layer "B.Cu")
		(net 13)
	)
	(segment
		(start 189.956 118.323971)
		(end 189.956 117.811)
		(width 0.15)
		(layer "B.Cu")
		(net 13)
	)
	(segment
		(start 188.488378 119.278622)
		(end 189.001349 119.278622)
		(width 0.15)
		(layer "B.Cu")
		(net 13)
	)
	(segment
		(start 189.956 117.811)
		(end 190.977 116.79)
		(width 0.15)
		(layer "B.Cu")
		(net 13)
	)
	(segment
		(start 189.001349 119.278622)
		(end 189.956 118.323971)
		(width 0.15)
		(layer "B.Cu")
		(net 13)
	)
	(segment
		(start 181.67 123.51)
		(end 182.27 123.51)
		(width 0.15)
		(layer "In2.Cu")
		(net 13)
	)
	(segment
		(start 182.27 123.51)
		(end 182.648843 123.888843)
		(width 0.15)
		(layer "In2.Cu")
		(net 13)
	)
	(segment
		(start 182.648843 123.888843)
		(end 183.528843 123.888843)
		(width 0.15)
		(layer "In2.Cu")
		(net 13)
	)
	(segment
		(start 189.24 129.6)
		(end 191.620485 129.6)
		(width 0.15)
		(layer "In2.Cu")
		(net 13)
	)
	(segment
		(start 191.850632 129.369853)
		(end 192.307147 129.369853)
		(width 0.15)
		(layer "In2.Cu")
		(net 13)
	)
	(segment
		(start 191.620485 129.6)
		(end 191.850632 129.369853)
		(width 0.15)
		(layer "In2.Cu")
		(net 13)
	)
	(segment
		(start 183.528843 123.888843)
		(end 189.24 129.6)
		(width 0.15)
		(layer "In2.Cu")
		(net 13)
	)
	(segment
		(start 186.75 132.25)
		(end 187.35 132.25)
		(width 0.15)
		(layer "F.Cu")
		(net 14)
	)
	(segment
		(start 177.749 124.857)
		(end 177.749 125.293463)
		(width 0.15)
		(layer "F.Cu")
		(net 14)
	)
	(segment
		(start 182.2 136.8)
		(end 183.356795 136.8)
		(width 0.15)
		(layer "F.Cu")
		(net 14)
	)
	(segment
		(start 178.299897 124.306103)
		(end 177.749 124.857)
		(width 0.15)
		(layer "F.Cu")
		(net 14)
	)
	(segment
		(start 188.6 132.1)
		(end 189.2 131.5)
		(width 0.15)
		(layer "F.Cu")
		(net 14)
	)
	(segment
		(start 190.255 116)
		(end 189.656 116.599)
		(width 0.15)
		(layer "F.Cu")
		(net 14)
	)
	(segment
		(start 181.9 138.285)
		(end 181.9 137.1)
		(width 0.15)
		(layer "F.Cu")
		(net 14)
	)
	(segment
		(start 183.93 136.226795)
		(end 183.93 135.07)
		(width 0.15)
		(layer "F.Cu")
		(net 14)
	)
	(segment
		(start 183.93 135.07)
		(end 186.75 132.25)
		(width 0.15)
		(layer "F.Cu")
		(net 14)
	)
	(segment
		(start 181.9 137.1)
		(end 182.2 136.8)
		(width 0.15)
		(layer "F.Cu")
		(net 14)
	)
	(segment
		(start 183.356795 136.8)
		(end 183.93 136.226795)
		(width 0.15)
		(layer "F.Cu")
		(net 14)
	)
	(segment
		(start 177.609 125.433463)
		(end 177.609 125.58)
		(width 0.15)
		(layer "F.Cu")
		(net 14)
	)
	(segment
		(start 178.450464 124.306103)
		(end 178.299897 124.306103)
		(width 0.15)
		(layer "F.Cu")
		(net 14)
	)
	(segment
		(start 177.749 125.293463)
		(end 177.609 125.433463)
		(width 0.15)
		(layer "F.Cu")
		(net 14)
	)
	(segment
		(start 191 116)
		(end 190.255 116)
		(width 0.15)
		(layer "F.Cu")
		(net 14)
	)
	(segment
		(start 188.453 132.247)
		(end 188.6 132.1)
		(width 0.15)
		(layer "F.Cu")
		(net 14)
	)
	(segment
		(start 189.2 131.5)
		(end 189.2015 131.5)
		(width 0.15)
		(layer "F.Cu")
		(net 14)
	)
	(segment
		(start 177.609 125.58)
		(end 177.364 125.825)
		(width 0.15)
		(layer "F.Cu")
		(net 14)
	)
	(segment
		(start 182.5 138.885)
		(end 181.9 138.285)
		(width 0.15)
		(layer "F.Cu")
		(net 14)
	)
	(segment
		(start 187.35 132.247)
		(end 188.453 132.247)
		(width 0.15)
		(layer "F.Cu")
		(net 14)
	)
	(via
		(at 189.2015 131.5)
		(size 0.6)
		(drill 0.25)
		(layers "F.Cu" "B.Cu")
		(net 14)
	)
	(via
		(at 189.656 116.599)
		(size 0.6)
		(drill 0.25)
		(layers "F.Cu" "B.Cu")
		(net 14)
	)
	(via
		(at 178.450464 124.306103)
		(size 0.6)
		(drill 0.25)
		(layers "F.Cu" "B.Cu")
		(net 14)
	)
	(via
		(at 180.6 123.2)
		(size 0.6)
		(drill 0.25)
		(layers "F.Cu" "B.Cu")
		(net 14)
	)
	(segment
		(start 188.173378 118.978622)
		(end 188.877085 118.978622)
		(width 0.15)
		(layer "B.Cu")
		(net 14)
	)
	(segment
		(start 189.656 118.199707)
		(end 189.656 116.599)
		(width 0.15)
		(layer "B.Cu")
		(net 14)
	)
	(segment
		(start 183.107674 123.888843)
		(end 183.62362 123.888843)
		(width 0.15)
		(layer "B.Cu")
		(net 14)
	)
	(segment
		(start 182.118831 122.9)
		(end 183.107674 123.888843)
		(width 0.15)
		(layer "B.Cu")
		(net 14)
	)
	(segment
		(start 183.955 123.197)
		(end 188.173378 118.978622)
		(width 0.15)
		(layer "B.Cu")
		(net 14)
	)
	(segment
		(start 180.6 123.2)
		(end 180.9 122.9)
		(width 0.15)
		(layer "B.Cu")
		(net 14)
	)
	(segment
		(start 188.877085 118.978622)
		(end 189.656 118.199707)
		(width 0.15)
		(layer "B.Cu")
		(net 14)
	)
	(segment
		(start 183.62362 123.888843)
		(end 183.955 123.557463)
		(width 0.15)
		(layer "B.Cu")
		(net 14)
	)
	(segment
		(start 180.9 122.9)
		(end 182.118831 122.9)
		(width 0.15)
		(layer "B.Cu")
		(net 14)
	)
	(segment
		(start 183.955 123.557463)
		(end 183.955 123.197)
		(width 0.15)
		(layer "B.Cu")
		(net 14)
	)
	(segment
		(start 185.9 128.7)
		(end 184.116727 128.7)
		(width 0.15)
		(layer "In2.Cu")
		(net 14)
	)
	(segment
		(start 181.4 128.7)
		(end 178.450464 125.750464)
		(width 0.15)
		(layer "In2.Cu")
		(net 14)
	)
	(segment
		(start 184.116727 128.7)
		(end 184.091727 128.725)
		(width 0.15)
		(layer "In2.Cu")
		(net 14)
	)
	(segment
		(start 180.6 123.2)
		(end 179.556567 123.2)
		(width 0.15)
		(layer "In2.Cu")
		(net 14)
	)
	(segment
		(start 183.250736 128.725)
		(end 183.225736 128.7)
		(width 0.15)
		(layer "In2.Cu")
		(net 14)
	)
	(segment
		(start 179.556567 123.2)
		(end 178.450464 124.306103)
		(width 0.15)
		(layer "In2.Cu")
		(net 14)
	)
	(segment
		(start 178.450464 125.750464)
		(end 178.450464 124.306103)
		(width 0.15)
		(layer "In2.Cu")
		(net 14)
	)
	(segment
		(start 184.091727 128.725)
		(end 183.250736 128.725)
		(width 0.15)
		(layer "In2.Cu")
		(net 14)
	)
	(segment
		(start 183.225736 128.7)
		(end 181.4 128.7)
		(width 0.15)
		(layer "In2.Cu")
		(net 14)
	)
	(segment
		(start 189.2015 131.5)
		(end 188.7 131.5)
		(width 0.15)
		(layer "In2.Cu")
		(net 14)
	)
	(segment
		(start 188.7 131.5)
		(end 185.9 128.7)
		(width 0.15)
		(layer "In2.Cu")
		(net 14)
	)
	(segment
		(start 194.372 126.571)
		(end 194.75 126.949)
		(width 0.15)
		(layer "F.Cu")
		(net 15)
	)
	(segment
		(start 191.91 120.614)
		(end 191.641 120.345)
		(width 0.15)
		(layer "F.Cu")
		(net 15)
	)
	(segment
		(start 192.664177 121.859579)
		(end 194.372 123.567402)
		(width 0.15)
		(layer "F.Cu")
		(net 15)
	)
	(segment
		(start 194.372 123.567402)
		(end 194.372 126.571)
		(width 0.15)
		(layer "F.Cu")
		(net 15)
	)
	(segment
		(start 197.7 134.75)
		(end 195.85 134.75)
		(width 0.15)
		(layer "F.Cu")
		(net 15)
	)
	(segment
		(start 194.75 126.949)
		(end 194.75 134.35)
		(width 0.15)
		(layer "F.Cu")
		(net 15)
	)
	(segment
		(start 194.75 134.35)
		(end 195.148 134.748)
		(width 0.15)
		(layer "F.Cu")
		(net 15)
	)
	(segment
		(start 186.339 117.597)
		(end 186.339 118.011)
		(width 0.15)
		(layer "F.Cu")
		(net 15)
	)
	(segment
		(start 186.339 118.011)
		(end 188.673 120.345)
		(width 0.15)
		(layer "F.Cu")
		(net 15)
	)
	(segment
		(start 199 136.05)
		(end 197.7 134.75)
		(width 0.15)
		(layer "F.Cu")
		(net 15)
	)
	(segment
		(start 188.673 120.345)
		(end 190.235 120.345)
		(width 0.15)
		(layer "F.Cu")
		(net 15)
	)
	(segment
		(start 191.641 120.345)
		(end 190.235 120.345)
		(width 0.15)
		(layer "F.Cu")
		(net 15)
	)
	(segment
		(start 195.148 134.748)
		(end 195.848 134.748)
		(width 0.15)
		(layer "F.Cu")
		(net 15)
	)
	(via
		(at 191.91 120.614)
		(size 0.6)
		(drill 0.25)
		(layers "F.Cu" "B.Cu")
		(net 15)
	)
	(via
		(at 192.664177 121.859579)
		(size 0.6)
		(drill 0.25)
		(layers "F.Cu" "B.Cu")
		(net 15)
	)
	(segment
		(start 192.664177 121.859579)
		(end 191.91 121.105402)
		(width 0.15)
		(layer "B.Cu")
		(net 15)
	)
	(segment
		(start 191.91 121.105402)
		(end 191.91 120.614)
		(width 0.15)
		(layer "B.Cu")
		(net 15)
	)
	(segment
		(start 186.2 137.865)
		(end 186.25 137.915)
		(width 0.15)
		(layer "F.Cu")
		(net 16)
	)
	(segment
		(start 186.2 134.65)
		(end 186.2 137.865)
		(width 0.15)
		(layer "F.Cu")
		(net 16)
	)
	(segment
		(start 186.6 134.25)
		(end 186.2 134.65)
		(width 0.15)
		(layer "F.Cu")
		(net 16)
	)
	(segment
		(start 186.25 137.915)
		(end 187.35 137.915)
		(width 0.15)
		(layer "F.Cu")
		(net 16)
	)
	(segment
		(start 187.35 134.25)
		(end 186.6 134.25)
		(width 0.15)
		(layer "F.Cu")
		(net 16)
	)
	(segment
		(start 187.35 133.75)
		(end 186.6 133.75)
		(width 0.15)
		(layer "F.Cu")
		(net 17)
	)
	(segment
		(start 185.85 134.5)
		(end 185.85 137)
		(width 0.15)
		(layer "F.Cu")
		(net 17)
	)
	(segment
		(start 186.6 133.75)
		(end 185.85 134.5)
		(width 0.15)
		(layer "F.Cu")
		(net 17)
	)
	(segment
		(start 185.85 137)
		(end 185.15 137.7)
		(width 0.15)
		(layer "F.Cu")
		(net 17)
	)
	(segment
		(start 185.15 137.915)
		(end 184.05 137.915)
		(width 0.15)
		(layer "F.Cu")
		(net 17)
	)
	(segment
		(start 185.15 137.7)
		(end 185.15 137.915)
		(width 0.15)
		(layer "F.Cu")
		(net 17)
	)
	(segment
		(start 187.9 116.6)
		(end 188.5 116)
		(width 0.15)
		(layer "F.Cu")
		(net 18)
	)
	(segment
		(start 193.849 127.748)
		(end 193.849 130.895568)
		(width 0.15)
		(layer "F.Cu")
		(net 18)
	)
	(segment
		(start 183.75 126.735)
		(end 183.75 127.9)
		(width 0.15)
		(layer "F.Cu")
		(net 18)
	)
	(segment
		(start 187.9 117.53)
		(end 187.9 116.6)
		(width 0.15)
		(layer "F.Cu")
		(net 18)
	)
	(segment
		(start 193.849 130.895568)
		(end 193.425629 131.318939)
		(width 0.15)
		(layer "F.Cu")
		(net 18)
	)
	(via
		(at 187.62 121.122001)
		(size 0.6)
		(drill 0.25)
		(layers "F.Cu" "B.Cu")
		(net 18)
	)
	(via
		(at 187.9 117.53)
		(size 0.6)
		(drill 0.25)
		(layers "F.Cu" "B.Cu")
		(net 18)
	)
	(via
		(at 183.75 127.9)
		(size 0.6)
		(drill 0.25)
		(layers "F.Cu" "B.Cu")
		(net 18)
	)
	(via
		(at 193.425629 131.318939)
		(size 0.6)
		(drill 0.25)
		(layers "F.Cu" "B.Cu")
		(net 18)
	)
	(segment
		(start 183.75 127.530002)
		(end 187.59 123.690002)
		(width 0.15)
		(layer "B.Cu")
		(net 18)
	)
	(segment
		(start 183.75 127.9)
		(end 183.75 127.530002)
		(width 0.15)
		(layer "B.Cu")
		(net 18)
	)
	(segment
		(start 187.59 121.152001)
		(end 187.62 121.122001)
		(width 0.15)
		(layer "B.Cu")
		(net 18)
	)
	(segment
		(start 187.59 123.690002)
		(end 187.59 121.152001)
		(width 0.15)
		(layer "B.Cu")
		(net 18)
	)
	(segment
		(start 185.341736 127.9)
		(end 185.523236 128.0815)
		(width 0.15)
		(layer "In2.Cu")
		(net 18)
	)
	(segment
		(start 187.62 117.81)
		(end 187.9 117.53)
		(width 0.15)
		(layer "In2.Cu")
		(net 18)
	)
	(segment
		(start 191.819 130.5)
		(end 192.637939 131.318939)
		(width 0.15)
		(layer "In2.Cu")
		(net 18)
	)
	(segment
		(start 185.523236 128.0815)
		(end 186.3565 128.0815)
		(width 0.15)
		(layer "In2.Cu")
		(net 18)
	)
	(segment
		(start 186.3565 128.0815)
		(end 188.775 130.5)
		(width 0.15)
		(layer "In2.Cu")
		(net 18)
	)
	(segment
		(start 188.775 130.5)
		(end 191.819 130.5)
		(width 0.15)
		(layer "In2.Cu")
		(net 18)
	)
	(segment
		(start 187.62 121.122001)
		(end 187.62 117.81)
		(width 0.15)
		(layer "In2.Cu")
		(net 18)
	)
	(segment
		(start 192.637939 131.318939)
		(end 193.425629 131.318939)
		(width 0.15)
		(layer "In2.Cu")
		(net 18)
	)
	(segment
		(start 183.75 127.9)
		(end 185.341736 127.9)
		(width 0.15)
		(layer "In2.Cu")
		(net 18)
	)
	(segment
		(start 186.89 119.303757)
		(end 186.89 119.04)
		(width 0.15)
		(layer "F.Cu")
		(net 19)
	)
	(segment
		(start 184.75 126.735)
		(end 185.387348 126.735)
		(width 0.15)
		(layer "F.Cu")
		(net 19)
	)
	(segment
		(start 188.345768 120.759525)
		(end 186.89 119.303757)
		(width 0.15)
		(layer "F.Cu")
		(net 19)
	)
	(segment
		(start 192.648636 130.03704)
		(end 192.849 129.836676)
		(width 0.15)
		(layer "F.Cu")
		(net 19)
	)
	(segment
		(start 184.07 118.27)
		(end 186.173736 118.27)
		(width 0.15)
		(layer "F.Cu")
		(net 19)
	)
	(segment
		(start 186.173736 118.27)
		(end 186.896868 118.993132)
		(width 0.15)
		(layer "F.Cu")
		(net 19)
	)
	(segment
		(start 183.5 116)
		(end 183.5 117.7)
		(width 0.15)
		(layer "F.Cu")
		(net 19)
	)
	(segment
		(start 185.387348 126.735)
		(end 185.908848 127.2565)
		(width 0.15)
		(layer "F.Cu")
		(net 19)
	)
	(segment
		(start 192.849 129.836676)
		(end 192.849 127.748)
		(width 0.15)
		(layer "F.Cu")
		(net 19)
	)
	(segment
		(start 183.5 117.7)
		(end 184.07 118.27)
		(width 0.15)
		(layer "F.Cu")
		(net 19)
	)
	(via
		(at 185.908848 127.2565)
		(size 0.6)
		(drill 0.25)
		(layers "F.Cu" "B.Cu")
		(net 19)
	)
	(via
		(at 188.345768 120.759525)
		(size 0.6)
		(drill 0.25)
		(layers "F.Cu" "B.Cu")
		(net 19)
	)
	(via
		(at 192.648636 130.03704)
		(size 0.6)
		(drill 0.25)
		(layers "F.Cu" "B.Cu")
		(net 19)
	)
	(segment
		(start 187.89 123.36)
		(end 187.89 121.957757)
		(width 0.15)
		(layer "B.Cu")
		(net 19)
	)
	(segment
		(start 185.908848 126.161152)
		(end 186.83 125.24)
		(width 0.15)
		(layer "B.Cu")
		(net 19)
	)
	(segment
		(start 187.89 124.18)
		(end 187.89 123.36)
		(width 0.15)
		(layer "B.Cu")
		(net 19)
	)
	(segment
		(start 188.4 121.447757)
		(end 188.4 121.35)
		(width 0.15)
		(layer "B.Cu")
		(net 19)
	)
	(segment
		(start 188.4 120.813757)
		(end 188.4 121.35)
		(width 0.15)
		(layer "B.Cu")
		(net 19)
	)
	(segment
		(start 186.83 125.24)
		(end 187.89 124.18)
		(width 0.15)
		(layer "B.Cu")
		(net 19)
	)
	(segment
		(start 188.345768 120.759525)
		(end 188.4 120.813757)
		(width 0.15)
		(layer "B.Cu")
		(net 19)
	)
	(segment
		(start 185.908848 127.2565)
		(end 185.908848 126.161152)
		(width 0.15)
		(layer "B.Cu")
		(net 19)
	)
	(segment
		(start 187.89 121.957757)
		(end 188.4 121.447757)
		(width 0.15)
		(layer "B.Cu")
		(net 19)
	)
	(segment
		(start 186.400236 127.2565)
		(end 189.043736 129.9)
		(width 0.15)
		(layer "In2.Cu")
		(net 19)
	)
	(segment
		(start 189.043736 129.9)
		(end 192.077 129.9)
		(width 0.15)
		(layer "In2.Cu")
		(net 19)
	)
	(segment
		(start 185.908848 127.2565)
		(end 186.400236 127.2565)
		(width 0.15)
		(layer "In2.Cu")
		(net 19)
	)
	(segment
		(start 192.077 129.9)
		(end 192.21404 130.03704)
		(width 0.15)
		(layer "In2.Cu")
		(net 19)
	)
	(segment
		(start 192.21404 130.03704)
		(end 192.648636 130.03704)
		(width 0.15)
		(layer "In2.Cu")
		(net 19)
	)
	(segment
		(start 182.75 127.8)
		(end 182.75 126.735)
		(width 0.15)
		(layer "F.Cu")
		(net 20)
	)
	(segment
		(start 194.349 131.458)
		(end 193.83 131.977)
		(width 0.15)
		(layer "F.Cu")
		(net 20)
	)
	(segment
		(start 186.955 116.955)
		(end 186 116)
		(width 0.15)
		(layer "F.Cu")
		(net 20)
	)
	(segment
		(start 194.349 127.748)
		(end 194.349 131.458)
		(width 0.15)
		(layer "F.Cu")
		(net 20)
	)
	(via
		(at 187.027669 121.751669)
		(size 0.6)
		(drill 0.25)
		(layers "F.Cu" "B.Cu")
		(net 20)
	)
	(via
		(at 182.75 127.8)
		(size 0.6)
		(drill 0.25)
		(layers "F.Cu" "B.Cu")
		(net 20)
	)
	(via
		(at 193.83 131.977)
		(size 0.6)
		(drill 0.25)
		(layers "F.Cu" "B.Cu")
		(net 20)
	)
	(via
		(at 186.955 116.955)
		(size 0.6)
		(drill 0.25)
		(layers "F.Cu" "B.Cu")
		(net 20)
	)
	(segment
		(start 182.75 127.8)
		(end 182.75 126.029338)
		(width 0.15)
		(layer "B.Cu")
		(net 20)
	)
	(segment
		(start 182.75 126.029338)
		(end 187.027669 121.751669)
		(width 0.15)
		(layer "B.Cu")
		(net 20)
	)
	(segment
		(start 191.496 130.8)
		(end 192.673 131.977)
		(width 0.15)
		(layer "In2.Cu")
		(net 20)
	)
	(segment
		(start 182.75 127.8)
		(end 183.375 128.425)
		(width 0.15)
		(layer "In2.Cu")
		(net 20)
	)
	(segment
		(start 183.375 128.425)
		(end 183.967463 128.425)
		(width 0.15)
		(layer "In2.Cu")
		(net 20)
	)
	(segment
		(start 188.650736 130.8)
		(end 191.496 130.8)
		(width 0.15)
		(layer "In2.Cu")
		(net 20)
	)
	(segment
		(start 187.027669 117.027669)
		(end 186.955 116.955)
		(width 0.15)
		(layer "In2.Cu")
		(net 20)
	)
	(segment
		(start 187.027669 121.751669)
		(end 187.027669 117.027669)
		(width 0.15)
		(layer "In2.Cu")
		(net 20)
	)
	(segment
		(start 192.673 131.977)
		(end 193.83 131.977)
		(width 0.15)
		(layer "In2.Cu")
		(net 20)
	)
	(segment
		(start 186.232236 128.3815)
		(end 188.650736 130.8)
		(width 0.15)
		(layer "In2.Cu")
		(net 20)
	)
	(segment
		(start 183.967463 128.425)
		(end 184.010963 128.3815)
		(width 0.15)
		(layer "In2.Cu")
		(net 20)
	)
	(segment
		(start 184.010963 128.3815)
		(end 186.232236 128.3815)
		(width 0.15)
		(layer "In2.Cu")
		(net 20)
	)
	(segment
		(start 177.13 124.182)
		(end 176.593 124.719)
		(width 0.15)
		(layer "F.Cu")
		(net 21)
	)
	(segment
		(start 183.405 128.738)
		(end 184.442 129.775)
		(width 0.15)
		(layer "F.Cu")
		(net 21)
	)
	(segment
		(start 176.725 127.025)
		(end 178.438 128.738)
		(width 0.15)
		(layer "F.Cu")
		(net 21)
	)
	(segment
		(start 187.322 129.775)
		(end 187.35 129.747)
		(width 0.15)
		(layer "F.Cu")
		(net 21)
	)
	(segment
		(start 184.442 129.775)
		(end 187.322 129.775)
		(width 0.15)
		(layer "F.Cu")
		(net 21)
	)
	(segment
		(start 176.007037 127.025)
		(end 176.725 127.025)
		(width 0.15)
		(layer "F.Cu")
		(net 21)
	)
	(segment
		(start 177.303 124.182)
		(end 177.13 124.182)
		(width 0.15)
		(layer "F.Cu")
		(net 21)
	)
	(segment
		(start 175.7 126.717963)
		(end 176.007037 127.025)
		(width 0.15)
		(layer "F.Cu")
		(net 21)
	)
	(segment
		(start 176.593 124.719)
		(end 176.593 125.03133)
		(width 0.15)
		(layer "F.Cu")
		(net 21)
	)
	(segment
		(start 176.593 125.03133)
		(end 175.7 125.92433)
		(width 0.15)
		(layer "F.Cu")
		(net 21)
	)
	(segment
		(start 175.7 125.92433)
		(end 175.7 126.717963)
		(width 0.15)
		(layer "F.Cu")
		(net 21)
	)
	(segment
		(start 178.438 128.738)
		(end 183.405 128.738)
		(width 0.15)
		(layer "F.Cu")
		(net 21)
	)
	(segment
		(start 180.604 117.73)
		(end 181 117.334)
		(width 0.15)
		(layer "F.Cu")
		(net 25)
	)
	(segment
		(start 181.744 124.344)
		(end 181.744 125.765)
		(width 0.15)
		(layer "F.Cu")
		(net 25)
	)
	(segment
		(start 180.774 126.735)
		(end 181.744 125.765)
		(width 0.15)
		(layer "F.Cu")
		(net 25)
	)
	(segment
		(start 181 117.334)
		(end 181 116)
		(width 0.15)
		(layer "F.Cu")
		(net 25)
	)
	(segment
		(start 181.7 124.3)
		(end 181.744 124.344)
		(width 0.15)
		(layer "F.Cu")
		(net 25)
	)
	(segment
		(start 180.75 126.735)
		(end 180.774 126.735)
		(width 0.15)
		(layer "F.Cu")
		(net 25)
	)
	(via
		(at 180.604 117.73)
		(size 0.6)
		(drill 0.25)
		(layers "F.Cu" "B.Cu")
		(net 25)
	)
	(via
		(at 181.7 124.3)
		(size 0.6)
		(drill 0.25)
		(layers "F.Cu" "B.Cu")
		(net 25)
	)
	(segment
		(start 181.7 124.3)
		(end 181.145 123.745)
		(width 0.15)
		(layer "In2.Cu")
		(net 25)
	)
	(segment
		(start 181.43 123.007537)
		(end 181.43 118.556)
		(width 0.15)
		(layer "In2.Cu")
		(net 25)
	)
	(segment
		(start 181.145 123.292537)
		(end 181.43 123.007537)
		(width 0.15)
		(layer "In2.Cu")
		(net 25)
	)
	(segment
		(start 181.43 118.556)
		(end 180.604 117.73)
		(width 0.15)
		(layer "In2.Cu")
		(net 25)
	)
	(segment
		(start 181.145 123.745)
		(end 181.145 123.292537)
		(width 0.15)
		(layer "In2.Cu")
		(net 25)
	)
	(segment
		(start 175.1435 123.1345)
		(end 175.209 123.2)
		(width 0.3)
		(layer "F.Cu")
		(net 26)
	)
	(segment
		(start 171.443 127.676)
		(end 171.443 133.4935)
		(width 0.3)
		(layer "F.Cu")
		(net 26)
	)
	(segment
		(start 169.95 138.7)
		(end 171.4 138.7)
		(width 0.3)
		(layer "F.Cu")
		(net 26)
	)
	(segment
		(start 171.443 133.4935)
		(end 171.45 133.5005)
		(width 0.3)
		(layer "F.Cu")
		(net 26)
	)
	(segment
		(start 172.115 137.3)
		(end 172.115 134.853)
		(width 0.3)
		(layer "F.Cu")
		(net 26)
	)
	(segment
		(start 174.175 123.206)
		(end 175.203 123.206)
		(width 0.3)
		(layer "F.Cu")
		(net 26)
	)
	(segment
		(start 175.203 123.206)
		(end 175.209 123.2)
		(width 0.3)
		(layer "F.Cu")
		(net 26)
	)
	(segment
		(start 175.1435 121.498)
		(end 175.1435 123.1345)
		(width 0.25)
		(layer "F.Cu")
		(net 26)
	)
	(segment
		(start 171.4 138.015)
		(end 172.115 137.3)
		(width 0.3)
		(layer "F.Cu")
		(net 26)
	)
	(segment
		(start 171.4 138.7)
		(end 171.4 138.015)
		(width 0.3)
		(layer "F.Cu")
		(net 26)
	)
	(segment
		(start 175.283 123.2)
		(end 176.246 124.163)
		(width 0.3)
		(layer "F.Cu")
		(net 26)
	)
	(segment
		(start 176.218 124.876)
		(end 175.909 125.185)
		(width 0.3)
		(layer "F.Cu")
		(net 26)
	)
	(segment
		(start 173.934 125.185)
		(end 171.443 127.676)
		(width 0.3)
		(layer "F.Cu")
		(net 26)
	)
	(segment
		(start 175.909 125.185)
		(end 173.934 125.185)
		(width 0.3)
		(layer "F.Cu")
		(net 26)
	)
	(segment
		(start 176.218 124.191)
		(end 176.218 124.876)
		(width 0.3)
		(layer "F.Cu")
		(net 26)
	)
	(segment
		(start 171.45 134.188)
		(end 171.45 133.5005)
		(width 0.3)
		(layer "F.Cu")
		(net 26)
	)
	(segment
		(start 175.209 123.2)
		(end 175.283 123.2)
		(width 0.3)
		(layer "F.Cu")
		(net 26)
	)
	(segment
		(start 176.246 124.163)
		(end 176.218 124.191)
		(width 0.3)
		(layer "F.Cu")
		(net 26)
	)
	(segment
		(start 172.115 134.853)
		(end 171.45 134.188)
		(width 0.3)
		(layer "F.Cu")
		(net 26)
	)
	(segment
		(start 167.925 124.35)
		(end 168.035 124.46)
		(width 0.25)
		(layer "F.Cu")
		(net 27)
	)
	(segment
		(start 166.14 124.35)
		(end 167.925 124.35)
		(width 0.25)
		(layer "F.Cu")
		(net 27)
	)
	(segment
		(start 169.066 137.3)
		(end 169.066 137.996)
		(width 0.25)
		(layer "F.Cu")
		(net 27)
	)
	(segment
		(start 166.14 129.15)
		(end 167.925 129.15)
		(width 0.25)
		(layer "F.Cu")
		(net 27)
	)
	(segment
		(start 168.666897 124.908103)
		(end 168.146794 124.388)
		(width 0.25)
		(layer "F.Cu")
		(net 27)
	)
	(segment
		(start 169.066 137.996)
		(end 168.362 138.7)
		(width 0.25)
		(layer "F.Cu")
		(net 27)
	)
	(segment
		(start 167.925 129.15)
		(end 168.035 129.04)
		(width 0.25)
		(layer "F.Cu")
		(net 27)
	)
	(segment
		(start 168.201 129.112)
		(end 168.697 128.616)
		(width 0.25)
		(layer "F.Cu")
		(net 27)
	)
	(segment
		(start 168.146794 124.388)
		(end 168.035 124.388)
		(width 0.25)
		(layer "F.Cu")
		(net 27)
	)
	(segment
		(start 168.035 129.112)
		(end 168.201 129.112)
		(width 0.25)
		(layer "F.Cu")
		(net 27)
	)
	(via
		(at 168.3 137.3)
		(size 0.6)
		(drill 0.25)
		(layers "F.Cu" "B.Cu")
		(net 27)
	)
	(via
		(at 167.5 138.8)
		(size 0.6)
		(drill 0.25)
		(layers "F.Cu" "B.Cu")
		(free yes)
		(net 27)
	)
	(via
		(at 167.6 137.3)
		(size 0.6)
		(drill 0.25)
		(layers "F.Cu" "B.Cu")
		(free yes)
		(net 27)
	)
	(via
		(at 167.551 138)
		(size 0.6)
		(drill 0.25)
		(layers "F.Cu" "B.Cu")
		(net 27)
	)
	(via
		(at 168.666897 124.908103)
		(size 0.6)
		(drill 0.25)
		(layers "F.Cu" "B.Cu")
		(net 27)
	)
	(via
		(at 168.697 128.616)
		(size 0.6)
		(drill 0.25)
		(layers "F.Cu" "B.Cu")
		(net 27)
	)
	(segment
		(start 185.15 129.2505)
		(end 185.1505 129.25)
		(width 0.15)
		(layer "F.Cu")
		(net 28)
	)
	(segment
		(start 185.1505 129.25)
		(end 187.35 129.25)
		(width 0.15)
		(layer "F.Cu")
		(net 28)
	)
	(via
		(at 185.15 129.2505)
		(size 0.6)
		(drill 0.25)
		(layers "F.Cu" "B.Cu")
		(net 28)
	)
	(segment
		(start 172.2 129.55)
		(end 174.1195 127.6305)
		(width 0.15)
		(layer "B.Cu")
		(net 28)
	)
	(segment
		(start 168.75 132.948)
		(end 169.45 132.248)
		(width 0.15)
		(layer "B.Cu")
		(net 28)
	)
	(segment
		(start 185.1495 129.25)
		(end 185.15 129.2505)
		(width 0.15)
		(layer "B.Cu")
		(net 28)
	)
	(segment
		(start 169.45 129.85)
		(end 169.75 129.55)
		(width 0.15)
		(layer "B.Cu")
		(net 28)
	)
	(segment
		(start 169.75 129.55)
		(end 172.2 129.55)
		(width 0.15)
		(layer "B.Cu")
		(net 28)
	)
	(segment
		(start 169.45 132.248)
		(end 169.45 129.85)
		(width 0.15)
		(layer "B.Cu")
		(net 28)
	)
	(segment
		(start 174.1195 127.6305)
		(end 179.6805 127.6305)
		(width 0.15)
		(layer "B.Cu")
		(net 28)
	)
	(segment
		(start 185.15 131.85)
		(end 184.05 132.95)
		(width 0.15)
		(layer "B.Cu")
		(net 28)
	)
	(segment
		(start 185.15 129.2505)
		(end 185.15 131.85)
		(width 0.15)
		(layer "B.Cu")
		(net 28)
	)
	(segment
		(start 179.6805 127.6305)
		(end 181.3 129.25)
		(width 0.15)
		(layer "B.Cu")
		(net 28)
	)
	(segment
		(start 181.3 129.25)
		(end 185.1495 129.25)
		(width 0.15)
		(layer "B.Cu")
		(net 28)
	)
	(segment
		(start 177.6455 115.6175)
		(end 178.04 115.223)
		(width 0.2)
		(layer "F.Cu")
		(net 29)
	)
	(segment
		(start 172.514 120.772)
		(end 173.4205 120.772)
		(width 0.2)
		(layer "F.Cu")
		(net 29)
	)
	(segment
		(start 172.226 121.06)
		(end 172.389 120.897)
		(width 0.2)
		(layer "F.Cu")
		(net 29)
	)
	(segment
		(start 172.226 121.345)
		(end 172.226 121.06)
		(width 0.2)
		(layer "F.Cu")
		(net 29)
	)
	(segment
		(start 178.04 115.223)
		(end 177.770934 114.953934)
		(width 0.2)
		(layer "F.Cu")
		(net 29)
	)
	(segment
		(start 173.447104 122.628104)
		(end 172.226 121.407)
		(width 0.2)
		(layer "F.Cu")
		(net 29)
	)
	(segment
		(start 172.389 120.897)
		(end 172.514 120.772)
		(width 0.2)
		(layer "F.Cu")
		(net 29)
	)
	(segment
		(start 177.6455 116.547)
		(end 177.6455 115.6175)
		(width 0.2)
		(layer "F.Cu")
		(net 29)
	)
	(segment
		(start 173.673435 122.628104)
		(end 173.447104 122.628104)
		(width 0.2)
		(layer "F.Cu")
		(net 29)
	)
	(segment
		(start 177.770934 114.953934)
		(end 176.584852 114.953934)
		(width 0.2)
		(layer "F.Cu")
		(net 29)
	)
	(segment
		(start 172.226 121.407)
		(end 172.226 121.06)
		(width 0.2)
		(layer "F.Cu")
		(net 29)
	)
	(via
		(at 173.673435 122.628104)
		(size 0.6)
		(drill 0.25)
		(layers "F.Cu" "B.Cu")
		(net 29)
	)
	(via
		(at 176.584852 114.953934)
		(size 0.6)
		(drill 0.25)
		(layers "F.Cu" "B.Cu")
		(net 29)
	)
	(segment
		(start 173.1 122.068318)
		(end 173.1 115.1)
		(width 0.2)
		(layer "In2.Cu")
		(net 29)
	)
	(segment
		(start 173.673435 122.628104)
		(end 173.659786 122.628104)
		(width 0.2)
		(layer "In2.Cu")
		(net 29)
	)
	(segment
		(start 174.1 114.1)
		(end 176.138384 114.1)
		(width 0.2)
		(layer "In2.Cu")
		(net 29)
	)
	(segment
		(start 176.138384 114.1)
		(end 176.584852 114.546468)
		(width 0.2)
		(layer "In2.Cu")
		(net 29)
	)
	(segment
		(start 176.584852 114.546468)
		(end 176.584852 114.953934)
		(width 0.2)
		(layer "In2.Cu")
		(net 29)
	)
	(segment
		(start 173.659786 122.628104)
		(end 173.1 122.068318)
		(width 0.2)
		(layer "In2.Cu")
		(net 29)
	)
	(segment
		(start 173.1 115.1)
		(end 174.1 114.1)
		(width 0.2)
		(layer "In2.Cu")
		(net 29)
	)
	(segment
		(start 197.291 139.5)
		(end 194.665 139.5)
		(width 0.25)
		(layer "F.Cu")
		(net 30)
	)
	(segment
		(start 192.3 137.55)
		(end 192.85 137)
		(width 0.25)
		(layer "F.Cu")
		(net 30)
	)
	(segment
		(start 194.665 139.5)
		(end 194.05 138.885)
		(width 0.25)
		(layer "F.Cu")
		(net 30)
	)
	(segment
		(start 194.05 138.885)
		(end 192.485 138.885)
		(width 0.25)
		(layer "F.Cu")
		(net 30)
	)
	(segment
		(start 197.8 138.991)
		(end 197.291 139.5)
		(width 0.25)
		(layer "F.Cu")
		(net 30)
	)
	(segment
		(start 192.3 138.7)
		(end 192.3 137.55)
		(width 0.25)
		(layer "F.Cu")
		(net 30)
	)
	(segment
		(start 192.485 138.885)
		(end 192.3 138.7)
		(width 0.25)
		(layer "F.Cu")
		(net 30)
	)
	(segment
		(start 192.85 137)
		(end 192.85 136.25)
		(width 0.25)
		(layer "F.Cu")
		(net 30)
	)
	(segment
		(start 183.6 134.8)
		(end 186.65 131.75)
		(width 0.15)
		(layer "F.Cu")
		(net 31)
	)
	(segment
		(start 183.41 134.8)
		(end 183.6 134.8)
		(width 0.15)
		(layer "F.Cu")
		(net 31)
	)
	(segment
		(start 183.41 135.9)
		(end 182.86 136.45)
		(width 0.15)
		(layer "F.Cu")
		(net 31)
	)
	(segment
		(start 181.01 136.9)
		(end 181.01 138.35)
		(width 0.15)
		(layer "F.Cu")
		(net 31)
	)
	(segment
		(start 182.86 136.45)
		(end 181.46 136.45)
		(width 0.15)
		(layer "F.Cu")
		(net 31)
	)
	(segment
		(start 186.65 131.75)
		(end 187.35 131.75)
		(width 0.15)
		(layer "F.Cu")
		(net 31)
	)
	(segment
		(start 181.46 136.45)
		(end 181.01 136.9)
		(width 0.15)
		(layer "F.Cu")
		(net 31)
	)
	(segment
		(start 183.41 135.9)
		(end 183.41 134.8)
		(width 0.15)
		(layer "F.Cu")
		(net 31)
	)
	(segment
		(start 191.95 138.35)
		(end 191.415 138.885)
		(width 0.15)
		(layer "F.Cu")
		(net 32)
	)
	(segment
		(start 192.35 137.005025)
		(end 191.95 137.405025)
		(width 0.15)
		(layer "F.Cu")
		(net 32)
	)
	(segment
		(start 192.35 136.25)
		(end 192.35 137.005025)
		(width 0.15)
		(layer "F.Cu")
		(net 32)
	)
	(segment
		(start 191.95 137.405025)
		(end 191.95 138.35)
		(width 0.15)
		(layer "F.Cu")
		(net 32)
	)
	(segment
		(start 190.65 138.885)
		(end 190.636 138.899)
		(width 0.15)
		(layer "F.Cu")
		(net 32)
	)
	(segment
		(start 191.415 138.885)
		(end 190.65 138.885)
		(width 0.15)
		(layer "F.Cu")
		(net 32)
	)
	(segment
		(start 183.41 133.75)
		(end 182.44 134.72)
		(width 0.15)
		(layer "F.Cu")
		(net 33)
	)
	(segment
		(start 179.76 135.5)
		(end 181.74 135.5)
		(width 0.15)
		(layer "F.Cu")
		(net 33)
	)
	(segment
		(start 186.7 131.25)
		(end 187.35 131.25)
		(width 0.15)
		(layer "F.Cu")
		(net 33)
	)
	(segment
		(start 183.41 133.7)
		(end 183.41 133.75)
		(width 0.15)
		(layer "F.Cu")
		(net 33)
	)
	(segment
		(start 181.74 135.5)
		(end 182.44 134.8)
		(width 0.15)
		(layer "F.Cu")
		(net 33)
	)
	(segment
		(start 184.25 133.7)
		(end 183.41 133.7)
		(width 0.15)
		(layer "F.Cu")
		(net 33)
	)
	(segment
		(start 178.61 134.35)
		(end 179.76 135.5)
		(width 0.15)
		(layer "F.Cu")
		(net 33)
	)
	(segment
		(start 182.44 134.72)
		(end 182.44 134.8)
		(width 0.15)
		(layer "F.Cu")
		(net 33)
	)
	(segment
		(start 184.25 133.7)
		(end 186.7 131.25)
		(width 0.15)
		(layer "F.Cu")
		(net 33)
	)
	(segment
		(start 174.5 122.455)
		(end 174.6435 122.3115)
		(width 0.15)
		(layer "F.Cu")
		(net 36)
	)
	(segment
		(start 176.246 122.525)
		(end 176.123 122.402)
		(width 0.15)
		(layer "F.Cu")
		(net 36)
	)
	(segment
		(start 176.246 123.193)
		(end 176.246 122.525)
		(width 0.2)
		(layer "F.Cu")
		(net 36)
	)
	(segment
		(start 174.6435 122.3115)
		(end 174.6435 121.498)
		(width 0.2)
		(layer "F.Cu")
		(net 36)
	)
	(via
		(at 174.5 122.455)
		(size 0.6)
		(drill 0.25)
		(layers "F.Cu" "B.Cu")
		(net 36)
	)
	(via
		(at 176.123 122.402)
		(size 0.6)
		(drill 0.25)
		(layers "F.Cu" "B.Cu")
		(net 36)
	)
	(segment
		(start 174.5 122.455)
		(end 174.553 122.402)
		(width 0.15)
		(layer "B.Cu")
		(net 36)
	)
	(segment
		(start 174.553 122.402)
		(end 176.123 122.402)
		(width 0.2)
		(layer "B.Cu")
		(net 36)
	)
	(segment
		(start 182.25 124.25)
		(end 182.25 123.252264)
		(width 0.15)
		(layer "F.Cu")
		(net 37)
	)
	(segment
		(start 179.268736 117.773)
		(end 178.3695 117.773)
		(width 0.15)
		(layer "F.Cu")
		(net 37)
	)
	(segment
		(start 182.75 124.75)
		(end 182.25 124.25)
		(width 0.15)
		(layer "F.Cu")
		(net 37)
	)
	(segment
		(start 181.251368 119.755632)
		(end 179.268736 117.773)
		(width 0.15)
		(layer "F.Cu")
		(net 37)
	)
	(segment
		(start 182.75 125.765)
		(end 182.75 124.75)
		(width 0.15)
		(layer "F.Cu")
		(net 37)
	)
	(segment
		(start 182.25 123.252264)
		(end 181.251368 122.253632)
		(width 0.15)
		(layer "F.Cu")
		(net 37)
	)
	(segment
		(start 181.251368 122.253632)
		(end 181.251368 119.755632)
		(width 0.15)
		(layer "F.Cu")
		(net 37)
	)
	(segment
		(start 183.75 125)
		(end 182.749 123.999)
		(width 0.15)
		(layer "F.Cu")
		(net 38)
	)
	(segment
		(start 179.194 117.274)
		(end 178.3695 117.274)
		(width 0.15)
		(layer "F.Cu")
		(net 38)
	)
	(segment
		(start 182.749 123.327)
		(end 181.607 122.185)
		(width 0.15)
		(layer "F.Cu")
		(net 38)
	)
	(segment
		(start 183.75 125.765)
		(end 183.75 125)
		(width 0.15)
		(layer "F.Cu")
		(net 38)
	)
	(segment
		(start 181.607 122.185)
		(end 181.607 119.687)
		(width 0.15)
		(layer "F.Cu")
		(net 38)
	)
	(segment
		(start 181.607 119.687)
		(end 179.194 117.274)
		(width 0.15)
		(layer "F.Cu")
		(net 38)
	)
	(segment
		(start 182.749 123.999)
		(end 182.749 123.327)
		(width 0.15)
		(layer "F.Cu")
		(net 38)
	)
	(segment
		(start 175.1435 116.547)
		(end 175.1435 115.819905)
		(width 0.15)
		(layer "F.Cu")
		(net 39)
	)
	(segment
		(start 178.205 126.518)
		(end 178.205 125.308394)
		(width 0.15)
		(layer "F.Cu")
		(net 39)
	)
	(segment
		(start 178.482 126.795)
		(end 178.205 126.518)
		(width 0.15)
		(layer "F.Cu")
		(net 39)
	)
	(segment
		(start 175.1435 115.819905)
		(end 175.323475 115.63993)
		(width 0.15)
		(layer "F.Cu")
		(net 39)
	)
	(segment
		(start 178.205 125.308394)
		(end 178.762155 124.751239)
		(width 0.15)
		(layer "F.Cu")
		(net 39)
	)
	(segment
		(start 178.762155 124.751239)
		(end 179.053462 124.751239)
		(width 0.15)
		(layer "F.Cu")
		(net 39)
	)
	(via
		(at 175.323475 115.63993)
		(size 0.6)
		(drill 0.25)
		(layers "F.Cu" "B.Cu")
		(net 39)
	)
	(via
		(at 179.053462 124.751239)
		(size 0.6)
		(drill 0.25)
		(layers "F.Cu" "B.Cu")
		(net 39)
	)
	(segment
		(start 179.053462 124.114462)
		(end 175.323475 120.384475)
		(width 0.15)
		(layer "B.Cu")
		(net 39)
	)
	(segment
		(start 179.053462 124.751239)
		(end 179.053462 124.114462)
		(width 0.15)
		(layer "B.Cu")
		(net 39)
	)
	(segment
		(start 175.323475 120.384475)
		(end 175.323475 115.63993)
		(width 0.15)
		(layer "B.Cu")
		(net 39)
	)
	(segment
		(start 176.941 126.5)
		(end 177.236 126.795)
		(width 0.15)
		(layer "F.Cu")
		(net 40)
	)
	(segment
		(start 176.2245 126.5)
		(end 176.941 126.5)
		(width 0.15)
		(layer "F.Cu")
		(net 40)
	)
	(segment
		(start 174.576025 115.5845)
		(end 174.6435 115.651975)
		(width 0.15)
		(layer "F.Cu")
		(net 40)
	)
	(segment
		(start 174.6435 115.651975)
		(end 174.6435 116.547)
		(width 0.15)
		(layer "F.Cu")
		(net 40)
	)
	(segment
		(start 177.236 126.795)
		(end 177.364 126.795)
		(width 0.15)
		(layer "F.Cu")
		(net 40)
	)
	(via
		(at 176.2245 126.5)
		(size 0.6)
		(drill 0.25)
		(layers "F.Cu" "B.Cu")
		(net 40)
	)
	(via
		(at 174.576025 115.5845)
		(size 0.6)
		(drill 0.25)
		(layers "F.Cu" "B.Cu")
		(net 40)
	)
	(segment
		(start 174.965 117.307)
		(end 174.576025 116.918025)
		(width 0.15)
		(layer "B.Cu")
		(net 40)
	)
	(segment
		(start 177.895 124.8295)
		(end 177.895 123.431537)
		(width 0.15)
		(layer "B.Cu")
		(net 40)
	)
	(segment
		(start 176.2245 126.5)
		(end 177.895 124.8295)
		(width 0.15)
		(layer "B.Cu")
		(net 40)
	)
	(segment
		(start 174.576025 116.918025)
		(end 174.576025 115.5845)
		(width 0.15)
		(layer "B.Cu")
		(net 40)
	)
	(segment
		(start 174.965 120.501537)
		(end 174.965 117.307)
		(width 0.15)
		(layer "B.Cu")
		(net 40)
	)
	(segment
		(start 177.895 123.431537)
		(end 174.965 120.501537)
		(width 0.15)
		(layer "B.Cu")
		(net 40)
	)
	(segment
		(start 184.75 125.31)
		(end 183.73 124.29)
		(width 0.15)
		(layer "F.Cu")
		(net 41)
	)
	(segment
		(start 183.62 124.18)
		(end 183.62 123.38)
		(width 0.15)
		(layer "F.Cu")
		(net 41)
	)
	(segment
		(start 183.58 123.34)
		(end 183.43 123.34)
		(width 0.15)
		(layer "F.Cu")
		(net 41)
	)
	(segment
		(start 183.73 124.29)
		(end 183.62 124.18)
		(width 0.15)
		(layer "F.Cu")
		(net 41)
	)
	(segment
		(start 184.75 125.765)
		(end 184.75 125.31)
		(width 0.15)
		(layer "F.Cu")
		(net 41)
	)
	(segment
		(start 174.1435 115.9635)
		(end 174.1435 116.547)
		(width 0.15)
		(layer "F.Cu")
		(net 41)
	)
	(segment
		(start 173.795422 115.615422)
		(end 174.1435 115.9635)
		(width 0.15)
		(layer "F.Cu")
		(net 41)
	)
	(segment
		(start 173.795422 115.614878)
		(end 173.795422 115.615422)
		(width 0.15)
		(layer "F.Cu")
		(net 41)
	)
	(segment
		(start 183.62 123.38)
		(end 183.58 123.34)
		(width 0.15)
		(layer "F.Cu")
		(net 41)
	)
	(via
		(at 173.795422 115.614878)
		(size 0.6)
		(drill 0.25)
		(layers "F.Cu" "B.Cu")
		(net 41)
	)
	(via
		(at 180.7 122.4)
		(size 0.6)
		(drill 0.25)
		(layers "F.Cu" "B.Cu")
		(net 41)
	)
	(via
		(at 183.43 123.34)
		(size 0.6)
		(drill 0.25)
		(layers "F.Cu" "B.Cu")
		(net 41)
	)
	(segment
		(start 182.49 122.4)
		(end 183.43 123.34)
		(width 0.15)
		(layer "B.Cu")
		(net 41)
	)
	(segment
		(start 180.7 122.4)
		(end 182.49 122.4)
		(width 0.15)
		(layer "B.Cu")
		(net 41)
	)
	(segment
		(start 179.67 122.4)
		(end 173.795422 116.525422)
		(width 0.15)
		(layer "In2.Cu")
		(net 41)
	)
	(segment
		(start 173.795422 116.525422)
		(end 173.795422 115.614878)
		(width 0.15)
		(layer "In2.Cu")
		(net 41)
	)
	(segment
		(start 180.7 122.4)
		(end 179.67 122.4)
		(width 0.15)
		(layer "In2.Cu")
		(net 41)
	)
	(segment
		(start 175.6 114.936969)
		(end 176.6445 115.981469)
		(width 0.15)
		(layer "F.Cu")
		(net 42)
	)
	(segment
		(start 182 127.8)
		(end 181.744 127.544)
		(width 0.15)
		(layer "F.Cu")
		(net 42)
	)
	(segment
		(start 181.744 127.544)
		(end 181.744 126.735)
		(width 0.15)
		(layer "F.Cu")
		(net 42)
	)
	(segment
		(start 175.6 114.7)
		(end 175.6 114.936969)
		(width 0.15)
		(layer "F.Cu")
		(net 42)
	)
	(segment
		(start 176.6445 115.981469)
		(end 176.6445 116.547)
		(width 0.15)
		(layer "F.Cu")
		(net 42)
	)
	(via
		(at 175.6 114.7)
		(size 0.6)
		(drill 0.25)
		(layers "F.Cu" "B.Cu")
		(net 42)
	)
	(via
		(at 182 127.8)
		(size 0.6)
		(drill 0.25)
		(layers "F.Cu" "B.Cu")
		(net 42)
	)
	(segment
		(start 175.93 114.7)
		(end 176.22 114.41)
		(width 0.15)
		(layer "B.Cu")
		(net 42)
	)
	(segment
		(start 180.0205 119.0405)
		(end 180.0205 123.753236)
		(width 0.15)
		(layer "B.Cu")
		(net 42)
	)
	(segment
		(start 176.22 114.41)
		(end 176.783381 114.41)
		(width 0.15)
		(layer "B.Cu")
		(net 42)
	)
	(segment
		(start 177.69 115.316619)
		(end 177.69 116.71)
		(width 0.15)
		(layer "B.Cu")
		(net 42)
	)
	(segment
		(start 180.0205 123.753236)
		(end 180.2 123.932736)
		(width 0.15)
		(layer "B.Cu")
		(net 42)
	)
	(segment
		(start 181.175 124.517463)
		(end 181.482537 124.825)
		(width 0.15)
		(layer "B.Cu")
		(net 42)
	)
	(segment
		(start 175.6 114.7)
		(end 175.93 114.7)
		(width 0.15)
		(layer "B.Cu")
		(net 42)
	)
	(segment
		(start 177.69 116.71)
		(end 180.0205 119.0405)
		(width 0.15)
		(layer "B.Cu")
		(net 42)
	)
	(segment
		(start 181.175 124.475)
		(end 181.175 124.517463)
		(width 0.15)
		(layer "B.Cu")
		(net 42)
	)
	(segment
		(start 181.525 124.825)
		(end 182 125.3)
		(width 0.15)
		(layer "B.Cu")
		(net 42)
	)
	(segment
		(start 176.783381 114.41)
		(end 177.69 115.316619)
		(width 0.15)
		(layer "B.Cu")
		(net 42)
	)
	(segment
		(start 180.632736 123.932736)
		(end 181.175 124.475)
		(width 0.15)
		(layer "B.Cu")
		(net 42)
	)
	(segment
		(start 182 125.3)
		(end 182 127.8)
		(width 0.15)
		(layer "B.Cu")
		(net 42)
	)
	(segment
		(start 180.2 123.932736)
		(end 180.632736 123.932736)
		(width 0.15)
		(layer "B.Cu")
		(net 42)
	)
	(segment
		(start 181.482537 124.825)
		(end 181.525 124.825)
		(width 0.15)
		(layer "B.Cu")
		(net 42)
	)
	(segment
		(start 176.6445 122.0905)
		(end 176.6445 121.498)
		(width 0.15)
		(layer "F.Cu")
		(net 43)
	)
	(segment
		(start 177.303 123.212)
		(end 177.303 122.749)
		(width 0.15)
		(layer "F.Cu")
		(net 43)
	)
	(segment
		(start 177.303 122.749)
		(end 176.6445 122.0905)
		(width 0.15)
		(layer "F.Cu")
		(net 43)
	)
	(segment
		(start 186.25 138.885)
		(end 186.25 139.4)
		(width 0.15)
		(layer "F.Cu")
		(net 44)
	)
	(segment
		(start 179.153 119.074)
		(end 179.315 119.236)
		(width 0.15)
		(layer "F.Cu")
		(net 44)
	)
	(segment
		(start 184.007963 138.885)
		(end 184.05 138.885)
		(width 0.15)
		(layer "F.Cu")
		(net 44)
	)
	(segment
		(start 187.95 139.6)
		(end 188.15 139.4)
		(width 0.15)
		(layer "F.Cu")
		(net 44)
	)
	(segment
		(start 188.15 139.4)
		(end 188.15 138.9)
		(width 0.15)
		(layer "F.Cu")
		(net 44)
	)
	(segment
		(start 178.3695 118.27)
		(end 178.9445 118.27)
		(width 0.15)
		(layer "F.Cu")
		(net 44)
	)
	(segment
		(start 179.153 118.4785)
		(end 179.153 119.074)
		(width 0.15)
		(layer "F.Cu")
		(net 44)
	)
	(segment
		(start 186.25 139.4)
		(end 186.45 139.6)
		(width 0.15)
		(layer "F.Cu")
		(net 44)
	)
	(segment
		(start 183.25 137.9195)
		(end 183.25 138.127037)
		(width 0.15)
		(layer "F.Cu")
		(net 44)
	)
	(segment
		(start 183.25 138.127037)
		(end 184.007963 138.885)
		(width 0.15)
		(layer "F.Cu")
		(net 44)
	)
	(segment
		(start 183.2695 137.9)
		(end 183.25 137.9195)
		(width 0.15)
		(layer "F.Cu")
		(net 44)
	)
	(segment
		(start 178.9445 118.27)
		(end 179.153 118.4785)
		(width 0.15)
		(layer "F.Cu")
		(net 44)
	)
	(segment
		(start 186.45 139.6)
		(end 187.95 139.6)
		(width 0.15)
		(layer "F.Cu")
		(net 44)
	)
	(via
		(at 183.2695 137.9)
		(size 0.6)
		(drill 0.25)
		(layers "F.Cu" "B.Cu")
		(net 44)
	)
	(via
		(at 179.315 119.236)
		(size 0.6)
		(drill 0.25)
		(layers "F.Cu" "B.Cu")
		(net 44)
	)
	(via
		(at 188.15 138.9)
		(size 0.6)
		(drill 0.25)
		(layers "F.Cu" "B.Cu")
		(net 44)
	)
	(segment
		(start 179.9 124.057)
		(end 179.9 126.475736)
		(width 0.15)
		(layer "B.Cu")
		(net 44)
	)
	(segment
		(start 179.7205 119.6415)
		(end 179.7205 123.8775)
		(width 0.15)
		(layer "B.Cu")
		(net 44)
	)
	(segment
		(start 179.7205 123.8775)
		(end 179.9 124.057)
		(width 0.15)
		(layer "B.Cu")
		(net 44)
	)
	(segment
		(start 184.808273 128.425)
		(end 186.081 128.425)
		(width 0.15)
		(layer "B.Cu")
		(net 44)
	)
	(segment
		(start 179.315 119.236)
		(end 179.7205 119.6415)
		(width 0.15)
		(layer "B.Cu")
		(net 44)
	)
	(segment
		(start 186.081 128.425)
		(end 188.677 131.021)
		(width 0.15)
		(layer "B.Cu")
		(net 44)
	)
	(segment
		(start 183.2695 137.9)
		(end 184.2695 138.9)
		(width 0.15)
		(layer "B.Cu")
		(net 44)
	)
	(segment
		(start 184.2695 138.9)
		(end 188.15 138.9)
		(width 0.15)
		(layer "B.Cu")
		(net 44)
	)
	(segment
		(start 188.677 138.373)
		(end 188.15 138.9)
		(width 0.15)
		(layer "B.Cu")
		(net 44)
	)
	(segment
		(start 184.733273 128.5)
		(end 184.808273 128.425)
		(width 0.15)
		(layer "B.Cu")
		(net 44)
	)
	(segment
		(start 179.9 126.475736)
		(end 181.924264 128.5)
		(width 0.15)
		(layer "B.Cu")
		(net 44)
	)
	(segment
		(start 181.924264 128.5)
		(end 184.733273 128.5)
		(width 0.15)
		(layer "B.Cu")
		(net 44)
	)
	(segment
		(start 188.677 131.021)
		(end 188.677 138.373)
		(width 0.15)
		(layer "B.Cu")
		(net 44)
	)
	(segment
		(start 183.5 139.6)
		(end 183.2805 139.3805)
		(width 0.15)
		(layer "F.Cu")
		(net 45)
	)
	(segment
		(start 185.15 139.4)
		(end 184.95 139.6)
		(width 0.15)
		(layer "F.Cu")
		(net 45)
	)
	(segment
		(start 177.1435 116.547)
		(end 177.1435 115.738006)
		(width 0.15)
		(layer "F.Cu")
		(net 45)
	)
	(segment
		(start 187.35 138.885)
		(end 187.415 138.885)
		(width 0.15)
		(layer "F.Cu")
		(net 45)
	)
	(segment
		(start 185.15 138.885)
		(end 185.15 139.4)
		(width 0.15)
		(layer "F.Cu")
		(net 45)
	)
	(segment
		(start 188.15 138.15)
		(end 188.15 137.95)
		(width 0.15)
		(layer "F.Cu")
		(net 45)
	)
	(segment
		(start 187.415 138.885)
		(end 188.15 138.15)
		(width 0.15)
		(layer "F.Cu")
		(net 45)
	)
	(segment
		(start 177.1435 115.738006)
		(end 176.989994 115.5845)
		(width 0.15)
		(layer "F.Cu")
		(net 45)
	)
	(segment
		(start 183.2805 139.3805)
		(end 183.2805 138.9)
		(width 0.15)
		(layer "F.Cu")
		(net 45)
	)
	(segment
		(start 184.95 139.6)
		(end 183.5 139.6)
		(width 0.15)
		(layer "F.Cu")
		(net 45)
	)
	(via
		(at 183.2805 138.9)
		(size 0.6)
		(drill 0.25)
		(layers "F.Cu" "B.Cu")
		(net 45)
	)
	(via
		(at 176.989994 115.5845)
		(size 0.6)
		(drill 0.25)
		(layers "F.Cu" "B.Cu")
		(net 45)
	)
	(via
		(at 188.15 137.95)
		(size 0.6)
		(drill 0.25)
		(layers "F.Cu" "B.Cu")
		(net 45)
	)
	(segment
		(start 181.9 128.9)
		(end 184.757537 128.9)
		(width 0.15)
		(layer "B.Cu")
		(net 45)
	)
	(segment
		(start 182.55 137.75)
		(end 182.55 138.1695)
		(width 0.15)
		(layer "B.Cu")
		(net 45)
	)
	(segment
		(start 185.835 129.137)
		(end 185.835 137.55)
		(width 0.15)
		(layer "B.Cu")
		(net 45)
	)
	(segment
		(start 184.2 137.95)
		(end 183.5 137.25)
		(width 0.15)
		(layer "B.Cu")
		(net 45)
	)
	(segment
		(start 179.6 124.181264)
		(end 179.6 126.6)
		(width 0.15)
		(layer "B.Cu")
		(net 45)
	)
	(segment
		(start 184.932537 128.725)
		(end 185.423 128.725)
		(width 0.15)
		(layer "B.Cu")
		(net 45)
	)
	(segment
		(start 188.15 137.95)
		(end 185.435 137.95)
		(width 0.15)
		(layer "B.Cu")
		(net 45)
	)
	(segment
		(start 183.5 137.25)
		(end 183.05 137.25)
		(width 0.15)
		(layer "B.Cu")
		(net 45)
	)
	(segment
		(start 182.55 138.1695)
		(end 183.2805 138.9)
		(width 0.15)
		(layer "B.Cu")
		(net 45)
	)
	(segment
		(start 183.05 137.25)
		(end 182.55 137.75)
		(width 0.15)
		(layer "B.Cu")
		(net 45)
	)
	(segment
		(start 184.556 137.95)
		(end 184.2 137.95)
		(width 0.15)
		(layer "B.Cu")
		(net 45)
	)
	(segment
		(start 176.989994 115.5845)
		(end 176.989994 116.971994)
		(width 0.15)
		(layer "B.Cu")
		(net 45)
	)
	(segment
		(start 185.835 137.55)
		(end 185.435 137.95)
		(width 0.15)
		(layer "B.Cu")
		(net 45)
	)
	(segment
		(start 185.423 128.725)
		(end 185.835 129.137)
		(width 0.15)
		(layer "B.Cu")
		(net 45)
	)
	(segment
		(start 179.4205 124.001764)
		(end 179.6 124.181264)
		(width 0.15)
		(layer "B.Cu")
		(net 45)
	)
	(segment
		(start 184.757537 128.9)
		(end 184.932537 128.725)
		(width 0.15)
		(layer "B.Cu")
		(net 45)
	)
	(segment
		(start 179.4205 121.6125)
		(end 179.4205 124.001764)
		(width 0.15)
		(layer "B.Cu")
		(net 45)
	)
	(segment
		(start 178.6705 120.8625)
		(end 179.4205 121.6125)
		(width 0.15)
		(layer "B.Cu")
		(net 45)
	)
	(segment
		(start 176.989994 116.971994)
		(end 178.6705 118.6525)
		(width 0.15)
		(layer "B.Cu")
		(net 45)
	)
	(segment
		(start 185.435 137.95)
		(end 184.556 137.95)
		(width 0.15)
		(layer "B.Cu")
		(net 45)
	)
	(segment
		(start 178.6705 118.6525)
		(end 178.6705 120.8625)
		(width 0.15)
		(layer "B.Cu")
		(net 45)
	)
	(segment
		(start 179.6 126.6)
		(end 181.9 128.9)
		(width 0.15)
		(layer "B.Cu")
		(net 45)
	)
	(segment
		(start 193.744 126.453)
		(end 193.349 126.848)
		(width 0.15)
		(layer "F.Cu")
		(net 46)
	)
	(segment
		(start 193.349 127.748)
		(end 193.349 130.367097)
		(width 0.15)
		(layer "F.Cu")
		(net 46)
	)
	(segment
		(start 180.75 125.34)
		(end 180.75 125.765)
		(width 0.15)
		(layer "F.Cu")
		(net 46)
	)
	(segment
		(start 180.529122 124.570878)
		(end 180.529122 125.119122)
		(width 0.15)
		(layer "F.Cu")
		(net 46)
	)
	(segment
		(start 193.744 125.572)
		(end 193.744 126.453)
		(width 0.15)
		(layer "F.Cu")
		(net 46)
	)
	(segment
		(start 180.529122 125.119122)
		(end 180.75 125.34)
		(width 0.15)
		(layer "F.Cu")
		(net 46)
	)
	(segment
		(start 193.349 126.848)
		(end 193.349 127.748)
		(width 0.15)
		(layer "F.Cu")
		(net 46)
	)
	(segment
		(start 193.349 130.367097)
		(end 193.039607 130.67649)
		(width 0.15)
		(layer "F.Cu")
		(net 46)
	)
	(via
		(at 180.529122 124.570878)
		(size 0.6)
		(drill 0.25)
		(layers "F.Cu" "B.Cu")
		(net 46)
	)
	(via
		(at 193.039607 130.67649)
		(size 0.6)
		(drill 0.25)
		(layers "F.Cu" "B.Cu")
		(net 46)
	)
	(segment
		(start 185.6475 127.7815)
		(end 186.500972 127.7815)
		(width 0.15)
		(layer "In2.Cu")
		(net 46)
	)
	(segment
		(start 183.4385 124.9555)
		(end 185.009 126.526)
		(width 0.15)
		(layer "In2.Cu")
		(net 46)
	)
	(segment
		(start 191.952736 130.2)
		(end 192.429226 130.67649)
		(width 0.15)
		(layer "In2.Cu")
		(net 46)
	)
	(segment
		(start 185.009 126.526)
		(end 185.009 127.143)
		(width 0.15)
		(layer "In2.Cu")
		(net 46)
	)
	(segment
		(start 188.919472 130.2)
		(end 191.952736 130.2)
		(width 0.15)
		(layer "In2.Cu")
		(net 46)
	)
	(segment
		(start 192.429226 130.67649)
		(end 193.039607 130.67649)
		(width 0.15)
		(layer "In2.Cu")
		(net 46)
	)
	(segment
		(start 186.500972 127.7815)
		(end 188.919472 130.2)
		(width 0.15)
		(layer "In2.Cu")
		(net 46)
	)
	(segment
		(start 180.913744 124.9555)
		(end 183.4385 124.9555)
		(width 0.15)
		(layer "In2.Cu")
		(net 46)
	)
	(segment
		(start 185.009 127.143)
		(end 185.6475 127.7815)
		(width 0.15)
		(layer "In2.Cu")
		(net 46)
	)
	(segment
		(start 180.529122 124.570878)
		(end 180.913744 124.9555)
		(width 0.15)
		(layer "In2.Cu")
		(net 46)
	)
	(segment
		(start 195.85 132.25)
		(end 197.3 132.25)
		(width 0.15)
		(layer "F.Cu")
		(net 47)
	)
	(segment
		(start 197.55 132.5)
		(end 198.015 132.5)
		(width 0.15)
		(layer "F.Cu")
		(net 47)
	)
	(segment
		(start 197.3 132.25)
		(end 197.55 132.5)
		(width 0.15)
		(layer "F.Cu")
		(net 47)
	)
	(segment
		(start 195.85 131.75)
		(end 197.2 131.75)
		(width 0.15)
		(layer "F.Cu")
		(net 48)
	)
	(segment
		(start 197.2 131.75)
		(end 197.55 131.4)
		(width 0.15)
		(layer "F.Cu")
		(net 48)
	)
	(segment
		(start 197.55 131.4)
		(end 198.015 131.4)
		(width 0.15)
		(layer "F.Cu")
		(net 48)
	)
	(segment
		(start 195.04 126.446)
		(end 196.07 127.476)
		(width 0.15)
		(layer "F.Cu")
		(net 49)
	)
	(segment
		(start 190.444 125.572)
		(end 190.35 125.666)
		(width 0.15)
		(layer "F.Cu")
		(net 49)
	)
	(segment
		(start 190.35 125.666)
		(end 190.35 127.748)
		(width 0.15)
		(layer "F.Cu")
		(net 49)
	)
	(segment
		(start 190.574 125.572)
		(end 191.544 124.602)
		(width 0.15)
		(layer "F.Cu")
		(net 49)
	)
	(segment
		(start 191.674 124.602)
		(end 192.644 125.572)
		(width 0.15)
		(layer "F.Cu")
		(net 49)
	)
	(segment
		(start 190.444 125.572)
		(end 190.574 125.572)
		(width 0.15)
		(layer "F.Cu")
		(net 49)
	)
	(segment
		(start 192.8 126.581)
		(end 192.644 126.425)
		(width 0.15)
		(layer "F.Cu")
		(net 49)
	)
	(segment
		(start 191.544 124.602)
		(end 191.674 124.602)
		(width 0.15)
		(layer "F.Cu")
		(net 49)
	)
	(segment
		(start 192.644 126.425)
		(end 192.644 125.572)
		(width 0.15)
		(layer "F.Cu")
		(net 49)
	)
	(segment
		(start 196.07 127.476)
		(end 197.411 127.476)
		(width 0.15)
		(layer "F.Cu")
		(net 49)
	)
	(via
		(at 195.04 126.446)
		(size 0.6)
		(drill 0.25)
		(layers "F.Cu" "B.Cu")
		(net 49)
	)
	(via
		(at 192.8 126.581)
		(size 0.6)
		(drill 0.25)
		(layers "F.Cu" "B.Cu")
		(net 49)
	)
	(segment
		(start 192.935 126.446)
		(end 192.8 126.581)
		(width 0.15)
		(layer "B.Cu")
		(net 49)
	)
	(segment
		(start 195.04 126.446)
		(end 192.935 126.446)
		(width 0.15)
		(layer "B.Cu")
		(net 49)
	)
	(segment
		(start 189.344 125.572)
		(end 189.344 126.123)
		(width 0.15)
		(layer "F.Cu")
		(net 50)
	)
	(segment
		(start 189.85 126.629)
		(end 189.85 127.748)
		(width 0.15)
		(layer "F.Cu")
		(net 50)
	)
	(segment
		(start 189.344 126.123)
		(end 189.85 126.629)
		(width 0.15)
		(layer "F.Cu")
		(net 50)
	)
	(segment
		(start 183.5345 119.5855)
		(end 184.294 120.345)
		(width 0.15)
		(layer "F.Cu")
		(net 51)
	)
	(segment
		(start 183.214 119.5785)
		(end 183.221 119.5855)
		(width 0.15)
		(layer "F.Cu")
		(net 51)
	)
	(segment
		(start 184.294 120.345)
		(end 185.337 120.345)
		(width 0.15)
		(layer "F.Cu")
		(net 51)
	)
	(segment
		(start 183.214 118.5625)
		(end 183.214 119.5785)
		(width 0.15)
		(layer "F.Cu")
		(net 51)
	)
	(segment
		(start 183.221 119.5855)
		(end 183.5345 119.5855)
		(width 0.15)
		(layer "F.Cu")
		(net 51)
	)
	(segment
		(start 183.2685 121.615)
		(end 185.337 121.615)
		(width 0.15)
		(layer "F.Cu")
		(net 52)
	)
	(segment
		(start 183.221 121.6625)
		(end 183.2685 121.615)
		(width 0.15)
		(layer "F.Cu")
		(net 52)
	)
	(segment
		(start 183.214 121.6555)
		(end 183.221 121.6625)
		(width 0.15)
		(layer "F.Cu")
		(net 52)
	)
	(segment
		(start 183.214 120.6235)
		(end 183.214 121.6555)
		(width 0.15)
		(layer "F.Cu")
		(net 52)
	)
	(segment
		(start 203.75 116.32)
		(end 203.75 117.35)
		(width 0.15)
		(layer "F.Cu")
		(net 53)
	)
	(segment
		(start 206.475001 117.474999)
		(end 206.35 117.6)
		(width 0.15)
		(layer "F.Cu")
		(net 53)
	)
	(segment
		(start 203.05 114.25)
		(end 203.05 115.62)
		(width 0.15)
		(layer "F.Cu")
		(net 53)
	)
	(segment
		(start 203.05 115.62)
		(end 203.75 116.32)
		(width 0.15)
		(layer "F.Cu")
		(net 53)
	)
	(segment
		(start 203.35 113.95)
		(end 203.05 114.25)
		(width 0.15)
		(layer "F.Cu")
		(net 53)
	)
	(segment
		(start 205.9 113.95)
		(end 203.35 113.95)
		(width 0.15)
		(layer "F.Cu")
		(net 53)
	)
	(segment
		(start 206.3 114.35)
		(end 205.9 113.95)
		(width 0.15)
		(layer "F.Cu")
		(net 53)
	)
	(segment
		(start 206.475001 116.975)
		(end 206.475001 117.474999)
		(width 0.15)
		(layer "F.Cu")
		(net 53)
	)
	(via
		(at 206.3 114.35)
		(size 0.6)
		(drill 0.25)
		(layers "F.Cu" "B.Cu")
		(net 53)
	)
	(via
		(at 206.35 117.6)
		(size 0.6)
		(drill 0.25)
		(layers "F.Cu" "B.Cu")
		(net 53)
	)
	(segment
		(start 206.35 117.6)
		(end 206.35 114.4)
		(width 0.15)
		(layer "B.Cu")
		(net 53)
	)
	(segment
		(start 206.35 114.4)
		(end 206.3 114.35)
		(width 0.15)
		(layer "B.Cu")
		(net 53)
	)
	(segment
		(start 182.84 129.845)
		(end 180.65 129.845)
		(width 0.15)
		(layer "F.Cu")
		(net 86)
	)
	(segment
		(start 185.35 131.5)
		(end 183.395 131.5)
		(width 0.15)
		(layer "F.Cu")
		(net 86)
	)
	(segment
		(start 183.395 130.4)
		(end 182.84 129.845)
		(width 0.15)
		(layer "F.Cu")
		(net 86)
	)
	(segment
		(start 187.35 130.25)
		(end 186.6 130.25)
		(width 0.15)
		(layer "F.Cu")
		(net 86)
	)
	(segment
		(start 183.395 130.4)
		(end 183.395 131.5)
		(width 0.15)
		(layer "F.Cu")
		(net 86)
	)
	(segment
		(start 186.6 130.25)
		(end 185.35 131.5)
		(width 0.15)
		(layer "F.Cu")
		(net 86)
	)
	(segment
		(start 181.8 131.5)
		(end 181.045 132.255)
		(width 0.15)
		(layer "F.Cu")
		(net 87)
	)
	(segment
		(start 181.045 132.255)
		(end 180.65 132.255)
		(width 0.15)
		(layer "F.Cu")
		(net 87)
	)
	(segment
		(start 184.8 132.6)
		(end 186.65 130.75)
		(width 0.15)
		(layer "F.Cu")
		(net 87)
	)
	(segment
		(start 186.65 130.75)
		(end 187.35 130.75)
		(width 0.15)
		(layer "F.Cu")
		(net 87)
	)
	(segment
		(start 182.9 131.975)
		(end 182.9 132.105)
		(width 0.15)
		(layer "F.Cu")
		(net 87)
	)
	(segment
		(start 183.395 132.6)
		(end 184.8 132.6)
		(width 0.15)
		(layer "F.Cu")
		(net 87)
	)
	(segment
		(start 182.425 131.5)
		(end 182.9 131.975)
		(width 0.15)
		(layer "F.Cu")
		(net 87)
	)
	(segment
		(start 182.425 131.5)
		(end 181.8 131.5)
		(width 0.15)
		(layer "F.Cu")
		(net 87)
	)
	(segment
		(start 182.9 132.105)
		(end 183.395 132.6)
		(width 0.15)
		(layer "F.Cu")
		(net 87)
	)
	(segment
		(start 209.0305 126.45)
		(end 209.0305 132.05)
		(width 0.15)
		(layer "F.Cu")
		(net 88)
	)
	(segment
		(start 208.575 117.782537)
		(end 208.575 118.217463)
		(width 0.15)
		(layer "B.Cu")
		(net 89)
	)
	(segment
		(start 208.575 118.217463)
		(end 209 118.642463)
		(width 0.15)
		(layer "B.Cu")
		(net 89)
	)
	(segment
		(start 209 120.355)
		(end 208.955 120.4)
		(width 0.15)
		(layer "B.Cu")
		(net 89)
	)
	(segment
		(start 209 118.642463)
		(end 209 120.355)
		(width 0.15)
		(layer "B.Cu")
		(net 89)
	)
	(segment
		(start 208.955 117.402537)
		(end 208.575 117.782537)
		(width 0.15)
		(layer "B.Cu")
		(net 89)
	)
	(segment
		(start 208.955 114.8)
		(end 208.955 117.402537)
		(width 0.15)
		(layer "B.Cu")
		(net 89)
	)
	(zone
		(net 0)
		(net_name "")
		(layer "F.Cu")
		(hatch edge 0.508)
		(connect_pads
			(clearance 0)
		)
		(min_thickness 0.254)
		(filled_areas_thickness no)
		(keepout
			(tracks allowed)
			(vias allowed)
			(pads allowed)
			(copperpour not_allowed)
			(footprints allowed)
		)
		(placement
			(enabled no)
			(sheetname "")
		)
		(fill
			(thermal_gap 0.508)
			(thermal_bridge_width 0.508)
		)
		(polygon
			(pts
				(xy 170.55 127.85) (xy 165.55 127.85) (xy 165.55 125.65) (xy 170.55 125.65)
			)
		)
	)
	(zone
		(net 27)
		(net_name "/VBUS")
		(layer "F.Cu")
		(name "USB_VBUS")
		(hatch edge 0.508)
		(priority 1)
		(connect_pads
			(clearance 0.15)
		)
		(min_thickness 0.15)
		(filled_areas_thickness no)
		(fill yes
			(thermal_gap 0.15)
			(thermal_bridge_width 0.25)
		)
		(polygon
			(pts
				(xy 169.55 139.4) (xy 167.2 139.4) (xy 167.2 136.85) (xy 169.55 136.85)
			)
		)
	)
	(zone
		(net 2)
		(net_name "+3V3")
		(layer "F.Cu")
		(name "+3V3")
		(hatch edge 0.508)
		(priority 1)
		(connect_pads
			(clearance 0)
		)
		(min_thickness 0.15)
		(filled_areas_thickness no)
		(fill yes
			(thermal_gap 0.15)
			(thermal_bridge_width 0.25)
		)
		(polygon
			(pts
				(xy 177.55 129.35) (xy 177 129.9) (xy 177 133.6) (xy 170.95 133.6) (xy 170.95 127.65) (xy 177.55 127.65)
			)
		)
	)
	(zone
		(net 1)
		(net_name "GND")
		(layers "F.Cu" "B.Cu" "In1.Cu")
		(name "GND")
		(hatch edge 0.508)
		(connect_pads
			(clearance 0.25)
		)
		(min_thickness 0.2)
		(filled_areas_thickness no)
		(fill yes
			(thermal_gap 0.15)
			(thermal_bridge_width 0.25)
		)
		(polygon
			(pts
				(xy 197.95 123.65) (xy 210 123.65) (xy 210 140) (xy 160 140) (xy 160 113.5) (xy 197.95 113.5)
			)
		)
	)
	(zone
		(net 0)
		(net_name "")
		(layers "F.Cu" "B.Cu" "In1.Cu" "In2.Cu")
		(hatch edge 0.508)
		(connect_pads
			(clearance 0)
		)
		(min_thickness 0.254)
		(filled_areas_thickness no)
		(keepout
			(tracks allowed)
			(vias allowed)
			(pads allowed)
			(copperpour not_allowed)
			(footprints allowed)
		)
		(placement
			(enabled no)
			(sheetname "")
		)
		(fill
			(thermal_gap 0.508)
			(thermal_bridge_width 0.508)
		)
		(polygon
			(pts
				(xy 211.016 126.817) (xy 194.462 126.817) (xy 194.462 112.868) (xy 211.016 112.868)
			)
		)
	)
	(zone
		(net 0)
		(net_name "")
		(layer "B.Cu")
		(name "BAT_KEEPOUT")
		(hatch edge 0.508)
		(connect_pads
			(clearance 0)
		)
		(min_thickness 0.15)
		(filled_areas_thickness no)
		(keepout
			(tracks allowed)
			(vias allowed)
			(pads allowed)
			(copperpour not_allowed)
			(footprints allowed)
		)
		(placement
			(enabled no)
			(sheetname "")
		)
		(fill
			(thermal_gap 0.15)
			(thermal_bridge_width 0.25)
		)
		(polygon
			(pts
				(xy 185.6 135.8) (xy 182.5 135.8) (xy 182.5 130.1) (xy 185.6 130.1)
			)
		)
	)
	(zone
		(net 0)
		(net_name "")
		(layer "B.Cu")
		(name "BAT_KEEPOUT")
		(hatch edge 0.508)
		(connect_pads
			(clearance 0)
		)
		(min_thickness 0.15)
		(filled_areas_thickness no)
		(keepout
			(tracks allowed)
			(vias allowed)
			(pads allowed)
			(copperpour not_allowed)
			(footprints allowed)
		)
		(placement
			(enabled no)
			(sheetname "")
		)
		(fill
			(thermal_gap 0.15)
			(thermal_bridge_width 0.25)
		)
		(polygon
			(pts
				(xy 170.3 135.8) (xy 167.2 135.8) (xy 167.2 130.1) (xy 170.3 130.1)
			)
		)
	)
	(zone
		(net 2)
		(net_name "+3V3")
		(layer "In2.Cu")
		(name "+3V3")
		(hatch edge 0.508)
		(connect_pads
			(clearance 0.25)
		)
		(min_thickness 0.15)
		(filled_areas_thickness no)
		(fill yes
			(thermal_gap 0.15)
			(thermal_bridge_width 0.25)
		)
		(polygon
			(pts
				(xy 197.846 123.992) (xy 209.896 123.992) (xy 209.896 140.342) (xy 169.696 140.342) (xy 169.696 113.842)
				(xy 197.846 113.842)
			)
		)
	)
	(zone
		(net 27)
		(net_name "/VBUS")
		(layer "In2.Cu")
		(name "USB_VBUS")
		(hatch edge 0.508)
		(connect_pads
			(clearance 0.25)
		)
		(min_thickness 0.15)
		(filled_areas_thickness no)
		(fill yes
			(thermal_gap 0.15)
			(thermal_bridge_width 0.25)
		)
		(polygon
			(pts
				(xy 169.446 140.342) (xy 159.896 140.342) (xy 159.896 113.842) (xy 169.446 113.842)
			)
		)
	)
)
